(kicad_pcb
	(version 20241229)
	(generator "pcbnew")
	(generator_version "9.0")
	(general
		(thickness 1.552)
		(legacy_teardrops no)
	)
	(paper "A4")
	(title_block
		(date "2023-07-25")
		(rev "1.1.4")
	)
	(layers
		(0 "F.Cu" signal)
		(4 "In1.Cu" signal)
		(6 "In2.Cu" signal)
		(8 "In3.Cu" signal)
		(10 "In4.Cu" signal)
		(12 "In5.Cu" signal)
		(14 "In6.Cu" signal)
		(2 "B.Cu" signal)
		(9 "F.Adhes" user "F.Adhesive")
		(11 "B.Adhes" user "B.Adhesive")
		(13 "F.Paste" user)
		(15 "B.Paste" user)
		(5 "F.SilkS" user "F.Silkscreen")
		(7 "B.SilkS" user "B.Silkscreen")
		(1 "F.Mask" user)
		(3 "B.Mask" user)
		(17 "Dwgs.User" user "User.Drawings")
		(19 "Cmts.User" user "User.Comments")
		(21 "Eco1.User" user "User.Eco1")
		(23 "Eco2.User" user "User.Eco2")
		(25 "Edge.Cuts" user)
		(27 "Margin" user)
		(31 "F.CrtYd" user "F.Courtyard")
		(29 "B.CrtYd" user "B.Courtyard")
		(35 "F.Fab" user)
		(33 "B.Fab" user)
	)
	(setup
		(stackup
			(layer "F.SilkS"
				(type "Top Silk Screen")
				(color "White")
			)
			(layer "F.Paste"
				(type "Top Solder Paste")
			)
			(layer "F.Mask"
				(type "Top Solder Mask")
				(color "Black")
				(thickness 0.01)
			)
			(layer "F.Cu"
				(type "copper")
				(thickness 0.035)
			)
			(layer "dielectric 1"
				(type "core")
				(thickness 0.12)
				(material "FR4")
				(epsilon_r 4.5)
				(loss_tangent 0.02)
			)
			(layer "In1.Cu"
				(type "copper")
				(thickness 0.018)
			)
			(layer "dielectric 2"
				(type "prepreg")
				(thickness 0.2)
				(material "FR4")
				(epsilon_r 4.5)
				(loss_tangent 0.02)
			)
			(layer "In2.Cu"
				(type "copper")
				(thickness 0.018)
			)
			(layer "dielectric 3"
				(type "core")
				(thickness 0.24)
				(material "FR4")
				(epsilon_r 4.5)
				(loss_tangent 0.02)
			)
			(layer "In3.Cu"
				(type "copper")
				(thickness 0.018)
			)
			(layer "dielectric 4"
				(type "prepreg")
				(thickness 0.2)
				(material "FR4")
				(epsilon_r 4.5)
				(loss_tangent 0.02)
			)
			(layer "In4.Cu"
				(type "copper")
				(thickness 0.018)
			)
			(layer "dielectric 5"
				(type "core")
				(thickness 0.24)
				(material "FR4")
				(epsilon_r 4.5)
				(loss_tangent 0.02)
			)
			(layer "In5.Cu"
				(type "copper")
				(thickness 0.035)
			)
			(layer "dielectric 6"
				(type "prepreg")
				(thickness 0.2)
				(material "FR4")
				(epsilon_r 4.5)
				(loss_tangent 0.02)
			)
			(layer "In6.Cu"
				(type "copper")
				(thickness 0.035)
			)
			(layer "dielectric 7"
				(type "core")
				(thickness 0.12)
				(material "FR4")
				(epsilon_r 4.5)
				(loss_tangent 0.02)
			)
			(layer "B.Cu"
				(type "copper")
				(thickness 0.035)
			)
			(layer "B.Mask"
				(type "Bottom Solder Mask")
				(color "Black")
				(thickness 0.01)
			)
			(layer "B.Paste"
				(type "Bottom Solder Paste")
			)
			(layer "B.SilkS"
				(type "Bottom Silk Screen")
				(color "White")
			)
			(copper_finish "None")
			(dielectric_constraints yes)
		)
		(pad_to_mask_clearance 0)
		(allow_soldermask_bridges_in_footprints no)
		(tenting front back)
		(aux_axis_origin 75.03 125.15)
		(grid_origin 75.03 125.14)
		(pcbplotparams
			(layerselection 0x00000000_00000000_55555555_5755f5ff)
			(plot_on_all_layers_selection 0x00000000_00000000_00000000_00000000)
			(disableapertmacros no)
			(usegerberextensions no)
			(usegerberattributes no)
			(usegerberadvancedattributes yes)
			(creategerberjobfile yes)
			(dashed_line_dash_ratio 12.000000)
			(dashed_line_gap_ratio 3.000000)
			(svgprecision 6)
			(plotframeref no)
			(mode 1)
			(useauxorigin no)
			(hpglpennumber 1)
			(hpglpenspeed 20)
			(hpglpendiameter 15.000000)
			(pdf_front_fp_property_popups yes)
			(pdf_back_fp_property_popups yes)
			(pdf_metadata yes)
			(pdf_single_document no)
			(dxfpolygonmode yes)
			(dxfimperialunits yes)
			(dxfusepcbnewfont yes)
			(psnegative no)
			(psa4output no)
			(plot_black_and_white yes)
			(sketchpadsonfab no)
			(plotpadnumbers no)
			(hidednponfab no)
			(sketchdnponfab yes)
			(crossoutdnponfab yes)
			(subtractmaskfromsilk no)
			(outputformat 1)
			(mirror no)
			(drillshape 0)
			(scaleselection 1)
			(outputdirectory "fab/")
		)
	)
	(net 0 "")
	(net 1 "GND")
	(net 2 "+3V3")
	(net 3 "+1V2")
	(net 4 "1V0_Power")
	(net 5 "Vref")
	(net 6 "Vtt")
	(net 7 "/SDI/SDI_P")
	(net 8 "/SDI/SDI_N")
	(net 9 "/FPGA Power/VCC_AUX")
	(net 10 "/FPGA Power/VCC_AUXA")
	(net 11 "/FPGA Power/VCC_DPHY")
	(net 12 "/FPGA Power/VCC_ADPHY")
	(net 13 "/FPGA Power/VCC_PLLDPHY")
	(net 14 "+5V")
	(net 15 "/FPGA/INITN")
	(net 16 "/Peripherals/FFC1_5V")
	(net 17 "/Peripherals/FFC1_3V3")
	(net 18 "/Peripherals/FFC2_3V3")
	(net 19 "FFC2_5V")
	(net 20 "AUDIO_ACLK")
	(net 21 "AUDIO_WCLK")
	(net 22 "AUDIO_OUT_CH1_2")
	(net 23 "AUDIO_OUT_CH5_6")
	(net 24 "AUDIO_OUT_CH3_4")
	(net 25 "AUDIO_OUT_CH7_8")
	(net 26 "AUDIO_MCLK")
	(net 27 "/FPGA/SPI_DQ3")
	(net 28 "/FPGA/SPI_DQ2")
	(net 29 "/FPGA/~{FLASH_CS_SOFT}")
	(net 30 "Net-(U1-REF)")
	(net 31 "/FPGA/MISO_SOFT")
	(net 32 "/FPGA/MOSI_SOFT")
	(net 33 "/FPGA/SPI_CLK_SOFT")
	(net 34 "LED1")
	(net 35 "LED0")
	(net 36 "/FPGA/PROGRAMN")
	(net 37 "/FPGA/SPI_DQ0_MOSI")
	(net 38 "/FPGA/SPI_DQ1_MISO")
	(net 39 "/FPGA/SPI_CLK")
	(net 40 "/FPGA/DONE")
	(net 41 "/FPGA/~{FLASH_CS}")
	(net 42 "/FPGA/INITN_SOFT")
	(net 43 "DIP1")
	(net 44 "DIP0")
	(net 45 "/SDI/XTAL1")
	(net 46 "/SDI/XTAL2")
	(net 47 "/SDI/SDO_P")
	(net 48 "/SDI/SDO_N")
	(net 49 "1V0_Clean")
	(net 50 "+1V8")
	(net 51 "unconnected-(J4-Pad13)")
	(net 52 "unconnected-(J4-Pad14)")
	(net 53 "unconnected-(J4-Pad16)")
	(net 54 "unconnected-(J4-Pad17)")
	(net 55 "unconnected-(J4-Pad31)")
	(net 56 "Net-(J4-Pad32)")
	(net 57 "unconnected-(U15B-RSV-PadB3)")
	(net 58 "Net-(D1-A)")
	(net 59 "unconnected-(U15B-RSV-PadF2)")
	(net 60 "Net-(U1-DDQ)")
	(net 61 "Net-(U5-BST)")
	(net 62 "Net-(D2-A)")
	(net 63 "Net-(D3-A)")
	(net 64 "Net-(D4-A)")
	(net 65 "Net-(U6-BST)")
	(net 66 "Net-(D5-C)")
	(net 67 "Net-(D5-A)")
	(net 68 "/Peripherals/MIPI0_D3_N")
	(net 69 "/Peripherals/MIPI0_D3_P")
	(net 70 "/Peripherals/MIPI0_D2_N")
	(net 71 "/Peripherals/MIPI0_D2_P")
	(net 72 "/Peripherals/MIPI0_D1_N")
	(net 73 "/Peripherals/MIPI0_D1_P")
	(net 74 "/Peripherals/MIPI0_D0_N")
	(net 75 "/Peripherals/MIPI0_D0_P")
	(net 76 "/Peripherals/MIPI0_CLK_N")
	(net 77 "/Peripherals/MIPI0_CLK_P")
	(net 78 "/Peripherals/MIPI2_D3_N")
	(net 79 "/Peripherals/MIPI2_D3_P")
	(net 80 "/Peripherals/MIPI2_D2_N")
	(net 81 "/Peripherals/MIPI2_D2_P")
	(net 82 "/Peripherals/MIPI2_D1_N")
	(net 83 "/Peripherals/MIPI2_D1_P")
	(net 84 "/Peripherals/MIPI2_D0_N")
	(net 85 "/Peripherals/MIPI2_D0_P")
	(net 86 "/Peripherals/MIPI2_CLK_N")
	(net 87 "/Peripherals/MIPI2_CLK_P")
	(net 88 "/Peripherals/FFC1_VSYNC0")
	(net 89 "/Peripherals/FFC1_RESET")
	(net 90 "/Peripherals/FFC1_VSYNC1")
	(net 91 "/Peripherals/FCC1_SDA1")
	(net 92 "/Peripherals/FCC1_SCL1")
	(net 93 "/Peripherals/FCC1_SDA2")
	(net 94 "/Peripherals/FCC1_SCL2")
	(net 95 "unconnected-(J6-Pad46)")
	(net 96 "unconnected-(J6-Pad45)")
	(net 97 "unconnected-(J6-Pad44)")
	(net 98 "unconnected-(J6-Pad43)")
	(net 99 "/Peripherals/FCC2_SDA2")
	(net 100 "SCL")
	(net 101 "SDA")
	(net 102 "unconnected-(J6-Pad38)")
	(net 103 "unconnected-(J6-Pad37)")
	(net 104 "unconnected-(J6-Pad36)")
	(net 105 "unconnected-(J6-Pad35)")
	(net 106 "/Peripherals/FFC2_VSYNC1")
	(net 107 "/Peripherals/FFC2_RESET")
	(net 108 "/Peripherals/FFC2_VSYNC0")
	(net 109 "unconnected-(J6-Pad31)")
	(net 110 "/Peripherals/MIPI1_CLK_P")
	(net 111 "/Peripherals/MIPI1_CLK_N")
	(net 112 "/Peripherals/MIPI1_D0_P")
	(net 113 "/Peripherals/MIPI1_D0_N")
	(net 114 "/Peripherals/MIPI1_D1_P")
	(net 115 "/Peripherals/MIPI1_D1_N")
	(net 116 "/Peripherals/MIPI1_D2_P")
	(net 117 "/Peripherals/MIPI1_D2_N")
	(net 118 "/Peripherals/MIPI1_D3_P")
	(net 119 "/Peripherals/MIPI1_D3_N")
	(net 120 "unconnected-(J6-Pad17)")
	(net 121 "unconnected-(J6-Pad16)")
	(net 122 "unconnected-(J6-Pad14)")
	(net 123 "unconnected-(J6-Pad13)")
	(net 124 "unconnected-(J6-Pad11)")
	(net 125 "unconnected-(J6-Pad10)")
	(net 126 "unconnected-(J6-Pad8)")
	(net 127 "unconnected-(J6-Pad7)")
	(net 128 "unconnected-(J6-Pad6)")
	(net 129 "unconnected-(J6-Pad5)")
	(net 130 "unconnected-(J6-Pad4)")
	(net 131 "unconnected-(J6-Pad3)")
	(net 132 "unconnected-(J6-Pad2)")
	(net 133 "unconnected-(J6-Pad1)")
	(net 134 "Net-(J7-Pad2)")
	(net 135 "Net-(J7-Pad4)")
	(net 136 "Net-(J7-Pad6)")
	(net 137 "unconnected-(J7-Pad7)")
	(net 138 "Net-(J7-Pad8)")
	(net 139 "Net-(J7-Pad10)")
	(net 140 "Net-(U7-BST)")
	(net 141 "/Power Supply/VREF_0V45")
	(net 142 "/DDR3/DDR3_CK_N")
	(net 143 "/DDR3/DDR3_CK_P")
	(net 144 "/DDR3/DDR3_A2")
	(net 145 "/DDR3/DDR3_A1")
	(net 146 "/DDR3/DDR3_A3")
	(net 147 "/DDR3/DDR3_A0")
	(net 148 "/DDR3/DDR3_A6")
	(net 149 "/DDR3/DDR3_A5")
	(net 150 "/DDR3/DDR3_A7")
	(net 151 "/DDR3/DDR3_A4")
	(net 152 "/DDR3/DDR3_A10")
	(net 153 "/DDR3/DDR3_A9")
	(net 154 "/DDR3/DDR3_A11")
	(net 155 "/DDR3/DDR3_A8")
	(net 156 "Net-(U15B-LF)")
	(net 157 "/DDR3/DDR3_BA0")
	(net 158 "/DDR3/DDR3_A13")
	(net 159 "/DDR3/DDR3_BA1")
	(net 160 "/DDR3/DDR3_A12")
	(net 161 "/DDR3/~{DDR3_CAS}")
	(net 162 "/DDR3/~{DDR3_RAS}")
	(net 163 "/DDR3/~{DDR3_WE}")
	(net 164 "/DDR3/~{DDR3_RESET}")
	(net 165 "/DDR3/DDR3_CKE")
	(net 166 "/DDR3/DDR3_ODT")
	(net 167 "/DDR3/DDR3_BA2")
	(net 168 "/DDR3/~{DDR3_CS}")
	(net 169 "TMS")
	(net 170 "TCK")
	(net 171 "TDO")
	(net 172 "TDI")
	(net 173 "JTAG_EN")
	(net 174 "unconnected-(U3-Pad13)")
	(net 175 "/SDI/RESET_TRST")
	(net 176 "/SDI/STANDBY")
	(net 177 "/SDI/SW_EN")
	(net 178 "/SDI/~{CS_TMS}")
	(net 179 "/SDI/SCLK_TCK")
	(net 180 "/SDI/TIM_861")
	(net 181 "/SDI/SDOUT_TDO")
	(net 182 "/SDI/SDIN_TDI")
	(net 183 "/SDI/SDI_STAT5")
	(net 184 "/SDI/~{SDO_DISABLE}")
	(net 185 "/SDI/SDO_EN{slash}DIS")
	(net 186 "40MHz_3V3")
	(net 187 "/SDI/SDI_D4")
	(net 188 "/SDI/SDI_D5")
	(net 189 "/SDI/SDI_D3")
	(net 190 "/SDI/SDI_D2")
	(net 191 "/SDI/SDI_D1")
	(net 192 "/SDI/SDI_D0")
	(net 193 "/SDI/DVB_ASI")
	(net 194 "/SDI/SDI_D7")
	(net 195 "/SDI/SDI_D8")
	(net 196 "/SDI/SDI_D6")
	(net 197 "/SDI/SDI_PCLK")
	(net 198 "/SDI/AUDIO_EN{slash}~{DIS}")
	(net 199 "/SDI/IOPROC_EN{slash}~{DIS}")
	(net 200 "/SDI/20bit{slash}~{10bit}")
	(net 201 "/SDI/~{SMPTE_BYPASS}")
	(net 202 "/SDI/SDI_D9")
	(net 203 "/SDI/SDI_D10")
	(net 204 "/SDI/SDI_D12")
	(net 205 "/SDI/SDI_D11")
	(net 206 "/SDI/SDI_D14")
	(net 207 "/SDI/SDI_D13")
	(net 208 "/SDI/JTAG{slash}~{HOST}")
	(net 209 "/SDI/~{RC_BYP}")
	(net 210 "/SDI/SDI_D15")
	(net 211 "/SDI/SDI_D16")
	(net 212 "/SDI/SDI_STAT2")
	(net 213 "/SDI/SDI_D19")
	(net 214 "/SDI/SDI_STAT0")
	(net 215 "/SDI/SDI_D17")
	(net 216 "/SDI/SDI_D18")
	(net 217 "/SDI/SDI_STAT1")
	(net 218 "/SDI/SDI_STAT4")
	(net 219 "/SDI/SDI_STAT3")
	(net 220 "/DDR3/DDR3_LDQS_N")
	(net 221 "/DDR3/DDR3_DQ0")
	(net 222 "/DDR3/DDR3_DQ3")
	(net 223 "/DDR3/DDR3_LDQS_P")
	(net 224 "/DDR3/DDR3_DQ5")
	(net 225 "/DDR3/DDR3_DQ7")
	(net 226 "/DDR3/DDR3_DQ8")
	(net 227 "/DDR3/DDR3_UDQS_P")
	(net 228 "/DDR3/DDR3_DQ11")
	(net 229 "/DDR3/DDR3_DQ12")
	(net 230 "/DDR3/DDR3_UDM")
	(net 231 "/DDR3/DDR3_DQ15")
	(net 232 "/DDR3/DDR3_LDM")
	(net 233 "/DDR3/DDR3_DQ1")
	(net 234 "/DDR3/DDR3_DQ2")
	(net 235 "/DDR3/DDR3_DQ4")
	(net 236 "/DDR3/DDR3_DQ6")
	(net 237 "/DDR3/DDR3_DQ10")
	(net 238 "/DDR3/DDR3_DQ9")
	(net 239 "/DDR3/DDR3_UDQS_N")
	(net 240 "/DDR3/DDR3_DQ13")
	(net 241 "/DDR3/DDR3_DQ14")
	(net 242 "Net-(U15B-VBG)")
	(net 243 "/SDI/SDI_IN_F")
	(net 244 "Net-(U15C-VCO_{VDD})")
	(net 245 "Net-(D6-A)")
	(net 246 "Net-(D7-A)")
	(net 247 "Net-(D8-A)")
	(net 248 "+1V5")
	(net 249 "/SDI/SDI_OUT_P")
	(net 250 "Net-(C77-Pad2)")
	(net 251 "/SDI/SDI_OUT_F2")
	(net 252 "/SDI/SDI_OUT")
	(net 253 "/SDI/SDI_IN")
	(net 254 "/SDI/SDI_OUT_N")
	(net 255 "Net-(D9-A)")
	(net 256 "Net-(D10-A)")
	(net 257 "Net-(D11-A)")
	(net 258 "Net-(D12-C)")
	(net 259 "Net-(Q1-D)")
	(net 260 "Net-(Q3-G)")
	(net 261 "Net-(Q6-G)")
	(net 262 "Net-(U1-V_{TT_EN})")
	(net 263 "Net-(U6-FB)")
	(net 264 "Net-(U8-V_{IN})")
	(net 265 "Net-(U9-V_{IN})")
	(net 266 "Net-(U10-V_{IN})")
	(net 267 "Net-(U5-FB)")
	(net 268 "Net-(U8-EN)")
	(net 269 "Net-(U9-EN)")
	(net 270 "Net-(U7-FB)")
	(net 271 "Net-(U10-EN)")
	(net 272 "Net-(U8-V_{OUT})")
	(net 273 "/Power Supply/1V0_OUT")
	(net 274 "/Power Supply/1V5_OUT")
	(net 275 "/Power Supply/3V3_OUT")
	(net 276 "/Power Supply/1V0_SW")
	(net 277 "/Power Supply/1V5_SW")
	(net 278 "/Power Supply/3V3_SW")
	(net 279 "Net-(U9-V_{OUT})")
	(net 280 "Net-(U8-ADJ)")
	(net 281 "Net-(R72-Pad2)")
	(net 282 "Net-(U9-ADJ)")
	(net 283 "Net-(U10-ADJ)")
	(net 284 "Net-(U10-V_{OUT})")
	(net 285 "Net-(U16-~{EQ_EN})")
	(net 286 "Net-(Y2-EN)")
	(net 287 "Net-(U12A-ZQ)")
	(net 288 "Net-(U15B-LB_CONT)")
	(net 289 "Net-(U16-RSET)")
	(net 290 "Net-(U17-SDA)")
	(net 291 "/SDI/AGC_N")
	(net 292 "/SDI/AGC_P")
	(net 293 "/SDI/SDI_N2")
	(net 294 "Net-(D12-A)")
	(net 295 "Net-(D13-A)")
	(net 296 "Net-(D13-C)")
	(net 297 "unconnected-(J1-SBU_{1}-PadA8)")
	(net 298 "Net-(U17-SCL)")
	(net 299 "Net-(U17-~{RESET})")
	(net 300 "Net-(U18-SI{slash}IO0)")
	(net 301 "Net-(U18-SO{slash}IO1)")
	(net 302 "Net-(J6-Pad40)")
	(net 303 "Net-(U18-SCLK)")
	(net 304 "/Power Supply/5V_I")
	(net 305 "/Power Supply/~{FAULT}")
	(net 306 "Net-(U18-~{CS})")
	(net 307 "/Peripherals/FFC1_PEN")
	(net 308 "Net-(U17-A2)")
	(net 309 "Net-(U17-~{INT})")
	(net 310 "/Peripherals/QWIIC_3V3")
	(net 311 "Net-(J1-CC_{1})")
	(net 312 "Net-(J8-Pad3)")
	(net 313 "Net-(J8-Pad4)")
	(net 314 "/Peripherals/QW_FLT")
	(net 315 "/Peripherals/QWIIC_PEN")
	(net 316 "Net-(U17-A1)")
	(net 317 "unconnected-(U12-PadL9)")
	(net 318 "unconnected-(U12-PadJ9)")
	(net 319 "unconnected-(U12-PadT7)")
	(net 320 "unconnected-(U12-PadM7)")
	(net 321 "unconnected-(U12-PadL1)")
	(net 322 "unconnected-(U12-PadJ1)")
	(net 323 "Net-(J6-Pad39)")
	(net 324 "Net-(U21-D4)")
	(net 325 "USB_POWER_IN")
	(net 326 "/Power Supply/5V_1V0_IN")
	(net 327 "/Power Supply/5V_1V5_IN")
	(net 328 "/Power Supply/5V_3V3_IN")
	(net 329 "/Power Supply/FFC2_5V_1")
	(net 330 "Net-(U17-A0)")
	(net 331 "/Peripherals/3V3_MISC")
	(net 332 "GPIO0")
	(net 333 "GPIO1")
	(net 334 "GPIO2")
	(net 335 "GPIO3")
	(net 336 "Net-(J4-Pad33)")
	(net 337 "Net-(J4-Pad34)")
	(net 338 "unconnected-(J4-Pad35)")
	(net 339 "unconnected-(J4-Pad36)")
	(net 340 "unconnected-(J4-Pad37)")
	(net 341 "unconnected-(J4-Pad38)")
	(net 342 "Net-(J4-Pad39)")
	(net 343 "Net-(J6-Pad32)")
	(net 344 "Net-(J6-Pad33)")
	(net 345 "Net-(J6-Pad34)")
	(net 346 "Net-(J6-Pad41)")
	(net 347 "Net-(J6-Pad42)")
	(net 348 "/Peripherals/FTDI_VCCIO")
	(net 349 "Net-(U4-ILIM)")
	(net 350 "Net-(J1-CC_{2})")
	(net 351 "Net-(U13-~{FAULT})")
	(net 352 "unconnected-(J1-SBU_{2}-PadB8)")
	(net 353 "Net-(U13-ILIM)")
	(net 354 "Net-(U14-ILIM)")
	(net 355 "RXD")
	(net 356 "Net-(U19-ILIM)")
	(net 357 "TXD")
	(net 358 "Net-(U17-GPIO2{slash}~{SS2})")
	(net 359 "/Peripherals/USB_DP")
	(net 360 "/Peripherals/USB_DN")
	(net 361 "/Peripherals/USB_D2N")
	(net 362 "/Peripherals/USB_D2P")
	(net 363 "/FPGA/DONE_SOFT")
	(net 364 "Net-(J4-Pad40)")
	(net 365 "Net-(J4-Pad41)")
	(net 366 "Net-(J4-Pad42)")
	(net 367 "unconnected-(J4-Pad43)")
	(net 368 "unconnected-(J4-Pad44)")
	(net 369 "unconnected-(J4-Pad45)")
	(net 370 "unconnected-(J4-Pad46)")
	(net 371 "FCC2_SCL2")
	(net 372 "Net-(U17-GPIO3{slash}~{SS3})")
	(net 373 "Net-(U5-EN)")
	(net 374 "Net-(U6-EN)")
	(net 375 "Net-(U7-EN)")
	(net 376 "/FPGA/SEL")
	(net 377 "Net-(U15B-XTAL_OUT)")
	(net 378 "Net-(U16-~{OSP})")
	(net 379 "Net-(U20-CBUS0)")
	(net 380 "Net-(U20-CBUS3)")
	(net 381 "Net-(C80-Pad2)")
	(net 382 "Net-(Q2-Pad2)")
	(net 383 "unconnected-(U11L-SD0_TXD--PadA11)")
	(net 384 "unconnected-(U11L-SD0_TXD+-PadA12)")
	(net 385 "unconnected-(U11M-VCCAUXSD-PadB11)")
	(net 386 "unconnected-(U11L-SD0_REFRET-PadB12)")
	(net 387 "unconnected-(U11M-VCCPLLSD0-PadB13)")
	(net 388 "unconnected-(U11M-VCCSD0-PadB15)")
	(net 389 "unconnected-(U11A-PT82B{slash}MCSNO{slash}MSDO-PadC13)")
	(net 390 "unconnected-(U11K-VCCADC18-PadL14)")
	(net 391 "unconnected-(U16-NC-Pad5)")
	(net 392 "unconnected-(U16-NC-Pad7)")
	(net 393 "unconnected-(U16-NC-Pad8)")
	(net 394 "unconnected-(U16-NC-Pad13)")
	(net 395 "unconnected-(U16-NC-Pad15)")
	(net 396 "unconnected-(U20-~{CTS}-Pad4)")
	(net 397 "unconnected-(U20-~{RTS}-Pad16)")
	(net 398 "unconnected-(MP1-Pad1)")
	(net 399 "unconnected-(MP2-Pad1)")
	(net 400 "unconnected-(MP3-Pad1)")
	(net 401 "unconnected-(MP4-Pad1)")
	(footprint "antmicro-footprints:SOT-23-5"
		(layer "F.Cu")
		(at 141.69 106.9 180)
		(property "Reference" "U8"
			(at -2.34 1.96 0)
			(layer "F.SilkS")
			(effects
				(font
					(size 0.65 0.65)
					(thickness 0.15)
				)
				(justify right bottom)
			)
		)
		(property "Value" "AP7330-W5-7"
			(at 0.002 2.799 0)
			(layer "F.Fab")
			(hide yes)
			(effects
				(font
					(size 0.7 0.7)
					(thickness 0.15)
				)
				(justify right bottom)
			)
		)
		(property "Datasheet" "https://www.diodes.com/assets/Datasheets/AP7330.pdf"
			(at 0 0 180)
			(layer "F.Fab")
			(hide yes)
			(effects
				(font
					(size 1.27 1.27)
					(thickness 0.15)
				)
			)
		)
		(property "Description" "Voltage regulator"
			(at 0 0 180)
			(layer "F.Fab")
			(hide yes)
			(effects
				(font
					(size 1.27 1.27)
					(thickness 0.15)
				)
			)
		)
		(property "Author" "Antmicro"
			(at 283.38 213.8 0)
			(layer "F.Fab")
			(hide yes)
			(effects
				(font
					(size 1 1)
					(thickness 0.15)
				)
			)
		)
		(property "License" "Apache-2.0"
			(at 283.38 213.8 0)
			(layer "F.Fab")
			(hide yes)
			(effects
				(font
					(size 1 1)
					(thickness 0.15)
				)
			)
		)
		(property "MPN" "AP7330-W5-7"
			(at 283.38 213.8 0)
			(layer "F.Fab")
			(hide yes)
			(effects
				(font
					(size 1 1)
					(thickness 0.15)
				)
			)
		)
		(property "Manufacturer" "Diodes Incorporated"
			(at 283.38 213.8 0)
			(layer "F.Fab")
			(hide yes)
			(effects
				(font
					(size 1 1)
					(thickness 0.15)
				)
			)
		)
		(sheetname "/Power Supply/")
		(sheetfile "supply.kicad_sch")
		(attr smd)
		(fp_line
			(start 0.8 1.599)
			(end 0.549 1.599)
			(stroke
				(width 0.15)
				(type solid)
			)
			(layer "F.SilkS")
		)
		(fp_line
			(start 0.8 1.3)
			(end 0.8 1.599)
			(stroke
				(width 0.15)
				(type solid)
			)
			(layer "F.SilkS")
		)
		(fp_line
			(start 0.8 0.55)
			(end 0.8 -0.55)
			(stroke
				(width 0.15)
				(type solid)
			)
			(layer "F.SilkS")
		)
		(fp_line
			(start 0.8 -1.3)
			(end 0.8 -1.6)
			(stroke
				(width 0.15)
				(type solid)
			)
			(layer "F.SilkS")
		)
		(fp_line
			(start 0.8 -1.6)
			(end 0.5 -1.6)
			(stroke
				(width 0.15)
				(type solid)
			)
			(layer "F.SilkS")
		)
		(fp_line
			(start -0.55 1.6)
			(end -0.85 1.6)
			(stroke
				(width 0.15)
				(type solid)
			)
			(layer "F.SilkS")
		)
		(fp_line
			(start -0.8 -1.6)
			(end -0.5 -1.6)
			(stroke
				(width 0.15)
				(type solid)
			)
			(layer "F.SilkS")
		)
		(fp_line
			(start -0.8 -1.6)
			(end -0.8 -1.3)
			(stroke
				(width 0.15)
				(type solid)
			)
			(layer "F.SilkS")
		)
		(fp_line
			(start -0.85 1.6)
			(end -0.85 1.301)
			(stroke
				(width 0.15)
				(type solid)
			)
			(layer "F.SilkS")
		)
		(fp_circle
			(center -1.25 -1.5)
			(end -1.2 -1.5)
			(stroke
				(width 0.15)
				(type solid)
			)
			(fill yes)
			(layer "F.SilkS")
		)
		(fp_rect
			(start 1.9 -1.76)
			(end -1.9 1.75)
			(stroke
				(width 0.05)
				(type solid)
			)
			(fill no)
			(layer "F.CrtYd")
		)
		(fp_line
			(start -0.398 -1.526)
			(end -0.874 -1.05)
			(stroke
				(width 0.15)
				(type solid)
			)
			(layer "F.Fab")
		)
		(fp_rect
			(start 0.874 1.523)
			(end -0.873 -1.525)
			(stroke
				(width 0.15)
				(type solid)
			)
			(fill no)
			(layer "F.Fab")
		)
		(pad "1" smd rect
			(at -1.351 -0.951 90)
			(size 0.55 1)
			(layers "F.Cu" "F.Mask" "F.Paste")
			(net 264 "Net-(U8-V_{IN})")
			(pinfunction "V_{IN}")
			(pintype "power_in")
		)
		(pad "2" smd rect
			(at -1.351 0 90)
			(size 0.55 1)
			(layers "F.Cu" "F.Mask" "F.Paste")
			(net 1 "GND")
			(pinfunction "GND")
			(pintype "power_in")
		)
		(pad "3" smd rect
			(at -1.351 0.949 90)
			(size 0.55 1)
			(layers "F.Cu" "F.Mask" "F.Paste")
			(net 268 "Net-(U8-EN)")
			(pinfunction "EN")
			(pintype "input")
		)
		(pad "4" smd rect
			(at 1.35 0.949 90)
			(size 0.55 1)
			(layers "F.Cu" "F.Mask" "F.Paste")
			(net 280 "Net-(U8-ADJ)")
			(pinfunction "ADJ")
			(pintype "passive")
		)
		(pad "5" smd rect
			(at 1.35 -0.951 90)
			(size 0.55 1)
			(layers "F.Cu" "F.Mask" "F.Paste")
			(net 272 "Net-(U8-V_{OUT})")
			(pinfunction "V_{OUT}")
			(pintype "power_out")
		)
	)
	(footprint "antmicro-footprints:C_0402_1005Metric"
		(layer "F.Cu")
		(at 84.2 108.15 180)
		(descr "Capacitor SMD 0402")
		(tags "capacitor SMD 0402")
		(property "Reference" "C77"
			(at -4.33 7.81 0)
			(layer "F.SilkS")
			(effects
				(font
					(size 0.65 0.65)
					(thickness 0.15)
				)
				(justify right bottom)
			)
		)
		(property "Value" "C_4u7_0402"
			(at 0 1.4 0)
			(layer "F.Fab")
			(hide yes)
			(effects
				(font
					(size 0.7 0.7)
					(thickness 0.15)
				)
				(justify right bottom)
			)
		)
		(property "Datasheet" "https://www.murata.com/products/productdetail?partno=GRM155R61A475MEAA%23"
			(at 0 0 180)
			(layer "F.Fab")
			(hide yes)
			(effects
				(font
					(size 1.27 1.27)
					(thickness 0.15)
				)
			)
		)
		(property "Description" "SMD Multilayer Ceramic Capacitor, 4.7 µF, 10 V, 0402 [1005 Metric], ± 20%, X5R, GRM Series"
			(at 0 0 180)
			(layer "F.Fab")
			(hide yes)
			(effects
				(font
					(size 1.27 1.27)
					(thickness 0.15)
				)
			)
		)
		(property "Author" "Antmicro"
			(at 168.4 216.3 0)
			(layer "F.Fab")
			(hide yes)
			(effects
				(font
					(size 1 1)
					(thickness 0.15)
				)
			)
		)
		(property "Dielectric" ""
			(at 168.4 216.3 0)
			(layer "F.Fab")
			(hide yes)
			(effects
				(font
					(size 1 1)
					(thickness 0.15)
				)
			)
		)
		(property "License" "Apache-2.0"
			(at 168.4 216.3 0)
			(layer "F.Fab")
			(hide yes)
			(effects
				(font
					(size 1 1)
					(thickness 0.15)
				)
			)
		)
		(property "MPN" "GRM155R61A475MEAAD"
			(at 168.4 216.3 0)
			(layer "F.Fab")
			(hide yes)
			(effects
				(font
					(size 1 1)
					(thickness 0.15)
				)
			)
		)
		(property "Manufacturer" "Murata"
			(at 168.4 216.3 0)
			(layer "F.Fab")
			(hide yes)
			(effects
				(font
					(size 1 1)
					(thickness 0.15)
				)
			)
		)
		(property "Val" "4u7"
			(at 168.4 216.3 0)
			(layer "F.Fab")
			(hide yes)
			(effects
				(font
					(size 1 1)
					(thickness 0.15)
				)
			)
		)
		(property "Voltage" ""
			(at 168.4 216.3 0)
			(layer "F.Fab")
			(hide yes)
			(effects
				(font
					(size 1 1)
					(thickness 0.15)
				)
			)
		)
		(sheetname "/SDI/")
		(sheetfile "sdi.kicad_sch")
		(attr smd)
		(fp_rect
			(start -0.925 -0.47)
			(end 0.925 0.47)
			(stroke
				(width 0.05)
				(type default)
			)
			(fill no)
			(layer "F.CrtYd")
		)
		(fp_line
			(start 0.504 0.248)
			(end -0.494 0.248)
			(stroke
				(width 0.15)
				(type solid)
			)
			(layer "F.Fab")
		)
		(fp_line
			(start 0.504 -0.25)
			(end 0.504 0.248)
			(stroke
				(width 0.15)
				(type solid)
			)
			(layer "F.Fab")
		)
		(fp_line
			(start -0.494 0.248)
			(end -0.494 -0.25)
			(stroke
				(width 0.15)
				(type solid)
			)
			(layer "F.Fab")
		)
		(fp_line
			(start -0.494 -0.25)
			(end 0.504 -0.25)
			(stroke
				(width 0.15)
				(type solid)
			)
			(layer "F.Fab")
		)
		(fp_text user "${REFERENCE}"
			(at -0.939 4.599 180)
			(layer "F.Fab")
			(effects
				(font
					(size 0.7 0.7)
					(thickness 0.15)
				)
				(justify left bottom)
			)
		)
		(fp_text user "License: Apache-2.0"
			(at -0.939 5.799 180)
			(layer "F.Fab")
			(effects
				(font
					(size 0.7 0.7)
					(thickness 0.15)
				)
				(justify left bottom)
			)
		)
		(fp_text user "Author: Antmicro"
			(at -0.939 3.399 180)
			(layer "F.Fab")
			(effects
				(font
					(size 0.7 0.7)
					(thickness 0.15)
				)
				(justify left bottom)
			)
		)
		(pad "1" smd roundrect
			(at -0.48 0 180)
			(size 0.59 0.64)
			(layers "F.Cu" "F.Mask" "F.Paste")
			(roundrect_rratio 0.25)
			(net 249 "/SDI/SDI_OUT_P")
			(pintype "passive")
		)
		(pad "2" smd roundrect
			(at 0.48 0 180)
			(size 0.59 0.64)
			(layers "F.Cu" "F.Mask" "F.Paste")
			(roundrect_rratio 0.25)
			(net 250 "Net-(C77-Pad2)")
			(pintype "passive")
		)
	)
	(footprint "antmicro-footprints:L_0402_1005Metric"
		(layer "F.Cu")
		(at 86.6 76.4 180)
		(descr "Inductor SMD 0402")
		(tags "Inductor SMD 0402")
		(property "Reference" "L4"
			(at 2.77 6.26 180)
			(layer "F.SilkS")
			(effects
				(font
					(size 0.65 0.65)
					(thickness 0.15)
				)
				(justify left bottom)
			)
		)
		(property "Value" "L_6n2_0.7A_0402"
			(at 0 1.4 180)
			(layer "F.Fab")
			(hide yes)
			(effects
				(font
					(size 0.7 0.7)
					(thickness 0.15)
				)
				(justify left bottom)
			)
		)
		(property "Datasheet" "https://www.mouser.com/datasheet/2/281/1/JELF243A_0050-1380872.pdf"
			(at 0 0 180)
			(layer "F.Fab")
			(hide yes)
			(effects
				(font
					(size 1.27 1.27)
					(thickness 0.15)
				)
			)
		)
		(property "Description" "Wirewound Inductor, 6.2 nH, 0.09 ohm, 8 GHz, 700 mA, 0402 [1005 Metric], LQW"
			(at 0 0 180)
			(layer "F.Fab")
			(hide yes)
			(effects
				(font
					(size 1.27 1.27)
					(thickness 0.15)
				)
			)
		)
		(property "Author" "Antmicro"
			(at 173.2 152.8 0)
			(layer "F.Fab")
			(hide yes)
			(effects
				(font
					(size 1 1)
					(thickness 0.15)
				)
			)
		)
		(property "IMax" "0.7 A"
			(at 173.2 152.8 0)
			(layer "F.Fab")
			(hide yes)
			(effects
				(font
					(size 1 1)
					(thickness 0.15)
				)
			)
		)
		(property "ISat" ""
			(at 173.2 152.8 0)
			(layer "F.Fab")
			(hide yes)
			(effects
				(font
					(size 1 1)
					(thickness 0.15)
				)
			)
		)
		(property "License" "Apache-2.0"
			(at 173.2 152.8 0)
			(layer "F.Fab")
			(hide yes)
			(effects
				(font
					(size 1 1)
					(thickness 0.15)
				)
			)
		)
		(property "MPN" "LQW15AN6N2C00D"
			(at 173.2 152.8 0)
			(layer "F.Fab")
			(hide yes)
			(effects
				(font
					(size 1 1)
					(thickness 0.15)
				)
			)
		)
		(property "Manufacturer" "Murata"
			(at 173.2 152.8 0)
			(layer "F.Fab")
			(hide yes)
			(effects
				(font
					(size 1 1)
					(thickness 0.15)
				)
			)
		)
		(property "Size" "1.0x0.5"
			(at 173.2 152.8 0)
			(layer "F.Fab")
			(hide yes)
			(effects
				(font
					(size 1 1)
					(thickness 0.15)
				)
			)
		)
		(property "Val" "6n2/0.7A"
			(at 173.2 152.8 0)
			(layer "F.Fab")
			(hide yes)
			(effects
				(font
					(size 1 1)
					(thickness 0.15)
				)
			)
		)
		(sheetname "/SDI/")
		(sheetfile "sdi.kicad_sch")
		(attr smd)
		(fp_rect
			(start -0.925 -0.47)
			(end 0.925 0.47)
			(stroke
				(width 0.05)
				(type default)
			)
			(fill no)
			(layer "F.CrtYd")
		)
		(fp_rect
			(start -0.499 -0.249)
			(end 0.499 0.249)
			(stroke
				(width 0.15)
				(type solid)
			)
			(fill no)
			(layer "F.Fab")
		)
		(fp_text user "Author: Antmicro"
			(at -0.932 4.17 180)
			(layer "F.Fab")
			(effects
				(font
					(size 0.7 0.7)
					(thickness 0.15)
				)
				(justify left bottom)
			)
		)
		(fp_text user "License: Apache-2.0"
			(at -0.932 5.17 180)
			(layer "F.Fab")
			(effects
				(font
					(size 0.7 0.7)
					(thickness 0.15)
				)
				(justify left bottom)
			)
		)
		(fp_text user "${REFERENCE}"
			(at -0.932 3.168 180)
			(layer "F.Fab")
			(effects
				(font
					(size 0.7 0.7)
					(thickness 0.15)
				)
				(justify left bottom)
			)
		)
		(pad "1" smd roundrect
			(at -0.48 0 180)
			(size 0.59 0.64)
			(layers "F.Cu" "F.Mask" "F.Paste")
			(roundrect_rratio 0.25)
			(net 243 "/SDI/SDI_IN_F")
			(pintype "passive")
		)
		(pad "2" smd roundrect
			(at 0.48 0 180)
			(size 0.59 0.64)
			(layers "F.Cu" "F.Mask" "F.Paste")
			(roundrect_rratio 0.25)
			(net 253 "/SDI/SDI_IN")
			(pintype "passive")
		)
	)
	(footprint "antmicro-footprints:TP_SMD_0.75mm"
		(layer "F.Cu")
		(at 104.9492 90.4 -90)
		(property "Reference" "TP17"
			(at -2.93 0.2792 90)
			(layer "F.SilkS")
			(effects
				(font
					(size 0.65 0.65)
					(thickness 0.15)
				)
				(justify right top)
			)
		)
		(property "Value" "TP_0.75mm_SMD"
			(at 0 1.2 90)
			(layer "F.Fab")
			(hide yes)
			(effects
				(font
					(size 0.7 0.7)
					(thickness 0.15)
				)
				(justify right bottom)
			)
		)
		(property "Description" "SMT test point"
			(at 0 0 90)
			(layer "F.Fab")
			(hide yes)
			(effects
				(font
					(size 1.27 1.27)
					(thickness 0.15)
				)
			)
		)
		(property "Author" "Antmicro"
			(at 14.5492 195.3492 0)
			(layer "F.Fab")
			(hide yes)
			(effects
				(font
					(size 1 1)
					(thickness 0.15)
				)
			)
		)
		(property "License" "Apache-2.0"
			(at 14.5492 195.3492 0)
			(layer "F.Fab")
			(hide yes)
			(effects
				(font
					(size 1 1)
					(thickness 0.15)
				)
			)
		)
		(property "MPN" ""
			(at 14.5492 195.3492 0)
			(layer "F.Fab")
			(hide yes)
			(effects
				(font
					(size 1 1)
					(thickness 0.15)
				)
			)
		)
		(property "Manufacturer" ""
			(at 14.5492 195.3492 0)
			(layer "F.Fab")
			(hide yes)
			(effects
				(font
					(size 1 1)
					(thickness 0.15)
				)
			)
		)
		(sheetname "/FPGA/")
		(sheetfile "fpga.kicad_sch")
		(attr exclude_from_pos_files)
		(fp_circle
			(center 0 0)
			(end 0.475 0)
			(stroke
				(width 0.05)
				(type default)
			)
			(fill no)
			(layer "F.CrtYd")
		)
		(fp_text user "${REFERENCE}"
			(at -0.4 2.7 90)
			(layer "F.Fab")
			(effects
				(font
					(size 0.7 0.7)
					(thickness 0.15)
				)
				(justify right top)
			)
		)
		(fp_text user "Author: Antmicro"
			(at -0.4 3.901 90)
			(layer "F.Fab")
			(effects
				(font
					(size 0.7 0.7)
					(thickness 0.15)
				)
				(justify right top)
			)
		)
		(fp_text user "License: Apache-2.0"
			(at -0.4 5.101 90)
			(layer "F.Fab")
			(effects
				(font
					(size 0.7 0.7)
					(thickness 0.15)
				)
				(justify right top)
			)
		)
		(pad "1" smd circle
			(at 0 0 270)
			(size 0.75 0.75)
			(layers "F.Cu" "F.Mask")
			(net 28 "/FPGA/SPI_DQ2")
			(pinfunction "1")
			(pintype "passive")
		)
	)
	(footprint "antmicro-footprints:TP_SMD_0.75mm"
		(layer "F.Cu")
		(at 102.69 97.1 -90)
		(property "Reference" "TP15"
			(at -0.33 3.06 0)
			(layer "F.SilkS")
			(effects
				(font
					(size 0.65 0.65)
					(thickness 0.15)
				)
				(justify left top)
			)
		)
		(property "Value" "TP_0.75mm_SMD"
			(at 0 1.2 90)
			(layer "F.Fab")
			(hide yes)
			(effects
				(font
					(size 0.7 0.7)
					(thickness 0.15)
				)
				(justify right bottom)
			)
		)
		(property "Description" "SMT test point"
			(at 0 0 90)
			(layer "F.Fab")
			(hide yes)
			(effects
				(font
					(size 1.27 1.27)
					(thickness 0.15)
				)
			)
		)
		(property "Author" "Antmicro"
			(at 5.59 199.79 0)
			(layer "F.Fab")
			(hide yes)
			(effects
				(font
					(size 1 1)
					(thickness 0.15)
				)
			)
		)
		(property "License" "Apache-2.0"
			(at 5.59 199.79 0)
			(layer "F.Fab")
			(hide yes)
			(effects
				(font
					(size 1 1)
					(thickness 0.15)
				)
			)
		)
		(property "MPN" ""
			(at 5.59 199.79 0)
			(layer "F.Fab")
			(hide yes)
			(effects
				(font
					(size 1 1)
					(thickness 0.15)
				)
			)
		)
		(property "Manufacturer" ""
			(at 5.59 199.79 0)
			(layer "F.Fab")
			(hide yes)
			(effects
				(font
					(size 1 1)
					(thickness 0.15)
				)
			)
		)
		(sheetname "/FPGA/")
		(sheetfile "fpga.kicad_sch")
		(attr exclude_from_pos_files)
		(fp_circle
			(center 0 0)
			(end 0.475 0)
			(stroke
				(width 0.05)
				(type default)
			)
			(fill no)
			(layer "F.CrtYd")
		)
		(fp_text user "License: Apache-2.0"
			(at -0.4 5.101 90)
			(layer "F.Fab")
			(effects
				(font
					(size 0.7 0.7)
					(thickness 0.15)
				)
				(justify right top)
			)
		)
		(fp_text user "${REFERENCE}"
			(at -0.4 2.7 90)
			(layer "F.Fab")
			(effects
				(font
					(size 0.7 0.7)
					(thickness 0.15)
				)
				(justify right top)
			)
		)
		(fp_text user "Author: Antmicro"
			(at -0.4 3.901 90)
			(layer "F.Fab")
			(effects
				(font
					(size 0.7 0.7)
					(thickness 0.15)
				)
				(justify right top)
			)
		)
		(pad "1" smd circle
			(at 0 0 270)
			(size 0.75 0.75)
			(layers "F.Cu" "F.Mask")
			(net 300 "Net-(U18-SI{slash}IO0)")
			(pinfunction "1")
			(pintype "passive")
		)
	)
	(footprint "antmicro-footprints:TP_SMD_0.75mm"
		(layer "F.Cu")
		(at 158.83 74.95)
		(property "Reference" "TP23"
			(at -1.4 -0.51 0)
			(layer "F.SilkS")
			(effects
				(font
					(size 0.65 0.65)
					(thickness 0.15)
				)
				(justify left bottom)
			)
		)
		(property "Value" "TP_0.75mm_SMD"
			(at 0 1.2 0)
			(layer "F.Fab")
			(hide yes)
			(effects
				(font
					(size 0.7 0.7)
					(thickness 0.15)
				)
				(justify left bottom)
			)
		)
		(property "Description" "SMT test point"
			(at 0 0 0)
			(layer "F.Fab")
			(hide yes)
			(effects
				(font
					(size 1.27 1.27)
					(thickness 0.15)
				)
			)
		)
		(property "Author" "Antmicro"
			(at 0 0 0)
			(layer "F.Fab")
			(hide yes)
			(effects
				(font
					(size 1 1)
					(thickness 0.15)
				)
			)
		)
		(property "License" "Apache-2.0"
			(at 0 0 0)
			(layer "F.Fab")
			(hide yes)
			(effects
				(font
					(size 1 1)
					(thickness 0.15)
				)
			)
		)
		(property "MPN" ""
			(at 0 0 0)
			(layer "F.Fab")
			(hide yes)
			(effects
				(font
					(size 1 1)
					(thickness 0.15)
				)
			)
		)
		(property "Manufacturer" ""
			(at 0 0 0)
			(layer "F.Fab")
			(hide yes)
			(effects
				(font
					(size 1 1)
					(thickness 0.15)
				)
			)
		)
		(sheetname "/Power Supply/")
		(sheetfile "supply.kicad_sch")
		(attr exclude_from_pos_files)
		(fp_circle
			(center 0 0)
			(end 0.475 0)
			(stroke
				(width 0.05)
				(type default)
			)
			(fill no)
			(layer "F.CrtYd")
		)
		(fp_text user "License: Apache-2.0"
			(at -0.4 5.101 0)
			(layer "F.Fab")
			(effects
				(font
					(size 0.7 0.7)
					(thickness 0.15)
				)
				(justify left bottom)
			)
		)
		(fp_text user "Author: Antmicro"
			(at -0.4 3.901 0)
			(layer "F.Fab")
			(effects
				(font
					(size 0.7 0.7)
					(thickness 0.15)
				)
				(justify left bottom)
			)
		)
		(fp_text user "${REFERENCE}"
			(at -0.4 2.7 0)
			(layer "F.Fab")
			(effects
				(font
					(size 0.7 0.7)
					(thickness 0.15)
				)
				(justify left bottom)
			)
		)
		(pad "1" smd circle
			(at 0 0)
			(size 0.75 0.75)
			(layers "F.Cu" "F.Mask")
			(net 305 "/Power Supply/~{FAULT}")
			(pinfunction "1")
			(pintype "passive")
		)
	)
	(footprint "antmicro-footprints:R_0603_1608Metric"
		(layer "F.Cu")
		(at 158.29 82.7 180)
		(descr "Resistor SMD 0603")
		(tags "resistor SMD 0603")
		(property "Reference" "R115"
			(at 4.06 -0.44 180)
			(layer "F.SilkS")
			(effects
				(font
					(size 0.65 0.65)
					(thickness 0.15)
				)
				(justify left bottom)
			)
		)
		(property "Value" "R_10k_0603"
			(at 0 1.6 180)
			(layer "F.Fab")
			(hide yes)
			(effects
				(font
					(size 0.7 0.7)
					(thickness 0.15)
				)
				(justify left bottom)
			)
		)
		(property "Datasheet" "https://www.bourns.com/docs/product-datasheets/cr.pdf"
			(at 0 0 180)
			(layer "F.Fab")
			(hide yes)
			(effects
				(font
					(size 1.27 1.27)
					(thickness 0.15)
				)
			)
		)
		(property "Description" "SMD Chip Resistor, 10 kohm, ± 1%, 100 mW, 0603 [1608 Metric], Thick Film, General Purpose"
			(at 0 0 180)
			(layer "F.Fab")
			(hide yes)
			(effects
				(font
					(size 1.27 1.27)
					(thickness 0.15)
				)
			)
		)
		(property "Author" "Antmicro"
			(at 316.58 165.4 0)
			(layer "F.Fab")
			(hide yes)
			(effects
				(font
					(size 1 1)
					(thickness 0.15)
				)
			)
		)
		(property "License" "Apache-2.0"
			(at 316.58 165.4 0)
			(layer "F.Fab")
			(hide yes)
			(effects
				(font
					(size 1 1)
					(thickness 0.15)
				)
			)
		)
		(property "MPN" "CR0603-FX-1002ELF"
			(at 316.58 165.4 0)
			(layer "F.Fab")
			(hide yes)
			(effects
				(font
					(size 1 1)
					(thickness 0.15)
				)
			)
		)
		(property "Manufacturer" "Bourns"
			(at 316.58 165.4 0)
			(layer "F.Fab")
			(hide yes)
			(effects
				(font
					(size 1 1)
					(thickness 0.15)
				)
			)
		)
		(property "Tolerance" "1%"
			(at 316.58 165.4 0)
			(layer "F.Fab")
			(hide yes)
			(effects
				(font
					(size 1 1)
					(thickness 0.15)
				)
			)
		)
		(property "Val" "10k"
			(at 316.58 165.4 0)
			(layer "F.Fab")
			(hide yes)
			(effects
				(font
					(size 1 1)
					(thickness 0.15)
				)
			)
		)
		(sheetname "/Peripherals/")
		(sheetfile "peripherals.kicad_sch")
		(attr smd exclude_from_pos_files exclude_from_bom dnp)
		(fp_line
			(start -0.15 0.4)
			(end 0.15 0.4)
			(stroke
				(width 0.15)
				(type solid)
			)
			(layer "F.SilkS")
		)
		(fp_line
			(start -0.15 -0.4)
			(end 0.15 -0.4)
			(stroke
				(width 0.15)
				(type solid)
			)
			(layer "F.SilkS")
		)
		(fp_rect
			(start -1.25 -0.65)
			(end 1.25 0.65)
			(stroke
				(width 0.05)
				(type solid)
			)
			(fill no)
			(layer "F.CrtYd")
		)
		(fp_rect
			(start -0.8 -0.4)
			(end 0.8 0.4)
			(stroke
				(width 0.15)
				(type solid)
			)
			(fill no)
			(layer "F.Fab")
		)
		(fp_text user "Author: Antmicro"
			(at -1.25 4.9 180)
			(layer "F.Fab")
			(effects
				(font
					(size 0.7 0.7)
					(thickness 0.15)
				)
				(justify left bottom)
			)
		)
		(fp_text user "License: Apache-2.0"
			(at -1.25 5.9 180)
			(layer "F.Fab")
			(effects
				(font
					(size 0.7 0.7)
					(thickness 0.15)
				)
				(justify left bottom)
			)
		)
		(fp_text user "${REFERENCE}"
			(at -1.25 3.898 180)
			(layer "F.Fab")
			(effects
				(font
					(size 0.7 0.7)
					(thickness 0.15)
				)
				(justify left bottom)
			)
		)
		(pad "1" smd roundrect
			(at -0.7 0 180)
			(size 0.8 1)
			(layers "F.Cu" "F.Mask" "F.Paste")
			(roundrect_rratio 0.2)
			(net 315 "/Peripherals/QWIIC_PEN")
			(pintype "passive")
		)
		(pad "2" smd roundrect
			(at 0.7 0 180)
			(size 0.8 1)
			(layers "F.Cu" "F.Mask" "F.Paste")
			(roundrect_rratio 0.2)
			(net 1 "GND")
			(pintype "passive")
		)
	)
	(footprint "antmicro-footprints:TP_SMD_0.75mm"
		(layer "F.Cu")
		(at 140.33 69.25 90)
		(property "Reference" "TP10"
			(at 0 -0.6 90)
			(layer "F.SilkS")
			(effects
				(font
					(size 0.65 0.65)
					(thickness 0.15)
				)
				(justify left bottom)
			)
		)
		(property "Value" "TP_0.75mm_SMD"
			(at 0 1.2 90)
			(layer "F.Fab")
			(hide yes)
			(effects
				(font
					(size 0.7 0.7)
					(thickness 0.15)
				)
				(justify left bottom)
			)
		)
		(property "Description" "SMT test point"
			(at 0 0 90)
			(layer "F.Fab")
			(hide yes)
			(effects
				(font
					(size 1.27 1.27)
					(thickness 0.15)
				)
			)
		)
		(property "Author" "Antmicro"
			(at 209.58 -71.08 0)
			(layer "F.Fab")
			(hide yes)
			(effects
				(font
					(size 1 1)
					(thickness 0.15)
				)
			)
		)
		(property "License" "Apache-2.0"
			(at 209.58 -71.08 0)
			(layer "F.Fab")
			(hide yes)
			(effects
				(font
					(size 1 1)
					(thickness 0.15)
				)
			)
		)
		(property "MPN" ""
			(at 209.58 -71.08 0)
			(layer "F.Fab")
			(hide yes)
			(effects
				(font
					(size 1 1)
					(thickness 0.15)
				)
			)
		)
		(property "Manufacturer" ""
			(at 209.58 -71.08 0)
			(layer "F.Fab")
			(hide yes)
			(effects
				(font
					(size 1 1)
					(thickness 0.15)
				)
			)
		)
		(sheetname "/Power Supply/")
		(sheetfile "supply.kicad_sch")
		(attr exclude_from_pos_files)
		(fp_circle
			(center 0 0)
			(end 0.475 0)
			(stroke
				(width 0.05)
				(type default)
			)
			(fill no)
			(layer "F.CrtYd")
		)
		(fp_text user "Author: Antmicro"
			(at -0.4 3.901 90)
			(layer "F.Fab")
			(effects
				(font
					(size 0.7 0.7)
					(thickness 0.15)
				)
				(justify left bottom)
			)
		)
		(fp_text user "License: Apache-2.0"
			(at -0.4 5.101 90)
			(layer "F.Fab")
			(effects
				(font
					(size 0.7 0.7)
					(thickness 0.15)
				)
				(justify left bottom)
			)
		)
		(fp_text user "${REFERENCE}"
			(at -0.4 2.7 90)
			(layer "F.Fab")
			(effects
				(font
					(size 0.7 0.7)
					(thickness 0.15)
				)
				(justify left bottom)
			)
		)
		(pad "1" smd circle
			(at 0 0 90)
			(size 0.75 0.75)
			(layers "F.Cu" "F.Mask")
			(net 373 "Net-(U5-EN)")
			(pinfunction "1")
			(pintype "passive")
		)
	)
	(footprint "antmicro-footprints:R_0603_1608Metric"
		(layer "F.Cu")
		(at 169.83 80.968952 180)
		(descr "Resistor SMD 0603")
		(tags "resistor SMD 0603")
		(property "Reference" "R102"
			(at 4.1 -0.29 180)
			(layer "F.SilkS")
			(effects
				(font
					(size 0.65 0.65)
					(thickness 0.15)
				)
				(justify left bottom)
			)
		)
		(property "Value" "R_200R_0603"
			(at 0 1.6 180)
			(layer "F.Fab")
			(hide yes)
			(effects
				(font
					(size 0.7 0.7)
					(thickness 0.15)
				)
				(justify left bottom)
			)
		)
		(property "Datasheet" "https://www.bourns.com/docs/product-datasheets/cr.pdf"
			(at 0 0 180)
			(layer "F.Fab")
			(hide yes)
			(effects
				(font
					(size 1.27 1.27)
					(thickness 0.15)
				)
			)
		)
		(property "Description" "SMD Chip Resistor, 200 ohm, ± 1%, 100 mW, 0603 [1608 Metric], Thick Film, General Purpose"
			(at 0 0 180)
			(layer "F.Fab")
			(hide yes)
			(effects
				(font
					(size 1.27 1.27)
					(thickness 0.15)
				)
			)
		)
		(property "Author" "Antmicro"
			(at 339.66 161.9 0)
			(layer "F.Fab")
			(hide yes)
			(effects
				(font
					(size 1 1)
					(thickness 0.15)
				)
			)
		)
		(property "License" "Apache-2.0"
			(at 339.66 161.9 0)
			(layer "F.Fab")
			(hide yes)
			(effects
				(font
					(size 1 1)
					(thickness 0.15)
				)
			)
		)
		(property "MPN" "CR0603-FX-2000ELF"
			(at 339.66 161.9 0)
			(layer "F.Fab")
			(hide yes)
			(effects
				(font
					(size 1 1)
					(thickness 0.15)
				)
			)
		)
		(property "Manufacturer" "Bourns"
			(at 339.66 161.9 0)
			(layer "F.Fab")
			(hide yes)
			(effects
				(font
					(size 1 1)
					(thickness 0.15)
				)
			)
		)
		(property "Tolerance" "1%"
			(at 339.66 161.9 0)
			(layer "F.Fab")
			(hide yes)
			(effects
				(font
					(size 1 1)
					(thickness 0.15)
				)
			)
		)
		(property "Val" "200R"
			(at 339.66 161.9 0)
			(layer "F.Fab")
			(hide yes)
			(effects
				(font
					(size 1 1)
					(thickness 0.15)
				)
			)
		)
		(sheetname "/Peripherals/")
		(sheetfile "peripherals.kicad_sch")
		(attr smd)
		(fp_line
			(start -0.15 0.4)
			(end 0.15 0.4)
			(stroke
				(width 0.15)
				(type solid)
			)
			(layer "F.SilkS")
		)
		(fp_line
			(start -0.15 -0.4)
			(end 0.15 -0.4)
			(stroke
				(width 0.15)
				(type solid)
			)
			(layer "F.SilkS")
		)
		(fp_rect
			(start -1.25 -0.65)
			(end 1.25 0.65)
			(stroke
				(width 0.05)
				(type solid)
			)
			(fill no)
			(layer "F.CrtYd")
		)
		(fp_rect
			(start -0.8 -0.4)
			(end 0.8 0.4)
			(stroke
				(width 0.15)
				(type solid)
			)
			(fill no)
			(layer "F.Fab")
		)
		(fp_text user "License: Apache-2.0"
			(at -1.25 5.9 180)
			(layer "F.Fab")
			(effects
				(font
					(size 0.7 0.7)
					(thickness 0.15)
				)
				(justify left bottom)
			)
		)
		(fp_text user "${REFERENCE}"
			(at -1.25 3.898 180)
			(layer "F.Fab")
			(effects
				(font
					(size 0.7 0.7)
					(thickness 0.15)
				)
				(justify left bottom)
			)
		)
		(fp_text user "Author: Antmicro"
			(at -1.25 4.9 180)
			(layer "F.Fab")
			(effects
				(font
					(size 0.7 0.7)
					(thickness 0.15)
				)
				(justify left bottom)
			)
		)
		(pad "1" smd roundrect
			(at -0.7 0 180)
			(size 0.8 1)
			(layers "F.Cu" "F.Mask" "F.Paste")
			(roundrect_rratio 0.2)
			(net 255 "Net-(D9-A)")
			(pintype "passive")
		)
		(pad "2" smd roundrect
			(at 0.7 0 180)
			(size 0.8 1)
			(layers "F.Cu" "F.Mask" "F.Paste")
			(roundrect_rratio 0.2)
			(net 17 "/Peripherals/FFC1_3V3")
			(pintype "passive")
		)
	)
	(footprint "antmicro-footprints:R_0603_1608Metric"
		(layer "F.Cu")
		(at 163.63 123.75 180)
		(descr "Resistor SMD 0603")
		(tags "resistor SMD 0603")
		(property "Reference" "R119"
			(at -4.2 -0.39 0)
			(layer "F.SilkS")
			(effects
				(font
					(size 0.65 0.65)
					(thickness 0.15)
				)
				(justify right bottom)
			)
		)
		(property "Value" "R_0R_0603"
			(at 0 1.6 0)
			(layer "F.Fab")
			(hide yes)
			(effects
				(font
					(size 0.7 0.7)
					(thickness 0.15)
				)
				(justify right bottom)
			)
		)
		(property "Datasheet" "https://www.bourns.com/docs/product-datasheets/cr.pdf?sfvrsn=574d41f6_14"
			(at 0 0 180)
			(layer "F.Fab")
			(hide yes)
			(effects
				(font
					(size 1.27 1.27)
					(thickness 0.15)
				)
			)
		)
		(property "Description" "Zero Ohm Resistor, Jumper, 0603 [1608 Metric], Thick Film, 100 mW, 1 A, Surface Mount Device, CR"
			(at 0 0 180)
			(layer "F.Fab")
			(hide yes)
			(effects
				(font
					(size 1.27 1.27)
					(thickness 0.15)
				)
			)
		)
		(property "Author" "Antmicro"
			(at 327.26 247.5 0)
			(layer "F.Fab")
			(hide yes)
			(effects
				(font
					(size 1 1)
					(thickness 0.15)
				)
			)
		)
		(property "Current" "1A"
			(at 327.26 247.5 0)
			(layer "F.Fab")
			(hide yes)
			(effects
				(font
					(size 1 1)
					(thickness 0.15)
				)
			)
		)
		(property "License" "Apache-2.0"
			(at 327.26 247.5 0)
			(layer "F.Fab")
			(hide yes)
			(effects
				(font
					(size 1 1)
					(thickness 0.15)
				)
			)
		)
		(property "MPN" "CR0603-J/-000ELF"
			(at 327.26 247.5 0)
			(layer "F.Fab")
			(hide yes)
			(effects
				(font
					(size 1 1)
					(thickness 0.15)
				)
			)
		)
		(property "Manufacturer" "Bourns"
			(at 327.26 247.5 0)
			(layer "F.Fab")
			(hide yes)
			(effects
				(font
					(size 1 1)
					(thickness 0.15)
				)
			)
		)
		(property "Tolerance" "~"
			(at 327.26 247.5 0)
			(layer "F.Fab")
			(hide yes)
			(effects
				(font
					(size 1 1)
					(thickness 0.15)
				)
			)
		)
		(property "Val" "0R"
			(at 327.26 247.5 0)
			(layer "F.Fab")
			(hide yes)
			(effects
				(font
					(size 1 1)
					(thickness 0.15)
				)
			)
		)
		(sheetname "/Peripherals/")
		(sheetfile "peripherals.kicad_sch")
		(attr smd)
		(fp_line
			(start -0.15 0.4)
			(end 0.15 0.4)
			(stroke
				(width 0.15)
				(type solid)
			)
			(layer "F.SilkS")
		)
		(fp_line
			(start -0.15 -0.4)
			(end 0.15 -0.4)
			(stroke
				(width 0.15)
				(type solid)
			)
			(layer "F.SilkS")
		)
		(fp_rect
			(start -1.25 -0.65)
			(end 1.25 0.65)
			(stroke
				(width 0.05)
				(type solid)
			)
			(fill no)
			(layer "F.CrtYd")
		)
		(fp_rect
			(start -0.8 -0.4)
			(end 0.8 0.4)
			(stroke
				(width 0.15)
				(type solid)
			)
			(fill no)
			(layer "F.Fab")
		)
		(fp_text user "${REFERENCE}"
			(at -1.25 3.898 180)
			(layer "F.Fab")
			(effects
				(font
					(size 0.7 0.7)
					(thickness 0.15)
				)
				(justify left bottom)
			)
		)
		(fp_text user "License: Apache-2.0"
			(at -1.25 5.9 180)
			(layer "F.Fab")
			(effects
				(font
					(size 0.7 0.7)
					(thickness 0.15)
				)
				(justify left bottom)
			)
		)
		(fp_text user "Author: Antmicro"
			(at -1.25 4.9 180)
			(layer "F.Fab")
			(effects
				(font
					(size 0.7 0.7)
					(thickness 0.15)
				)
				(justify left bottom)
			)
		)
		(pad "1" smd roundrect
			(at -0.7 0 180)
			(size 0.8 1)
			(layers "F.Cu" "F.Mask" "F.Paste")
			(roundrect_rratio 0.2)
			(net 315 "/Peripherals/QWIIC_PEN")
			(pintype "passive")
		)
		(pad "2" smd roundrect
			(at 0.7 0 180)
			(size 0.8 1)
			(layers "F.Cu" "F.Mask" "F.Paste")
			(roundrect_rratio 0.2)
			(net 335 "GPIO3")
			(pintype "passive")
		)
	)
	(footprint "antmicro-footprints:R_0603_1608Metric"
		(layer "F.Cu")
		(at 158.53 91.65 -90)
		(descr "Resistor SMD 0603")
		(tags "resistor SMD 0603")
		(property "Reference" "R104"
			(at -1.31 1.52 90)
			(layer "F.SilkS")
			(effects
				(font
					(size 0.65 0.65)
					(thickness 0.15)
				)
				(justify right top)
			)
		)
		(property "Value" "R_10k_0603"
			(at 0 1.6 90)
			(layer "F.Fab")
			(hide yes)
			(effects
				(font
					(size 0.7 0.7)
					(thickness 0.15)
				)
				(justify right top)
			)
		)
		(property "Datasheet" "https://www.bourns.com/docs/product-datasheets/cr.pdf"
			(at 0 0 90)
			(layer "F.Fab")
			(hide yes)
			(effects
				(font
					(size 1.27 1.27)
					(thickness 0.15)
				)
			)
		)
		(property "Description" "SMD Chip Resistor, 10 kohm, ± 1%, 100 mW, 0603 [1608 Metric], Thick Film, General Purpose"
			(at 0 0 90)
			(layer "F.Fab")
			(hide yes)
			(effects
				(font
					(size 1.27 1.27)
					(thickness 0.15)
				)
			)
		)
		(property "Author" "Antmicro"
			(at 66.88 250.18 0)
			(layer "F.Fab")
			(hide yes)
			(effects
				(font
					(size 1 1)
					(thickness 0.15)
				)
			)
		)
		(property "License" "Apache-2.0"
			(at 66.88 250.18 0)
			(layer "F.Fab")
			(hide yes)
			(effects
				(font
					(size 1 1)
					(thickness 0.15)
				)
			)
		)
		(property "MPN" "CR0603-FX-1002ELF"
			(at 66.88 250.18 0)
			(layer "F.Fab")
			(hide yes)
			(effects
				(font
					(size 1 1)
					(thickness 0.15)
				)
			)
		)
		(property "Manufacturer" "Bourns"
			(at 66.88 250.18 0)
			(layer "F.Fab")
			(hide yes)
			(effects
				(font
					(size 1 1)
					(thickness 0.15)
				)
			)
		)
		(property "Tolerance" "1%"
			(at 66.88 250.18 0)
			(layer "F.Fab")
			(hide yes)
			(effects
				(font
					(size 1 1)
					(thickness 0.15)
				)
			)
		)
		(property "Val" "10k"
			(at 66.88 250.18 0)
			(layer "F.Fab")
			(hide yes)
			(effects
				(font
					(size 1 1)
					(thickness 0.15)
				)
			)
		)
		(sheetname "/Peripherals/")
		(sheetfile "peripherals.kicad_sch")
		(attr smd)
		(fp_line
			(start -0.15 0.4)
			(end 0.15 0.4)
			(stroke
				(width 0.15)
				(type solid)
			)
			(layer "F.SilkS")
		)
		(fp_line
			(start -0.15 -0.4)
			(end 0.15 -0.4)
			(stroke
				(width 0.15)
				(type solid)
			)
			(layer "F.SilkS")
		)
		(fp_rect
			(start -1.25 -0.65)
			(end 1.25 0.65)
			(stroke
				(width 0.05)
				(type solid)
			)
			(fill no)
			(layer "F.CrtYd")
		)
		(fp_rect
			(start -0.8 -0.4)
			(end 0.8 0.4)
			(stroke
				(width 0.15)
				(type solid)
			)
			(fill no)
			(layer "F.Fab")
		)
		(fp_text user "Author: Antmicro"
			(at -1.25 4.9 270)
			(layer "F.Fab")
			(effects
				(font
					(size 0.7 0.7)
					(thickness 0.15)
				)
				(justify left bottom)
			)
		)
		(fp_text user "License: Apache-2.0"
			(at -1.25 5.9 270)
			(layer "F.Fab")
			(effects
				(font
					(size 0.7 0.7)
					(thickness 0.15)
				)
				(justify left bottom)
			)
		)
		(fp_text user "${REFERENCE}"
			(at -1.25 3.898 270)
			(layer "F.Fab")
			(effects
				(font
					(size 0.7 0.7)
					(thickness 0.15)
				)
				(justify left bottom)
			)
		)
		(pad "1" smd roundrect
			(at -0.7 0 270)
			(size 0.8 1)
			(layers "F.Cu" "F.Mask" "F.Paste")
			(roundrect_rratio 0.2)
			(net 2 "+3V3")
			(pintype "passive")
		)
		(pad "2" smd roundrect
			(at 0.7 0 270)
			(size 0.8 1)
			(layers "F.Cu" "F.Mask" "F.Paste")
			(roundrect_rratio 0.2)
			(net 351 "Net-(U13-~{FAULT})")
			(pintype "passive")
		)
	)
	(footprint "antmicro-footprints:USB-C_Receptacle_GCT_USB4105-GF-A"
		(layer "F.Cu")
		(at 154.03 59.002 180)
		(property "Reference" "J1"
			(at 0.45 -5.138 0)
			(layer "F.SilkS")
			(effects
				(font
					(size 0.65 0.65)
					(thickness 0.15)
				)
				(justify right bottom)
			)
		)
		(property "Value" "USB-C_USB4105-GF-A"
			(at 0 5 0)
			(layer "F.Fab")
			(hide yes)
			(effects
				(font
					(size 0.7 0.7)
					(thickness 0.15)
				)
				(justify right bottom)
			)
		)
		(property "Datasheet" "https://gct.co/files/drawings/usb4105.pdf"
			(at 0 0 180)
			(layer "F.Fab")
			(hide yes)
			(effects
				(font
					(size 1.27 1.27)
					(thickness 0.15)
				)
			)
		)
		(property "Description" "USB-C (USB TYPE-C) USB 2.0 Receptacle Connector 24 (16+8 Dummy) Position Surface Mount, Right Angle"
			(at 0 0 180)
			(layer "F.Fab")
			(hide yes)
			(effects
				(font
					(size 1.27 1.27)
					(thickness 0.15)
				)
			)
		)
		(property "Author" "Antmicro"
			(at 308.06 118.004 0)
			(layer "F.Fab")
			(hide yes)
			(effects
				(font
					(size 1 1)
					(thickness 0.15)
				)
			)
		)
		(property "License" "Apache-2.0"
			(at 308.06 118.004 0)
			(layer "F.Fab")
			(hide yes)
			(effects
				(font
					(size 1 1)
					(thickness 0.15)
				)
			)
		)
		(property "MPN" "USB4105-GF-A"
			(at 308.06 118.004 0)
			(layer "F.Fab")
			(hide yes)
			(effects
				(font
					(size 1 1)
					(thickness 0.15)
				)
			)
		)
		(property "Manufacturer" "GCT"
			(at 308.06 118.004 0)
			(layer "F.Fab")
			(hide yes)
			(effects
				(font
					(size 1 1)
					(thickness 0.15)
				)
			)
		)
		(sheetname "/Peripherals/")
		(sheetfile "peripherals.kicad_sch")
		(attr smd)
		(fp_line
			(start 4.788 3.854)
			(end 4.788 2.575)
			(stroke
				(width 0.15)
				(type solid)
			)
			(layer "F.SilkS")
		)
		(fp_line
			(start 4.788 -1.395)
			(end 4.788 -0.145)
			(stroke
				(width 0.15)
				(type solid)
			)
			(layer "F.SilkS")
		)
		(fp_line
			(start -4.79 3.854)
			(end 4.788 3.854)
			(stroke
				(width 0.15)
				(type solid)
			)
			(layer "F.SilkS")
		)
		(fp_line
			(start -4.79 2.575)
			(end -4.79 3.854)
			(stroke
				(width 0.15)
				(type solid)
			)
			(layer "F.SilkS")
		)
		(fp_line
			(start -4.79 -1.395)
			(end -4.79 -0.145)
			(stroke
				(width 0.15)
				(type solid)
			)
			(layer "F.SilkS")
		)
		(fp_circle
			(center -3.8 -4.27071)
			(end -3.75 -4.22071)
			(stroke
				(width 0.15)
				(type solid)
			)
			(fill yes)
			(layer "F.SilkS")
		)
		(fp_rect
			(start -5.1 -4.4)
			(end 5.1 3.9)
			(stroke
				(width 0.05)
				(type solid)
			)
			(fill no)
			(layer "F.CrtYd")
		)
		(fp_line
			(start 4.788 3.854)
			(end -4.79 3.854)
			(stroke
				(width 0.15)
				(type solid)
			)
			(layer "F.Fab")
		)
		(fp_line
			(start 4.788 -3.676)
			(end 4.788 3.854)
			(stroke
				(width 0.15)
				(type solid)
			)
			(layer "F.Fab")
		)
		(fp_line
			(start -4.702 3.854)
			(end 4.788 3.854)
			(stroke
				(width 0.15)
				(type solid)
			)
			(layer "F.Fab")
		)
		(fp_line
			(start -4.79 3.854)
			(end -4.79 -3.676)
			(stroke
				(width 0.15)
				(type solid)
			)
			(layer "F.Fab")
		)
		(fp_line
			(start -4.79 -3.676)
			(end 4.788 -3.676)
			(stroke
				(width 0.15)
				(type solid)
			)
			(layer "F.Fab")
		)
		(fp_text user "License: Apache-2.0"
			(at -4.79 8.855 180)
			(layer "F.Fab")
			(effects
				(font
					(size 0.7 0.7)
					(thickness 0.15)
				)
				(justify left bottom)
			)
		)
		(fp_text user "Author: Antmicro"
			(at -4.79 7.853 180)
			(layer "F.Fab")
			(effects
				(font
					(size 0.7 0.7)
					(thickness 0.15)
				)
				(justify left bottom)
			)
		)
		(fp_text user "${REFERENCE}"
			(at -4.79 6.853 180)
			(layer "F.Fab")
			(effects
				(font
					(size 0.7 0.7)
					(thickness 0.15)
				)
				(justify left bottom)
			)
		)
		(fp_text user "PCB-EDGE"
			(at -4.79 5.853 180)
			(layer "F.Fab")
			(effects
				(font
					(size 0.7 0.7)
					(thickness 0.15)
				)
				(justify left bottom)
			)
		)
		(pad "" np_thru_hole circle
			(at -2.891 -2.426 180)
			(size 0.65 0.65)
			(drill 0.65)
			(layers "*.Cu" "*.Mask")
		)
		(pad "" np_thru_hole circle
			(at 2.89 -2.426 180)
			(size 0.65 0.65)
			(drill 0.65)
			(layers "*.Cu" "*.Mask")
		)
		(pad "A1" smd roundrect
			(at -3.202 -3.5 180)
			(size 0.6 1.15)
			(layers "F.Cu" "F.Mask" "F.Paste")
			(roundrect_rratio 0.25)
			(net 1 "GND")
			(pinfunction "GND")
			(pintype "power_in")
		)
		(pad "A4" smd roundrect
			(at -2.4 -3.5 180)
			(size 0.6 1.15)
			(layers "F.Cu" "F.Mask" "F.Paste")
			(roundrect_rratio 0.25)
			(net 325 "USB_POWER_IN")
			(pinfunction "VBUS")
			(pintype "power_in")
		)
		(pad "A5" smd roundrect
			(at -1.25 -3.5 180)
			(size 0.3 1.15)
			(layers "F.Cu" "F.Mask" "F.Paste")
			(roundrect_rratio 0.25)
			(net 311 "Net-(J1-CC_{1})")
			(pinfunction "CC_{1}")
			(pintype "bidirectional")
		)
		(pad "A6" smd roundrect
			(at -0.25 -3.5 180)
			(size 0.3 1.15)
			(layers "F.Cu" "F.Mask" "F.Paste")
			(roundrect_rratio 0.25)
			(net 359 "/Peripherals/USB_DP")
			(pinfunction "D_{A}+")
			(pintype "bidirectional")
		)
		(pad "A7" smd roundrect
			(at 0.248 -3.5 180)
			(size 0.3 1.15)
			(layers "F.Cu" "F.Mask" "F.Paste")
			(roundrect_rratio 0.25)
			(net 360 "/Peripherals/USB_DN")
			(pinfunction "D_{A}-")
			(pintype "bidirectional")
		)
		(pad "A8" smd roundrect
			(at 1.249 -3.5 180)
			(size 0.3 1.15)
			(layers "F.Cu" "F.Mask" "F.Paste")
			(roundrect_rratio 0.25)
			(net 297 "unconnected-(J1-SBU_{1}-PadA8)")
			(pinfunction "SBU_{1}")
			(pintype "bidirectional+no_connect")
		)
		(pad "A9" smd roundrect
			(at 2.398 -3.5 180)
			(size 0.6 1.15)
			(layers "F.Cu" "F.Mask" "F.Paste")
			(roundrect_rratio 0.25)
			(net 325 "USB_POWER_IN")
			(pinfunction "VBUS")
			(pintype "passive")
		)
		(pad "A12" smd roundrect
			(at 3.2 -3.5 180)
			(size 0.6 1.15)
			(layers "F.Cu" "F.Mask" "F.Paste")
			(roundrect_rratio 0.25)
			(net 1 "GND")
			(pinfunction "GND")
			(pintype "passive")
		)
		(pad "B1" smd roundrect
			(at 3.2 -3.5 180)
			(size 0.6 1.15)
			(layers "F.Cu" "F.Mask" "F.Paste")
			(roundrect_rratio 0.25)
			(net 1 "GND")
			(pinfunction "GND")
			(pintype "passive")
		)
		(pad "B4" smd roundrect
			(at 2.398 -3.5 180)
			(size 0.6 1.15)
			(layers "F.Cu" "F.Mask" "F.Paste")
			(roundrect_rratio 0.25)
			(net 325 "USB_POWER_IN")
			(pinfunction "VBUS")
			(pintype "passive")
		)
		(pad "B5" smd roundrect
			(at 1.749 -3.5 180)
			(size 0.3 1.15)
			(layers "F.Cu" "F.Mask" "F.Paste")
			(roundrect_rratio 0.25)
			(net 350 "Net-(J1-CC_{2})")
			(pinfunction "CC_{2}")
			(pintype "bidirectional")
		)
		(pad "B6" smd roundrect
			(at 0.748 -3.5 180)
			(size 0.3 1.15)
			(layers "F.Cu" "F.Mask" "F.Paste")
			(roundrect_rratio 0.25)
			(net 359 "/Peripherals/USB_DP")
			(pinfunction "D_{B}+")
			(pintype "bidirectional")
		)
		(pad "B7" smd roundrect
			(at -0.75 -3.5 180)
			(size 0.3 1.15)
			(layers "F.Cu" "F.Mask" "F.Paste")
			(roundrect_rratio 0.25)
			(net 360 "/Peripherals/USB_DN")
			(pinfunction "D_{B}-")
			(pintype "bidirectional")
		)
		(pad "B8" smd roundrect
			(at -1.75 -3.5 180)
			(size 0.3 1.15)
			(layers "F.Cu" "F.Mask" "F.Paste")
			(roundrect_rratio 0.25)
			(net 352 "unconnected-(J1-SBU_{2}-PadB8)")
			(pinfunction "SBU_{2}")
			(pintype "bidirectional+no_connect")
		)
		(pad "B9" smd roundrect
			(at -2.4 -3.5 180)
			(size 0.6 1.15)
			(layers "F.Cu" "F.Mask" "F.Paste")
			(roundrect_rratio 0.25)
			(net 325 "USB_POWER_IN")
			(pinfunction "VBUS")
			(pintype "passive")
		)
		(pad "B12" smd roundrect
			(at -3.202 -3.5 180)
			(size 0.6 1.15)
			(layers "F.Cu" "F.Mask" "F.Paste")
			(roundrect_rratio 0.25)
			(net 1 "GND")
			(pinfunction "GND")
			(pintype "passive")
		)
		(pad "SH" thru_hole oval
			(at -4.321 -2.926 180)
			(size 1.05 2.1)
			(drill oval 0.6 1.7)
			(layers "*.Cu" "*.Mask")
			(remove_unused_layers no)
			(net 1 "GND")
			(pinfunction "SH")
			(pintype "passive")
		)
		(pad "SH" thru_hole oval
			(at -4.321 1.255 180)
			(size 1 2)
			(drill oval 0.6 1.4)
			(layers "*.Cu" "*.Mask")
			(remove_unused_layers no)
			(net 1 "GND")
			(pinfunction "SH")
			(pintype "passive")
		)
		(pad "SH" thru_hole oval
			(at 4.32 -2.926 180)
			(size 1.05 2.1)
			(drill oval 0.6 1.7)
			(layers "*.Cu" "*.Mask")
			(remove_unused_layers no)
			(net 1 "GND")
			(pinfunction "SH")
			(pintype "passive")
		)
		(pad "SH" thru_hole oval
			(at 4.32 1.255 180)
			(size 1 2)
			(drill oval 0.6 1.4)
			(layers "*.Cu" "*.Mask")
			(remove_unused_layers no)
			(net 1 "GND")
			(pinfunction "SH")
			(pintype "passive")
		)
	)
	(footprint "antmicro-footprints:C_0402_1005Metric"
		(layer "F.Cu")
		(at 100.97 86.46 90)
		(descr "Capacitor SMD 0402")
		(tags "capacitor SMD 0402")
		(property "Reference" "C51"
			(at -3.08 0.36 90)
			(layer "F.SilkS")
			(effects
				(font
					(size 0.65 0.65)
					(thickness 0.15)
				)
				(justify left bottom)
			)
		)
		(property "Value" "C_33p_0402"
			(at 0 1.4 90)
			(layer "F.Fab")
			(hide yes)
			(effects
				(font
					(size 0.7 0.7)
					(thickness 0.15)
				)
				(justify left bottom)
			)
		)
		(property "Datasheet" "https://spicat.kyocera-avx.com/product/mlcc/chartview/04025A330FAT2A/"
			(at 0 0 90)
			(layer "F.Fab")
			(hide yes)
			(effects
				(font
					(size 1.27 1.27)
					(thickness 0.15)
				)
			)
		)
		(property "Description" "SMD Multilayer Ceramic Capacitor, 33 pF, 50 V, 0402 [1005 Metric], ± 5%, C0G / NP0, MC"
			(at 0 0 90)
			(layer "F.Fab")
			(hide yes)
			(effects
				(font
					(size 1.27 1.27)
					(thickness 0.15)
				)
			)
		)
		(property "Author" "Antmicro"
			(at 187.43 -14.51 0)
			(layer "F.Fab")
			(hide yes)
			(effects
				(font
					(size 1 1)
					(thickness 0.15)
				)
			)
		)
		(property "Dielectric" ""
			(at 187.43 -14.51 0)
			(layer "F.Fab")
			(hide yes)
			(effects
				(font
					(size 1 1)
					(thickness 0.15)
				)
			)
		)
		(property "License" "Apache-2.0"
			(at 187.43 -14.51 0)
			(layer "F.Fab")
			(hide yes)
			(effects
				(font
					(size 1 1)
					(thickness 0.15)
				)
			)
		)
		(property "MPN" "04025A330FAT2A"
			(at 187.43 -14.51 0)
			(layer "F.Fab")
			(hide yes)
			(effects
				(font
					(size 1 1)
					(thickness 0.15)
				)
			)
		)
		(property "Manufacturer" "KYOCERA AVX"
			(at 187.43 -14.51 0)
			(layer "F.Fab")
			(hide yes)
			(effects
				(font
					(size 1 1)
					(thickness 0.15)
				)
			)
		)
		(property "Val" "33p"
			(at 187.43 -14.51 0)
			(layer "F.Fab")
			(hide yes)
			(effects
				(font
					(size 1 1)
					(thickness 0.15)
				)
			)
		)
		(property "Voltage" ""
			(at 187.43 -14.51 0)
			(layer "F.Fab")
			(hide yes)
			(effects
				(font
					(size 1 1)
					(thickness 0.15)
				)
			)
		)
		(sheetname "/SDI/")
		(sheetfile "sdi.kicad_sch")
		(attr smd)
		(fp_rect
			(start -0.925 -0.47)
			(end 0.925 0.47)
			(stroke
				(width 0.05)
				(type default)
			)
			(fill no)
			(layer "F.CrtYd")
		)
		(fp_line
			(start 0.504 -0.25)
			(end 0.504 0.248)
			(stroke
				(width 0.15)
				(type solid)
			)
			(layer "F.Fab")
		)
		(fp_line
			(start -0.494 -0.25)
			(end 0.504 -0.25)
			(stroke
				(width 0.15)
				(type solid)
			)
			(layer "F.Fab")
		)
		(fp_line
			(start 0.504 0.248)
			(end -0.494 0.248)
			(stroke
				(width 0.15)
				(type solid)
			)
			(layer "F.Fab")
		)
		(fp_line
			(start -0.494 0.248)
			(end -0.494 -0.25)
			(stroke
				(width 0.15)
				(type solid)
			)
			(layer "F.Fab")
		)
		(fp_text user "License: Apache-2.0"
			(at -0.939 5.799 90)
			(layer "F.Fab")
			(effects
				(font
					(size 0.7 0.7)
					(thickness 0.15)
				)
				(justify left bottom)
			)
		)
		(fp_text user "${REFERENCE}"
			(at -0.939 4.599 90)
			(layer "F.Fab")
			(effects
				(font
					(size 0.7 0.7)
					(thickness 0.15)
				)
				(justify left bottom)
			)
		)
		(fp_text user "Author: Antmicro"
			(at -0.939 3.399 90)
			(layer "F.Fab")
			(effects
				(font
					(size 0.7 0.7)
					(thickness 0.15)
				)
				(justify left bottom)
			)
		)
		(pad "1" smd roundrect
			(at -0.48 0 90)
			(size 0.59 0.64)
			(layers "F.Cu" "F.Mask" "F.Paste")
			(roundrect_rratio 0.25)
			(net 46 "/SDI/XTAL2")
			(pintype "passive")
		)
		(pad "2" smd roundrect
			(at 0.48 0 90)
			(size 0.59 0.64)
			(layers "F.Cu" "F.Mask" "F.Paste")
			(roundrect_rratio 0.25)
			(net 1 "GND")
			(pintype "passive")
		)
	)
	(footprint "antmicro-footprints:BGA-256_14x14mm_Layout16x16_P0.8mm"
		(locked yes)
		(layer "F.Cu")
		(at 126.3 90.3 180)
		(property "Reference" "U11"
			(at 0 -8 180)
			(layer "F.SilkS")
			(effects
				(font
					(size 0.7 0.7)
					(thickness 0.15)
				)
				(justify left bottom)
			)
		)
		(property "Value" "LIFCL-40-9BG256C"
			(at -8 8.55 180)
			(layer "F.Fab")
			(effects
				(font
					(size 0.7 0.7)
					(thickness 0.15)
				)
				(justify left bottom)
			)
		)
		(property "Datasheet" "https://www.latticesemi.com/-/media/LatticeSemi/Documents/DataSheets/CrossLink/FPGA-DS-02007-2-1-CrossLink-Family-Data-Sheet.ashx?document_id=51662"
			(at 0 0 180)
			(layer "F.Fab")
			(hide yes)
			(effects
				(font
					(size 1.27 1.27)
					(thickness 0.15)
				)
			)
		)
		(property "Description" "CrossLink-NX™ Field Programmable Gate Array 256-LFBGA"
			(at 0 0 180)
			(layer "F.Fab")
			(hide yes)
			(effects
				(font
					(size 1.27 1.27)
					(thickness 0.15)
				)
			)
		)
		(property "Author" "Antmicro"
			(at 252.6 180.6 0)
			(layer "F.Fab")
			(hide yes)
			(effects
				(font
					(size 1 1)
					(thickness 0.15)
				)
			)
		)
		(property "License" "Apache-2.0"
			(at 252.6 180.6 0)
			(layer "F.Fab")
			(hide yes)
			(effects
				(font
					(size 1 1)
					(thickness 0.15)
				)
			)
		)
		(property "MPN" "LIFCL-40-9BG256C"
			(at 252.6 180.6 0)
			(layer "F.Fab")
			(hide yes)
			(effects
				(font
					(size 1 1)
					(thickness 0.15)
				)
			)
		)
		(property "Manufacturer" "Lattice Semiconductor"
			(at 252.6 180.6 0)
			(layer "F.Fab")
			(hide yes)
			(effects
				(font
					(size 1 1)
					(thickness 0.15)
				)
			)
		)
		(sheetname "/DDR3/")
		(sheetfile "ddr3.kicad_sch")
		(attr smd)
		(fp_line
			(start 7.118 7.118)
			(end 7.118 3.62)
			(stroke
				(width 0.15)
				(type solid)
			)
			(layer "F.SilkS")
		)
		(fp_line
			(start 7.118 -7.12)
			(end 7.118 -3.621)
			(stroke
				(width 0.15)
				(type solid)
			)
			(layer "F.SilkS")
		)
		(fp_line
			(start 7.118 -7.12)
			(end 7.118 -3.621)
			(stroke
				(width 0.15)
				(type solid)
			)
			(layer "F.SilkS")
		)
		(fp_line
			(start 7.118 -7.12)
			(end 7.118 -3.621)
			(stroke
				(width 0.15)
				(type solid)
			)
			(layer "F.SilkS")
		)
		(fp_line
			(start 3.62 7.118)
			(end 7.118 7.118)
			(stroke
				(width 0.15)
				(type solid)
			)
			(layer "F.SilkS")
		)
		(fp_line
			(start 3.62 -7.12)
			(end 7.118 -7.12)
			(stroke
				(width 0.15)
				(type solid)
			)
			(layer "F.SilkS")
		)
		(fp_line
			(start 3.62 -7.12)
			(end 7.118 -7.12)
			(stroke
				(width 0.15)
				(type solid)
			)
			(layer "F.SilkS")
		)
		(fp_line
			(start 3.62 -7.12)
			(end 7.118 -7.12)
			(stroke
				(width 0.15)
				(type solid)
			)
			(layer "F.SilkS")
		)
		(fp_line
			(start -3.621 7.118)
			(end -7.12 7.118)
			(stroke
				(width 0.15)
				(type solid)
			)
			(layer "F.SilkS")
		)
		(fp_line
			(start -3.621 -7.12)
			(end -6 -7.12)
			(stroke
				(width 0.15)
				(type solid)
			)
			(layer "F.SilkS")
		)
		(fp_line
			(start -6 -7.12)
			(end -7.12 -6)
			(stroke
				(width 0.15)
				(type solid)
			)
			(layer "F.SilkS")
		)
		(fp_line
			(start -7.12 7.118)
			(end -7.12 3.62)
			(stroke
				(width 0.15)
				(type solid)
			)
			(layer "F.SilkS")
		)
		(fp_line
			(start -7.12 -6)
			(end -7.12 -3.621)
			(stroke
				(width 0.15)
				(type solid)
			)
			(layer "F.SilkS")
		)
		(fp_circle
			(center -7.149 -7.15)
			(end -7.1 -7.15)
			(stroke
				(width 0.15)
				(type solid)
			)
			(fill yes)
			(layer "F.SilkS")
		)
		(fp_rect
			(start -7.5 -7.5)
			(end 7.49 7.49)
			(stroke
				(width 0.05)
				(type solid)
			)
			(fill no)
			(layer "F.CrtYd")
		)
		(fp_line
			(start 6.998 6.998)
			(end 6.998 -7)
			(stroke
				(width 0.15)
				(type solid)
			)
			(layer "F.Fab")
		)
		(fp_line
			(start 6.998 -7)
			(end -6 -7)
			(stroke
				(width 0.15)
				(type solid)
			)
			(layer "F.Fab")
		)
		(fp_line
			(start -6 -7)
			(end -7 -6)
			(stroke
				(width 0.15)
				(type solid)
			)
			(layer "F.Fab")
		)
		(fp_line
			(start -7 6.998)
			(end 6.998 6.998)
			(stroke
				(width 0.15)
				(type solid)
			)
			(layer "F.Fab")
		)
		(fp_line
			(start -7 -6)
			(end -7 6.998)
			(stroke
				(width 0.15)
				(type solid)
			)
			(layer "F.Fab")
		)
		(fp_text user "Author: Antmicro"
			(at -8 11.749 180)
			(layer "F.Fab")
			(effects
				(font
					(size 0.7 0.7)
					(thickness 0.15)
				)
				(justify left bottom)
			)
		)
		(fp_text user "${REFERENCE}"
			(at 0 0 180)
			(layer "F.Fab")
			(effects
				(font
					(size 1 1)
					(thickness 0.15)
				)
			)
		)
		(fp_text user "${REFERENCE}"
			(at -8 10.55 180)
			(layer "F.Fab")
			(effects
				(font
					(size 0.7 0.7)
					(thickness 0.15)
				)
				(justify left bottom)
			)
		)
		(fp_text user "License: Apache-2.0"
			(at -8 12.95 180)
			(layer "F.Fab")
			(effects
				(font
					(size 0.7 0.7)
					(thickness 0.15)
				)
				(justify left bottom)
			)
		)
		(pad "A1" smd circle
			(at -6 -6 180)
			(size 0.45 0.45)
			(layers "F.Cu" "F.Mask" "F.Paste")
			(net 1 "GND")
			(pinfunction "VSSADPHY")
			(pintype "power_in")
		)
		(pad "A2" smd circle
			(at -5.2 -6 180)
			(size 0.45 0.45)
			(layers "F.Cu" "F.Mask" "F.Paste")
			(net 13 "/FPGA Power/VCC_PLLDPHY")
			(pinfunction "VCCPLLDPHY0")
			(pintype "power_in")
		)
		(pad "A3" smd circle
			(at -4.4 -6 180)
			(size 0.45 0.45)
			(layers "F.Cu" "F.Mask" "F.Paste")
			(net 116 "/Peripherals/MIPI1_D2_P")
			(pinfunction "DPHY1_D2+")
			(pintype "bidirectional")
		)
		(pad "A4" smd circle
			(at -3.6 -6 180)
			(size 0.45 0.45)
			(layers "F.Cu" "F.Mask" "F.Paste")
			(net 112 "/Peripherals/MIPI1_D0_P")
			(pinfunction "DPHY1_D0+")
			(pintype "bidirectional")
		)
		(pad "A5" smd circle
			(at -2.8 -6 180)
			(size 0.45 0.45)
			(layers "F.Cu" "F.Mask" "F.Paste")
			(net 110 "/Peripherals/MIPI1_CLK_P")
			(pinfunction "DPHY1_CK+")
			(pintype "bidirectional")
		)
		(pad "A6" smd circle
			(at -2 -6 180)
			(size 0.45 0.45)
			(layers "F.Cu" "F.Mask" "F.Paste")
			(net 114 "/Peripherals/MIPI1_D1_P")
			(pinfunction "DPHY1_D1+")
			(pintype "bidirectional")
		)
		(pad "A7" smd circle
			(at -1.2 -6 180)
			(size 0.45 0.45)
			(layers "F.Cu" "F.Mask" "F.Paste")
			(net 118 "/Peripherals/MIPI1_D3_P")
			(pinfunction "DPHY1_D3+")
			(pintype "bidirectional")
		)
		(pad "A8" smd circle
			(at -0.4 -6 180)
			(size 0.45 0.45)
			(layers "F.Cu" "F.Mask" "F.Paste")
			(net 1 "GND")
			(pinfunction "VSSADPHY")
			(pintype "passive")
		)
		(pad "A9" smd circle
			(at 0.4 -6 180)
			(size 0.45 0.45)
			(layers "F.Cu" "F.Mask" "F.Paste")
			(net 1 "GND")
			(pinfunction "SD_REFCLK+")
			(pintype "bidirectional")
		)
		(pad "A10" smd circle
			(at 1.2 -6 180)
			(size 0.45 0.45)
			(layers "F.Cu" "F.Mask" "F.Paste")
			(net 1 "GND")
			(pinfunction "VSSSD")
			(pintype "power_in")
		)
		(pad "A11" smd circle
			(at 2 -6 180)
			(size 0.45 0.45)
			(layers "F.Cu" "F.Mask" "F.Paste")
			(net 383 "unconnected-(U11L-SD0_TXD--PadA11)")
			(pinfunction "SD0_TXD-")
			(pintype "output+no_connect")
		)
		(pad "A12" smd circle
			(at 2.8 -6 180)
			(size 0.45 0.45)
			(layers "F.Cu" "F.Mask" "F.Paste")
			(net 384 "unconnected-(U11L-SD0_TXD+-PadA12)")
			(pinfunction "SD0_TXD+")
			(pintype "output+no_connect")
		)
		(pad "A13" smd circle
			(at 3.6 -6 180)
			(size 0.45 0.45)
			(layers "F.Cu" "F.Mask" "F.Paste")
			(net 1 "GND")
			(pinfunction "VSSSD")
			(pintype "passive")
		)
		(pad "A14" smd circle
			(at 4.4 -6 180)
			(size 0.45 0.45)
			(layers "F.Cu" "F.Mask" "F.Paste")
			(net 1 "GND")
			(pinfunction "SD0_RXD-")
			(pintype "input")
		)
		(pad "A15" smd circle
			(at 5.2 -6 180)
			(size 0.45 0.45)
			(layers "F.Cu" "F.Mask" "F.Paste")
			(net 1 "GND")
			(pinfunction "SD0_RXD+")
			(pintype "input")
		)
		(pad "A16" smd circle
			(at 6 -6 180)
			(size 0.45 0.45)
			(layers "F.Cu" "F.Mask" "F.Paste")
			(net 1 "GND")
			(pinfunction "VSSSD")
			(pintype "passive")
		)
		(pad "B1" smd circle
			(at -6 -5.2 180)
			(size 0.45 0.45)
			(layers "F.Cu" "F.Mask" "F.Paste")
			(net 69 "/Peripherals/MIPI0_D3_P")
			(pinfunction "DPHY0_D3+")
			(pintype "bidirectional")
		)
		(pad "B2" smd circle
			(at -5.2 -5.2 180)
			(size 0.45 0.45)
			(layers "F.Cu" "F.Mask" "F.Paste")
			(net 68 "/Peripherals/MIPI0_D3_N")
			(pinfunction "DPHY0_D3-")
			(pintype "bidirectional")
		)
		(pad "B3" smd circle
			(at -4.4 -5.2 180)
			(size 0.45 0.45)
			(layers "F.Cu" "F.Mask" "F.Paste")
			(net 117 "/Peripherals/MIPI1_D2_N")
			(pinfunction "DPHY1_D2-")
			(pintype "bidirectional")
		)
		(pad "B4" smd circle
			(at -3.6 -5.2 180)
			(size 0.45 0.45)
			(layers "F.Cu" "F.Mask" "F.Paste")
			(net 113 "/Peripherals/MIPI1_D0_N")
			(pinfunction "DPHY1_D0-")
			(pintype "bidirectional")
		)
		(pad "B5" smd circle
			(at -2.8 -5.2 180)
			(size 0.45 0.45)
			(layers "F.Cu" "F.Mask" "F.Paste")
			(net 111 "/Peripherals/MIPI1_CLK_N")
			(pinfunction "DPHY1_CK-")
			(pintype "bidirectional")
		)
		(pad "B6" smd circle
			(at -2 -5.2 180)
			(size 0.45 0.45)
			(layers "F.Cu" "F.Mask" "F.Paste")
			(net 115 "/Peripherals/MIPI1_D1_N")
			(pinfunction "DPHY1_D1-")
			(pintype "bidirectional")
		)
		(pad "B7" smd circle
			(at -1.2 -5.2 180)
			(size 0.45 0.45)
			(layers "F.Cu" "F.Mask" "F.Paste")
			(net 119 "/Peripherals/MIPI1_D3_N")
			(pinfunction "DPHY1_D3-")
			(pintype "bidirectional")
		)
		(pad "B8" smd circle
			(at -0.4 -5.2 180)
			(size 0.45 0.45)
			(layers "F.Cu" "F.Mask" "F.Paste")
			(net 1 "GND")
			(pinfunction "VSSADPHY")
			(pintype "passive")
		)
		(pad "B9" smd circle
			(at 0.4 -5.2 180)
			(size 0.45 0.45)
			(layers "F.Cu" "F.Mask" "F.Paste")
			(net 1 "GND")
			(pinfunction "SD_REFCLK-")
			(pintype "bidirectional")
		)
		(pad "B10" smd circle
			(at 1.2 -5.2 180)
			(size 0.45 0.45)
			(layers "F.Cu" "F.Mask" "F.Paste")
			(net 1 "GND")
			(pinfunction "VSSSD")
			(pintype "passive")
		)
		(pad "B11" smd circle
			(at 2 -5.2 180)
			(size 0.45 0.45)
			(layers "F.Cu" "F.Mask" "F.Paste")
			(net 385 "unconnected-(U11M-VCCAUXSD-PadB11)")
			(pinfunction "VCCAUXSD")
			(pintype "power_in+no_connect")
		)
		(pad "B12" smd circle
			(at 2.8 -5.2 180)
			(size 0.45 0.45)
			(layers "F.Cu" "F.Mask" "F.Paste")
			(net 386 "unconnected-(U11L-SD0_REFRET-PadB12)")
			(pinfunction "SD0_REFRET")
			(pintype "input+no_connect")
		)
		(pad "B13" smd circle
			(at 3.6 -5.2 180)
			(size 0.45 0.45)
			(layers "F.Cu" "F.Mask" "F.Paste")
			(net 387 "unconnected-(U11M-VCCPLLSD0-PadB13)")
			(pinfunction "VCCPLLSD0")
			(pintype "power_in+no_connect")
		)
		(pad "B14" smd circle
			(at 4.4 -5.2 180)
			(size 0.45 0.45)
			(layers "F.Cu" "F.Mask" "F.Paste")
			(net 1 "GND")
			(pinfunction "VSSSD")
			(pintype "passive")
		)
		(pad "B15" smd circle
			(at 5.2 -5.2 180)
			(size 0.45 0.45)
			(layers "F.Cu" "F.Mask" "F.Paste")
			(net 388 "unconnected-(U11M-VCCSD0-PadB15)")
			(pinfunction "VCCSD0")
			(pintype "power_in+no_connect")
		)
		(pad "B16" smd circle
			(at 6 -5.2 180)
			(size 0.45 0.45)
			(layers "F.Cu" "F.Mask" "F.Paste")
			(net 40 "/FPGA/DONE")
			(pinfunction "PT76B/DONE\n")
			(pintype "bidirectional")
		)
		(pad "C1" smd circle
			(at -6 -4.4 180)
			(size 0.45 0.45)
			(layers "F.Cu" "F.Mask" "F.Paste")
			(net 73 "/Peripherals/MIPI0_D1_P")
			(pinfunction "DPHY0_D1+")
			(pintype "bidirectional")
		)
		(pad "C2" smd circle
			(at -5.2 -4.4 180)
			(size 0.45 0.45)
			(layers "F.Cu" "F.Mask" "F.Paste")
			(net 72 "/Peripherals/MIPI0_D1_N")
			(pinfunction "DPHY0_D1-")
			(pintype "bidirectional")
		)
		(pad "C3" smd circle
			(at -4.4 -4.4 180)
			(size 0.45 0.45)
			(layers "F.Cu" "F.Mask" "F.Paste")
			(net 1 "GND")
			(pinfunction "VSSADPHY")
			(pintype "passive")
		)
		(pad "C4" smd circle
			(at -3.6 -4.4 180)
			(size 0.45 0.45)
			(layers "F.Cu" "F.Mask" "F.Paste")
			(net 11 "/FPGA Power/VCC_DPHY")
			(pinfunction "VCCDPHY0")
			(pintype "power_in")
		)
		(pad "C5" smd circle
			(at -2.8 -4.4 180)
			(size 0.45 0.45)
			(layers "F.Cu" "F.Mask" "F.Paste")
			(net 13 "/FPGA Power/VCC_PLLDPHY")
			(pinfunction "VCCPLLDPHY1")
			(pintype "power_in")
		)
		(pad "C6" smd circle
			(at -2 -4.4 180)
			(size 0.45 0.45)
			(layers "F.Cu" "F.Mask" "F.Paste")
			(net 1 "GND")
			(pinfunction "VSSADPHY")
			(pintype "passive")
		)
		(pad "C7" smd circle
			(at -1.2 -4.4 180)
			(size 0.45 0.45)
			(layers "F.Cu" "F.Mask" "F.Paste")
			(net 11 "/FPGA Power/VCC_DPHY")
			(pinfunction "VCCDPHY1")
			(pintype "power_in")
		)
		(pad "C8" smd circle
			(at -0.4 -4.4 180)
			(size 0.45 0.45)
			(layers "F.Cu" "F.Mask" "F.Paste")
			(net 12 "/FPGA Power/VCC_ADPHY")
			(pinfunction "VCCADPHY1")
			(pintype "power_in")
		)
		(pad "C9" smd circle
			(at 0.4 -4.4 180)
			(size 0.45 0.45)
			(layers "F.Cu" "F.Mask" "F.Paste")
			(net 1 "GND")
			(pinfunction "VSS")
			(pintype "passive")
		)
		(pad "C10" smd circle
			(at 1.2 -4.4 180)
			(size 0.45 0.45)
			(layers "F.Cu" "F.Mask" "F.Paste")
			(net 1 "GND")
			(pinfunction "VSS")
			(pintype "power_in")
		)
		(pad "C11" smd circle
			(at 2 -4.4 180)
			(size 0.45 0.45)
			(layers "F.Cu" "F.Mask" "F.Paste")
			(net 1 "GND")
			(pinfunction "SD0_REXT")
			(pintype "input")
		)
		(pad "C12" smd circle
			(at 2.8 -4.4 180)
			(size 0.45 0.45)
			(layers "F.Cu" "F.Mask" "F.Paste")
			(net 36 "/FPGA/PROGRAMN")
			(pinfunction "PT74B/PROGRAMN")
			(pintype "bidirectional")
		)
		(pad "C13" smd circle
			(at 3.6 -4.4 180)
			(size 0.45 0.45)
			(layers "F.Cu" "F.Mask" "F.Paste")
			(net 389 "unconnected-(U11A-PT82B{slash}MCSNO{slash}MSDO-PadC13)")
			(pinfunction "PT82B/MCSNO/MSDO")
			(pintype "bidirectional+no_connect")
		)
		(pad "C14" smd circle
			(at 4.4 -4.4 180)
			(size 0.45 0.45)
			(layers "F.Cu" "F.Mask" "F.Paste")
			(net 37 "/FPGA/SPI_DQ0_MOSI")
			(pinfunction "PT78B/MOSI/MD0")
			(pintype "bidirectional")
		)
		(pad "C15" smd circle
			(at 5.2 -4.4 180)
			(size 0.45 0.45)
			(layers "F.Cu" "F.Mask" "F.Paste")
			(net 41 "/FPGA/~{FLASH_CS}")
			(pinfunction "PT78A/MCSN/PCLKT0_1")
			(pintype "bidirectional")
		)
		(pad "C16" smd circle
			(at 6 -4.4 180)
			(size 0.45 0.45)
			(layers "F.Cu" "F.Mask" "F.Paste")
			(net 39 "/FPGA/SPI_CLK")
			(pinfunction "PT76A/MCLK/PCLKT0_0")
			(pintype "bidirectional")
		)
		(pad "D1" smd circle
			(at -6 -3.6 180)
			(size 0.45 0.45)
			(layers "F.Cu" "F.Mask" "F.Paste")
			(net 77 "/Peripherals/MIPI0_CLK_P")
			(pinfunction "DPHY0_CK+")
			(pintype "bidirectional")
		)
		(pad "D2" smd circle
			(at -5.2 -3.6 180)
			(size 0.45 0.45)
			(layers "F.Cu" "F.Mask" "F.Paste")
			(net 76 "/Peripherals/MIPI0_CLK_N")
			(pinfunction "DPHY0_CK-")
			(pintype "bidirectional")
		)
		(pad "D3" smd circle
			(at -4.4 -3.6 180)
			(size 0.45 0.45)
			(layers "F.Cu" "F.Mask" "F.Paste")
			(net 1 "GND")
			(pinfunction "VSSADPHY")
			(pintype "passive")
		)
		(pad "D4" smd circle
			(at -3.6 -3.6 180)
			(size 0.45 0.45)
			(layers "F.Cu" "F.Mask" "F.Paste")
			(net 175 "/SDI/RESET_TRST")
			(pinfunction "PL3A/ULC_GPLL0T_IN")
			(pintype "bidirectional")
		)
		(pad "D5" smd circle
			(at -2.8 -3.6 180)
			(size 0.45 0.45)
			(layers "F.Cu" "F.Mask" "F.Paste")
			(net 206 "/SDI/SDI_D14")
			(pinfunction "PL3B/ULC_GPLL0C_IN")
			(pintype "bidirectional")
		)
		(pad "D6" smd circle
			(at -2 -3.6 180)
			(size 0.45 0.45)
			(layers "F.Cu" "F.Mask" "F.Paste")
			(net 177 "/SDI/SW_EN")
			(pinfunction "PL4A")
			(pintype "bidirectional")
		)
		(pad "D7" smd circle
			(at -1.2 -3.6 180)
			(size 0.45 0.45)
			(layers "F.Cu" "F.Mask" "F.Paste")
			(net 4 "1V0_Power")
			(pinfunction "VCC")
			(pintype "power_in")
		)
		(pad "D8" smd circle
			(at -0.4 -3.6 180)
			(size 0.45 0.45)
			(layers "F.Cu" "F.Mask" "F.Paste")
			(net 1 "GND")
			(pinfunction "VSS")
			(pintype "passive")
		)
		(pad "D9" smd circle
			(at 0.4 -3.6 180)
			(size 0.45 0.45)
			(layers "F.Cu" "F.Mask" "F.Paste")
			(net 4 "1V0_Power")
			(pinfunction "VCC")
			(pintype "passive")
		)
		(pad "D10" smd circle
			(at 1.2 -3.6 180)
			(size 0.45 0.45)
			(layers "F.Cu" "F.Mask" "F.Paste")
			(net 173 "JTAG_EN")
			(pinfunction "JTAG_EN")
			(pintype "input")
		)
		(pad "D11" smd circle
			(at 2 -3.6 180)
			(size 0.45 0.45)
			(layers "F.Cu" "F.Mask" "F.Paste")
			(net 15 "/FPGA/INITN")
			(pinfunction "PT74A/INITN\n")
			(pintype "bidirectional")
		)
		(pad "D12" smd circle
			(at 2.8 -3.6 180)
			(size 0.45 0.45)
			(layers "F.Cu" "F.Mask" "F.Paste")
			(net 27 "/FPGA/SPI_DQ3")
			(pinfunction "PT82A/MD3")
			(pintype "bidirectional")
		)
		(pad "D13" smd circle
			(at 3.6 -3.6 180)
			(size 0.45 0.45)
			(layers "F.Cu" "F.Mask" "F.Paste")
			(net 2 "+3V3")
			(pinfunction "VCCIO0")
			(pintype "power_in")
		)
		(pad "D14" smd circle
			(at 4.4 -3.6 180)
			(size 0.45 0.45)
			(layers "F.Cu" "F.Mask" "F.Paste")
			(net 1 "GND")
			(pinfunction "VSS")
			(pintype "passive")
		)
		(pad "D15" smd circle
			(at 5.2 -3.6 180)
			(size 0.45 0.45)
			(layers "F.Cu" "F.Mask" "F.Paste")
			(net 28 "/FPGA/SPI_DQ2")
			(pinfunction "PT80B/MD2")
			(pintype "bidirectional")
		)
		(pad "D16" smd circle
			(at 6 -3.6 180)
			(size 0.45 0.45)
			(layers "F.Cu" "F.Mask" "F.Paste")
			(net 38 "/FPGA/SPI_DQ1_MISO")
			(pinfunction "PT80A/MISO/MD1")
			(pintype "bidirectional")
		)
		(pad "E1" smd circle
			(at -6 -2.8 180)
			(size 0.45 0.45)
			(layers "F.Cu" "F.Mask" "F.Paste")
			(net 75 "/Peripherals/MIPI0_D0_P")
			(pinfunction "DPHY0_D0+")
			(pintype "bidirectional")
		)
		(pad "E2" smd circle
			(at -5.2 -2.8 180)
			(size 0.45 0.45)
			(layers "F.Cu" "F.Mask" "F.Paste")
			(net 74 "/Peripherals/MIPI0_D0_N")
			(pinfunction "DPHY0_D0-")
			(pintype "bidirectional")
		)
		(pad "E3" smd circle
			(at -4.4 -2.8 180)
			(size 0.45 0.45)
			(layers "F.Cu" "F.Mask" "F.Paste")
			(net 12 "/FPGA Power/VCC_ADPHY")
			(pinfunction "VCCADPHY0")
			(pintype "power_in")
		)
		(pad "E4" smd circle
			(at -3.6 -2.8 180)
			(size 0.45 0.45)
			(layers "F.Cu" "F.Mask" "F.Paste")
			(net 178 "/SDI/~{CS_TMS}")
			(pinfunction "PL6A")
			(pintype "bidirectional")
		)
		(pad "E5" smd circle
			(at -2.8 -2.8 180)
			(size 0.45 0.45)
			(layers "F.Cu" "F.Mask" "F.Paste")
			(net 179 "/SDI/SCLK_TCK")
			(pinfunction "PL6B")
			(pintype "bidirectional")
		)
		(pad "E6" smd circle
			(at -2 -2.8 180)
			(size 0.45 0.45)
			(layers "F.Cu" "F.Mask" "F.Paste")
			(net 215 "/SDI/SDI_D17")
			(pinfunction "PL4B")
			(pintype "bidirectional")
		)
		(pad "E7" smd circle
			(at -1.2 -2.8 180)
			(size 0.45 0.45)
			(layers "F.Cu" "F.Mask" "F.Paste")
			(net 1 "GND")
			(pinfunction "VSS")
			(pintype "passive")
		)
		(pad "E8" smd circle
			(at -0.4 -2.8 180)
			(size 0.45 0.45)
			(layers "F.Cu" "F.Mask" "F.Paste")
			(net 1 "GND")
			(pinfunction "VSS")
			(pintype "passive")
		)
		(pad "E9" smd circle
			(at 0.4 -2.8 180)
			(size 0.45 0.45)
			(layers "F.Cu" "F.Mask" "F.Paste")
			(net 107 "/Peripherals/FFC2_RESET")
			(pinfunction "PR4A")
			(pintype "bidirectional")
		)
		(pad "E10" smd circle
			(at 1.2 -2.8 180)
			(size 0.45 0.45)
			(layers "F.Cu" "F.Mask" "F.Paste")
			(net 106 "/Peripherals/FFC2_VSYNC1")
			(pinfunction "PR4B")
			(pintype "bidirectional")
		)
		(pad "E11" smd circle
			(at 2 -2.8 180)
			(size 0.45 0.45)
			(layers "F.Cu" "F.Mask" "F.Paste")
			(net 169 "TMS")
			(pinfunction "PR6B/TMS/SCSN")
			(pintype "bidirectional")
		)
		(pad "E12" smd circle
			(at 2.8 -2.8 180)
			(size 0.45 0.45)
			(layers "F.Cu" "F.Mask" "F.Paste")
			(net 307 "/Peripherals/FFC1_PEN")
			(pinfunction "PR6A")
			(pintype "bidirectional")
		)
		(pad "E13" smd circle
			(at 3.6 -2.8 180)
			(size 0.45 0.45)
			(layers "F.Cu" "F.Mask" "F.Paste")
			(net 99 "/Peripherals/FCC2_SDA2")
			(pinfunction "PR10A")
			(pintype "bidirectional")
		)
		(pad "E14" smd circle
			(at 4.4 -2.8 180)
			(size 0.45 0.45)
			(layers "F.Cu" "F.Mask" "F.Paste")
			(net 171 "TDO")
			(pinfunction "PR10B/TDO/SSO")
			(pintype "bidirectional")
		)
		(pad "E15" smd circle
			(at 5.2 -2.8 180)
			(size 0.45 0.45)
			(layers "F.Cu" "F.Mask" "F.Paste")
			(net 35 "LED0")
			(pinfunction "PT84A")
			(pintype "bidirectional")
		)
		(pad "E16" smd circle
			(at 6 -2.8 180)
			(size 0.45 0.45)
			(layers "F.Cu" "F.Mask" "F.Paste")
			(net 34 "LED1")
			(pinfunction "PT84B")
			(pintype "bidirectional")
		)
		(pad "F1" smd circle
			(at -6 -2 180)
			(size 0.45 0.45)
			(layers "F.Cu" "F.Mask" "F.Paste")
			(net 71 "/Peripherals/MIPI0_D2_P")
			(pinfunction "DPHY0_D2+")
			(pintype "bidirectional")
		)
		(pad "F2" smd circle
			(at -5.2 -2 180)
			(size 0.45 0.45)
			(layers "F.Cu" "F.Mask" "F.Paste")
			(net 70 "/Peripherals/MIPI0_D2_N")
			(pinfunction "DPHY0_D2-")
			(pintype "bidirectional")
		)
		(pad "F3" smd circle
			(at -4.4 -2 180)
			(size 0.45 0.45)
			(layers "F.Cu" "F.Mask" "F.Paste")
			(net 1 "GND")
			(pinfunction "VSSADPHY")
			(pintype "passive")
		)
		(pad "F4" smd circle
			(at -3.6 -2 180)
			(size 0.45 0.45)
			(layers "F.Cu" "F.Mask" "F.Paste")
			(net 181 "/SDI/SDOUT_TDO")
			(pinfunction "PL19A/PCLKT7_1")
			(pintype "bidirectional")
		)
		(pad "F5" smd circle
			(at -2.8 -2 180)
			(size 0.45 0.45)
			(layers "F.Cu" "F.Mask" "F.Paste")
			(net 2 "+3V3")
			(pinfunction "VCCIO7")
			(pintype "power_in")
		)
		(pad "F6" smd circle
			(at -2 -2 180)
			(size 0.45 0.45)
			(layers "F.Cu" "F.Mask" "F.Paste")
			(net 176 "/SDI/STANDBY")
			(pinfunction "PL17A/PCLKT7_2")
			(pintype "bidirectional")
		)
		(pad "F7" smd circle
			(at -1.2 -2 180)
			(size 0.45 0.45)
			(layers "F.Cu" "F.Mask" "F.Paste")
			(net 10 "/FPGA Power/VCC_AUXA")
			(pinfunction "VCCAUXA")
			(pintype "power_in")
		)
		(pad "F8" smd circle
			(at -0.4 -2 180)
			(size 0.45 0.45)
			(layers "F.Cu" "F.Mask" "F.Paste")
			(net 9 "/FPGA Power/VCC_AUX")
			(pinfunction "VCCAUX")
			(pintype "power_in")
		)
		(pad "F9" smd circle
			(at 0.4 -2 180)
			(size 0.45 0.45)
			(layers "F.Cu" "F.Mask" "F.Paste")
			(net 108 "/Peripherals/FFC2_VSYNC0")
			(pinfunction "PR3B")
			(pintype "bidirectional")
		)
		(pad "F10" smd circle
			(at 1.2 -2 180)
			(size 0.45 0.45)
			(layers "F.Cu" "F.Mask" "F.Paste")
			(net 89 "/Peripherals/FFC1_RESET")
			(pinfunction "PR8A")
			(pintype "bidirectional")
		)
		(pad "F11" smd circle
			(at 2 -2 180)
			(size 0.45 0.45)
			(layers "F.Cu" "F.Mask" "F.Paste")
			(net 172 "TDI")
			(pinfunction "PR8B/TDI/SSI")
			(pintype "bidirectional")
		)
		(pad "F12" smd circle
			(at 2.8 -2 180)
			(size 0.45 0.45)
			(layers "F.Cu" "F.Mask" "F.Paste")
			(net 1 "GND")
			(pinfunction "VSS")
			(pintype "passive")
		)
		(pad "F13" smd circle
			(at 3.6 -2 180)
			(size 0.45 0.45)
			(layers "F.Cu" "F.Mask" "F.Paste")
			(net 2 "+3V3")
			(pinfunction "VCCIO1")
			(pintype "power_in")
		)
		(pad "F14" smd circle
			(at 4.4 -2 180)
			(size 0.45 0.45)
			(layers "F.Cu" "F.Mask" "F.Paste")
			(net 170 "TCK")
			(pinfunction "PR13A/TCK/SCLK")
			(pintype "bidirectional")
		)
		(pad "F15" smd circle
			(at 5.2 -2 180)
			(size 0.45 0.45)
			(layers "F.Cu" "F.Mask" "F.Paste")
			(net 44 "DIP0")
			(pinfunction "PR13B")
			(pintype "bidirectional")
		)
		(pad "F16" smd circle
			(at 6 -2 180)
			(size 0.45 0.45)
			(layers "F.Cu" "F.Mask" "F.Paste")
			(net 88 "/Peripherals/FFC1_VSYNC0")
			(pinfunction "PR19A/PCLKT1_1")
			(pintype "bidirectional")
		)
		(pad "G1" smd circle
			(at -6 -1.2 180)
			(size 0.45 0.45)
			(layers "F.Cu" "F.Mask" "F.Paste")
			(net 1 "GND")
			(pinfunction "VSSADPHY")
			(pintype "passive")
		)
		(pad "G2" smd circle
			(at -5.2 -1.2 180)
			(size 0.45 0.45)
			(layers "F.Cu" "F.Mask" "F.Paste")
			(net 1 "GND")
			(pinfunction "VSS")
			(pintype "passive")
		)
		(pad "G3" smd circle
			(at -4.4 -1.2 180)
			(size 0.45 0.45)
			(layers "F.Cu" "F.Mask" "F.Paste")
			(net 183 "/SDI/SDI_STAT5")
			(pinfunction "PL20A/PCLKT7_0")
			(pintype "bidirectional")
		)
		(pad "G4" smd circle
			(at -3.6 -1.2 180)
			(size 0.45 0.45)
			(layers "F.Cu" "F.Mask" "F.Paste")
			(net 184 "/SDI/~{SDO_DISABLE}")
			(pinfunction "PL19B")
			(pintype "bidirectional")
		)
		(pad "G5" smd circle
			(at -2.8 -1.2 180)
			(size 0.45 0.45)
			(layers "F.Cu" "F.Mask" "F.Paste")
			(net 1 "GND")
			(pinfunction "VSS")
			(pintype "passive")
		)
		(pad "G6" smd circle
			(at -2 -1.2 180)
			(size 0.45 0.45)
			(layers "F.Cu" "F.Mask" "F.Paste")
			(net 185 "/SDI/SDO_EN{slash}DIS")
			(pinfunction "PL17B")
			(pintype "bidirectional")
		)
		(pad "G7" smd circle
			(at -1.2 -1.2 180)
			(size 0.45 0.45)
			(layers "F.Cu" "F.Mask" "F.Paste")
			(net 9 "/FPGA Power/VCC_AUX")
			(pinfunction "VCCAUX")
			(pintype "passive")
		)
		(pad "G8" smd circle
			(at -0.4 -1.2 180)
			(size 0.45 0.45)
			(layers "F.Cu" "F.Mask" "F.Paste")
			(net 1 "GND")
			(pinfunction "VSS")
			(pintype "passive")
		)
		(pad "G9" smd circle
			(at 0.4 -1.2 180)
			(size 0.45 0.45)
			(layers "F.Cu" "F.Mask" "F.Paste")
			(net 101 "SDA")
			(pinfunction "PR11A/SDA/USER_SDA")
			(pintype "bidirectional")
		)
		(pad "G10" smd circle
			(at 1.2 -1.2 180)
			(size 0.45 0.45)
			(layers "F.Cu" "F.Mask" "F.Paste")
			(net 100 "SCL")
			(pinfunction "PR11B/SCL/USER_SCL")
			(pintype "bidirectional")
		)
		(pad "G11" smd circle
			(at 2 -1.2 180)
			(size 0.45 0.45)
			(layers "F.Cu" "F.Mask" "F.Paste")
			(net 91 "/Peripherals/FCC1_SDA1")
			(pinfunction "PR15A")
			(pintype "bidirectional")
		)
		(pad "G12" smd circle
			(at 2.8 -1.2 180)
			(size 0.45 0.45)
			(layers "F.Cu" "F.Mask" "F.Paste")
			(net 92 "/Peripherals/FCC1_SCL1")
			(pinfunction "PR15B")
			(pintype "bidirectional")
		)
		(pad "G13" smd circle
			(at 3.6 -1.2 180)
			(size 0.45 0.45)
			(layers "F.Cu" "F.Mask" "F.Paste")
			(net 93 "/Peripherals/FCC1_SDA2")
			(pinfunction "PR17A/PCLKT1_2")
			(pintype "bidirectional")
		)
		(pad "G14" smd circle
			(at 4.4 -1.2 180)
			(size 0.45 0.45)
			(layers "F.Cu" "F.Mask" "F.Paste")
			(net 94 "/Peripherals/FCC1_SCL2")
			(pinfunction "PR17B")
			(pintype "bidirectional")
		)
		(pad "G15" smd circle
			(at 5.2 -1.2 180)
			(size 0.45 0.45)
			(layers "F.Cu" "F.Mask" "F.Paste")
			(net 186 "40MHz_3V3")
			(pinfunction "PR20A/PCLKT1_0\n")
			(pintype "bidirectional")
		)
		(pad "G16" smd circle
			(at 6 -1.2 180)
			(size 0.45 0.45)
			(layers "F.Cu" "F.Mask" "F.Paste")
			(net 90 "/Peripherals/FFC1_VSYNC1")
			(pinfunction "PR19B")
			(pintype "bidirectional")
		)
		(pad "H1" smd circle
			(at -6 -0.4 180)
			(size 0.45 0.45)
			(layers "F.Cu" "F.Mask" "F.Paste")
			(net 194 "/SDI/SDI_D7")
			(pinfunction "PL27A")
			(pintype "bidirectional")
		)
		(pad "H2" smd circle
			(at -5.2 -0.4 180)
			(size 0.45 0.45)
			(layers "F.Cu" "F.Mask" "F.Paste")
			(net 205 "/SDI/SDI_D11")
			(pinfunction "PL27B")
			(pintype "bidirectional")
		)
		(pad "H3" smd circle
			(at -4.4 -0.4 180)
			(size 0.45 0.45)
			(layers "F.Cu" "F.Mask" "F.Paste")
			(net 180 "/SDI/TIM_861")
			(pinfunction "PL26B")
			(pintype "bidirectional")
		)
		(pad "H4" smd circle
			(at -3.6 -0.4 180)
			(size 0.45 0.45)
			(layers "F.Cu" "F.Mask" "F.Paste")
			(net 195 "/SDI/SDI_D8")
			(pinfunction "PL26A")
			(pintype "bidirectional")
		)
		(pad "H5" smd circle
			(at -2.8 -0.4 180)
			(size 0.45 0.45)
			(layers "F.Cu" "F.Mask" "F.Paste")
			(net 203 "/SDI/SDI_D10")
			(pinfunction "PL24B")
			(pintype "bidirectional")
		)
		(pad "H6" smd circle
			(at -2 -0.4 180)
			(size 0.45 0.45)
			(layers "F.Cu" "F.Mask" "F.Paste")
			(net 182 "/SDI/SDIN_TDI")
			(pinfunction "PL24A")
			(pintype "bidirectional")
		)
		(pad "H7" smd circle
			(at -1.2 -0.4 180)
			(size 0.45 0.45)
			(layers "F.Cu" "F.Mask" "F.Paste")
			(net 4 "1V0_Power")
			(pinfunction "VCC")
			(pintype "passive")
		)
		(pad "H8" smd circle
			(at -0.4 -0.4 180)
			(size 0.45 0.45)
			(layers "F.Cu" "F.Mask" "F.Paste")
			(net 1 "GND")
			(pinfunction "VSS")
			(pintype "passive")
		)
		(pad "H9" smd circle
			(at 0.4 -0.4 180)
			(size 0.45 0.45)
			(layers "F.Cu" "F.Mask" "F.Paste")
			(net 1 "GND")
			(pinfunction "VSS")
			(pintype "passive")
		)
		(pad "H10" smd circle
			(at 1.2 -0.4 180)
			(size 0.45 0.45)
			(layers "F.Cu" "F.Mask" "F.Paste")
			(net 43 "DIP1")
			(pinfunction "PR30B")
			(pintype "bidirectional")
		)
		(pad "H11" smd circle
			(at 2 -0.4 180)
			(size 0.45 0.45)
			(layers "F.Cu" "F.Mask" "F.Paste")
			(net 193 "/SDI/DVB_ASI")
			(pinfunction "PR30A/PCLKT2_0")
			(pintype "bidirectional")
		)
		(pad "H12" smd circle
			(at 2.8 -0.4 180)
			(size 0.45 0.45)
			(layers "F.Cu" "F.Mask" "F.Paste")
			(net 371 "FCC2_SCL2")
			(pinfunction "PR32B")
			(pintype "bidirectional")
		)
		(pad "H13" smd circle
			(at 3.6 -0.4 180)
			(size 0.45 0.45)
			(layers "F.Cu" "F.Mask" "F.Paste")
			(net 199 "/SDI/IOPROC_EN{slash}~{DIS}")
			(pinfunction "PR32A/PCLKT2_1")
			(pintype "bidirectional")
		)
		(pad "H14" smd circle
			(at 4.4 -0.4 180)
			(size 0.45 0.45)
			(layers "F.Cu" "F.Mask" "F.Paste")
			(net 333 "GPIO1")
			(pinfunction "PR27B")
			(pintype "bidirectional")
		)
		(pad "H15" smd circle
			(at 5.2 -0.4 180)
			(size 0.45 0.45)
			(layers "F.Cu" "F.Mask" "F.Paste")
			(net 334 "GPIO2")
			(pinfunction "PR27A")
			(pintype "bidirectional")
		)
		(pad "H16" smd circle
			(at 6 -0.4 180)
			(size 0.45 0.45)
			(layers "F.Cu" "F.Mask" "F.Paste")
			(net 332 "GPIO0")
			(pinfunction "PR26A")
			(pintype "bidirectional")
		)
		(pad "J1" smd circle
			(at -6 0.4 180)
			(size 0.45 0.45)
			(layers "F.Cu" "F.Mask" "F.Paste")
			(net 187 "/SDI/SDI_D4")
			(pinfunction "PL32A/PCLKT6_1")
			(pintype "bidirectional")
		)
		(pad "J2" smd circle
			(at -5.2 0.4 180)
			(size 0.45 0.45)
			(layers "F.Cu" "F.Mask" "F.Paste")
			(net 188 "/SDI/SDI_D5")
			(pinfunction "PL32B")
			(pintype "bidirectional")
		)
		(pad "J3" smd circle
			(at -4.4 0.4 180)
			(size 0.45 0.45)
			(layers "F.Cu" "F.Mask" "F.Paste")
			(net 1 "GND")
			(pinfunction "VSS")
			(pintype "passive")
		)
		(pad "J4" smd circle
			(at -3.6 0.4 180)
			(size 0.45 0.45)
			(layers "F.Cu" "F.Mask" "F.Paste")
			(net 2 "+3V3")
			(pinfunction "VCCIO6")
			(pintype "power_in")
		)
		(pad "J5" smd circle
			(at -2.8 0.4 180)
			(size 0.45 0.45)
			(layers "F.Cu" "F.Mask" "F.Paste")
			(net 210 "/SDI/SDI_D15")
			(pinfunction "PL30B")
			(pintype "bidirectional")
		)
		(pad "J6" smd circle
			(at -2 0.4 180)
			(size 0.45 0.45)
			(layers "F.Cu" "F.Mask" "F.Paste")
			(net 204 "/SDI/SDI_D12")
			(pinfunction "PL30A/PCLKT6_0")
			(pintype "bidirectional")
		)
		(pad "J7" smd circle
			(at -1.2 0.4 180)
			(size 0.45 0.45)
			(layers "F.Cu" "F.Mask" "F.Paste")
			(net 1 "GND")
			(pinfunction "VSS")
			(pintype "passive")
		)
		(pad "J8" smd circle
			(at -0.4 0.4 180)
			(size 0.45 0.45)
			(layers "F.Cu" "F.Mask" "F.Paste")
			(net 1 "GND")
			(pinfunction "VSS")
			(pintype "passive")
		)
		(pad "J9" smd circle
			(at 0.4 0.4 180)
			(size 0.45 0.45)
			(layers "F.Cu" "F.Mask" "F.Paste")
			(net 1 "GND")
			(pinfunction "VSS")
			(pintype "passive")
		)
		(pad "J10" smd circle
			(at 1.2 0.4 180)
			(size 0.45 0.45)
			(layers "F.Cu" "F.Mask" "F.Paste")
			(net 4 "1V0_Power")
			(pinfunction "VCC")
			(pintype "passive")
		)
		(pad "J11" smd circle
			(at 2 0.4 180)
			(size 0.45 0.45)
			(layers "F.Cu" "F.Mask" "F.Paste")
			(net 357 "TXD")
			(pinfunction "PR36A")
			(pintype "bidirectional")
		)
		(pad "J12" smd circle
			(at 2.8 0.4 180)
			(size 0.45 0.45)
			(layers "F.Cu" "F.Mask" "F.Paste")
			(net 355 "RXD")
			(pinfunction "PR36B")
			(pintype "bidirectional")
		)
		(pad "J13" smd circle
			(at 3.6 0.4 180)
			(size 0.45 0.45)
			(layers "F.Cu" "F.Mask" "F.Paste")
			(net 2 "+3V3")
			(pinfunction "VCCIO2")
			(pintype "power_in")
		)
		(pad "J14" smd circle
			(at 4.4 0.4 180)
			(size 0.45 0.45)
			(layers "F.Cu" "F.Mask" "F.Paste")
			(net 1 "GND")
			(pinfunction "VSS")
			(pintype "passive")
		)
		(pad "J15" smd circle
			(at 5.2 0.4 180)
			(size 0.45 0.45)
			(layers "F.Cu" "F.Mask" "F.Paste")
			(net 335 "GPIO3")
			(pinfunction "PR34B")
			(pintype "bidirectional")
		)
		(pad "J16" smd circle
			(at 6 0.4 180)
			(size 0.45 0.45)
			(layers "F.Cu" "F.Mask" "F.Paste")
			(net 201 "/SDI/~{SMPTE_BYPASS}")
			(pinfunction "PR34A/PCLKT2_2")
			(pintype "bidirectional")
		)
		(pad "K1" smd circle
			(at -6 1.2 180)
			(size 0.45 0.45)
			(layers "F.Cu" "F.Mask" "F.Paste")
			(net 190 "/SDI/SDI_D2")
			(pinfunction "PL34A/PCLKT6_2")
			(pintype "bidirectional")
		)
		(pad "K2" smd circle
			(at -5.2 1.2 180)
			(size 0.45 0.45)
			(layers "F.Cu" "F.Mask" "F.Paste")
			(net 189 "/SDI/SDI_D3")
			(pinfunction "PL34B")
			(pintype "bidirectional")
		)
		(pad "K3" smd circle
			(at -4.4 1.2 180)
			(size 0.45 0.45)
			(layers "F.Cu" "F.Mask" "F.Paste")
			(net 202 "/SDI/SDI_D9")
			(pinfunction "PL36B")
			(pintype "bidirectional")
		)
		(pad "K4" smd circle
			(at -3.6 1.2 180)
			(size 0.45 0.45)
			(layers "F.Cu" "F.Mask" "F.Paste")
			(net 213 "/SDI/SDI_D19")
			(pinfunction "PL36A")
			(pintype "bidirectional")
		)
		(pad "K5" smd circle
			(at -2.8 1.2 180)
			(size 0.45 0.45)
			(layers "F.Cu" "F.Mask" "F.Paste")
			(net 207 "/SDI/SDI_D13")
			(pinfunction "PL38B")
			(pintype "bidirectional")
		)
		(pad "K6" smd circle
			(at -2 1.2 180)
			(size 0.45 0.45)
			(layers "F.Cu" "F.Mask" "F.Paste")
			(net 216 "/SDI/SDI_D18")
			(pinfunction "PL38A")
			(pintype "bidirectional")
		)
		(pad "K7" smd circle
			(at -1.2 1.2 180)
			(size 0.45 0.45)
			(layers "F.Cu" "F.Mask" "F.Paste")
			(net 78 "/Peripherals/MIPI2_D3_N")
			(pinfunction "PB10B/PCLKC5_2/ADC_CN2/COMP3N")
			(pintype "bidirectional")
		)
		(pad "K8" smd circle
			(at -0.4 1.2 180)
			(size 0.45 0.45)
			(layers "F.Cu" "F.Mask" "F.Paste")
			(net 9 "/FPGA Power/VCC_AUX")
			(pinfunction "VCCAUXH4")
			(pintype "power_in")
		)
		(pad "K9" smd circle
			(at 0.4 1.2 180)
			(size 0.45 0.45)
			(layers "F.Cu" "F.Mask" "F.Paste")
			(net 4 "1V0_Power")
			(pinfunction "VCCECLK")
			(pintype "power_in")
		)
		(pad "K10" smd circle
			(at 1.2 1.2 180)
			(size 0.45 0.45)
			(layers "F.Cu" "F.Mask" "F.Paste")
			(net 9 "/FPGA Power/VCC_AUX")
			(pinfunction "VCCAUXH3")
			(pintype "power_in")
		)
		(pad "K11" smd circle
			(at 2 1.2 180)
			(size 0.45 0.45)
			(layers "F.Cu" "F.Mask" "F.Paste")
			(net 208 "/SDI/JTAG{slash}~{HOST}")
			(pinfunction "PR38A")
			(pintype "bidirectional")
		)
		(pad "K12" smd circle
			(at 2.8 1.2 180)
			(size 0.45 0.45)
			(layers "F.Cu" "F.Mask" "F.Paste")
			(net 209 "/SDI/~{RC_BYP}")
			(pinfunction "PR38B")
			(pintype "bidirectional")
		)
		(pad "K13" smd circle
			(at 3.6 1.2 180)
			(size 0.45 0.45)
			(layers "F.Cu" "F.Mask" "F.Paste")
			(net 1 "GND")
			(pinfunction "ADC_D0-")
			(pintype "passive")
		)
		(pad "K14" smd circle
			(at 4.4 1.2 180)
			(size 0.45 0.45)
			(layers "F.Cu" "F.Mask" "F.Paste")
			(net 1 "GND")
			(pinfunction "ADC_D0+")
			(pintype "passive")
		)
		(pad "K15" smd circle
			(at 5.2 1.2 180)
			(size 0.45 0.45)
			(layers "F.Cu" "F.Mask" "F.Paste")
			(net 1 "GND")
			(pinfunction "ADC_D1+")
			(pintype "passive")
		)
		(pad "K16" smd circle
			(at 6 1.2 180)
			(size 0.45 0.45)
			(layers "F.Cu" "F.Mask" "F.Paste")
			(net 1 "GND")
			(pinfunction "ADC_D1-")
			(pintype "passive")
		)
		(pad "L1" smd circle
			(at -6 2 180)
			(size 0.45 0.45)
			(layers "F.Cu" "F.Mask" "F.Paste")
			(net 192 "/SDI/SDI_D0")
			(pinfunction "PL40A")
			(pintype "bidirectional")
		)
		(pad "L2" smd circle
			(at -5.2 2 180)
			(size 0.45 0.45)
			(layers "F.Cu" "F.Mask" "F.Paste")
			(net 191 "/SDI/SDI_D1")
			(pinfunction "PL40B")
			(pintype "bidirectional")
		)
		(pad "L3" smd circle
			(at -4.4 2 180)
			(size 0.45 0.45)
			(layers "F.Cu" "F.Mask" "F.Paste")
			(net 196 "/SDI/SDI_D6")
			(pinfunction "PL47B")
			(pintype "bidirectional")
		)
		(pad "L4" smd circle
			(at -3.6 2 180)
			(size 0.45 0.45)
			(layers "F.Cu" "F.Mask" "F.Paste")
			(net 211 "/SDI/SDI_D16")
			(pinfunction "PL46A")
			(pintype "bidirectional")
		)
		(pad "L5" smd circle
			(at -2.8 2 180)
			(size 0.45 0.45)
			(layers "F.Cu" "F.Mask" "F.Paste")
			(net 197 "/SDI/SDI_PCLK")
			(pinfunction "PL46B")
			(pintype "bidirectional")
		)
		(pad "L6" smd circle
			(at -2 2 180)
			(size 0.45 0.45)
			(layers "F.Cu" "F.Mask" "F.Paste")
			(net 79 "/Peripherals/MIPI2_D3_P")
			(pinfunction "PB10A/PCLKT5_2/ADC_CP2/COMP3P")
			(pintype "bidirectional")
		)
		(pad "L7" smd circle
			(at -1.2 2 180)
			(size 0.45 0.45)
			(layers "F.Cu" "F.Mask" "F.Paste")
			(net 81 "/Peripherals/MIPI2_D2_P")
			(pinfunction "PB8A/PCLKT5_1/LLC_GPLL0T_IN/ADC_CP3")
			(pintype "bidirectional")
		)
		(pad "L8" smd circle
			(at -0.4 2 180)
			(size 0.45 0.45)
			(layers "F.Cu" "F.Mask" "F.Paste")
			(net 153 "/DDR3/DDR3_A9")
			(pinfunction "PB34A")
			(pintype "bidirectional")
		)
		(pad "L9" smd circle
			(at 0.4 2 180)
			(size 0.45 0.45)
			(layers "F.Cu" "F.Mask" "F.Paste")
			(net 149 "/DDR3/DDR3_A5")
			(pinfunction "PB34B")
			(pintype "bidirectional")
		)
		(pad "L10" smd circle
			(at 1.2 2 180)
			(size 0.45 0.45)
			(layers "F.Cu" "F.Mask" "F.Paste")
			(net 150 "/DDR3/DDR3_A7")
			(pinfunction "PB80B/ADC_CN12")
			(pintype "bidirectional")
		)
		(pad "L11" smd circle
			(at 2 2 180)
			(size 0.45 0.45)
			(layers "F.Cu" "F.Mask" "F.Paste")
			(net 144 "/DDR3/DDR3_A2")
			(pinfunction "PB80A/ADC_CP12")
			(pintype "bidirectional")
		)
		(pad "L12" smd circle
			(at 2.8 2 180)
			(size 0.45 0.45)
			(layers "F.Cu" "F.Mask" "F.Paste")
			(net 155 "/DDR3/DDR3_A8")
			(pinfunction "PB82B/ADC_CN15")
			(pintype "bidirectional")
		)
		(pad "L13" smd circle
			(at 3.6 2 180)
			(size 0.45 0.45)
			(layers "F.Cu" "F.Mask" "F.Paste")
			(net 1 "GND")
			(pinfunction "VSSADC")
			(pintype "power_in")
		)
		(pad "L14" smd circle
			(at 4.4 2 180)
			(size 0.45 0.45)
			(layers "F.Cu" "F.Mask" "F.Paste")
			(net 390 "unconnected-(U11K-VCCADC18-PadL14)")
			(pinfunction "VCCADC18")
			(pintype "power_in+no_connect")
		)
		(pad "L15" smd circle
			(at 5.2 2 180)
			(size 0.45 0.45)
			(layers "F.Cu" "F.Mask" "F.Paste")
			(net 1 "GND")
			(pinfunction "ADC_REFP0")
			(pintype "passive")
		)
		(pad "L16" smd circle
			(at 6 2 180)
			(size 0.45 0.45)
			(layers "F.Cu" "F.Mask" "F.Paste")
			(net 1 "GND")
			(pinfunction "ADC_REFP1")
			(pintype "passive")
		)
		(pad "M1" smd circle
			(at -6 2.8 180)
			(size 0.45 0.45)
			(layers "F.Cu" "F.Mask" "F.Paste")
			(net 218 "/SDI/SDI_STAT4")
			(pinfunction "PL42A")
			(pintype "bidirectional")
		)
		(pad "M2" smd circle
			(at -5.2 2.8 180)
			(size 0.45 0.45)
			(layers "F.Cu" "F.Mask" "F.Paste")
			(net 212 "/SDI/SDI_STAT2")
			(pinfunction "PL42B")
			(pintype "bidirectional")
		)
		(pad "M3" smd circle
			(at -4.4 2.8 180)
			(size 0.45 0.45)
			(layers "F.Cu" "F.Mask" "F.Paste")
			(net 217 "/SDI/SDI_STAT1")
			(pinfunction "PL47A")
			(pintype "bidirectional")
		)
		(pad "M4" smd circle
			(at -3.6 2.8 180)
			(size 0.45 0.45)
			(layers "F.Cu" "F.Mask" "F.Paste")
			(net 82 "/Peripherals/MIPI2_D1_N")
			(pinfunction "PB6B/PCLKC5_0/CDR_RXN1/ADC_CN1/COMP2N")
			(pintype "bidirectional")
		)
		(pad "M5" smd circle
			(at -2.8 2.8 180)
			(size 0.45 0.45)
			(layers "F.Cu" "F.Mask" "F.Paste")
			(net 1 "GND")
			(pinfunction "VSS")
			(pintype "passive")
		)
		(pad "M6" smd circle
			(at -2 2.8 180)
			(size 0.45 0.45)
			(layers "F.Cu" "F.Mask" "F.Paste")
			(net 9 "/FPGA Power/VCC_AUX")
			(pinfunction "VCCAUXH5")
			(pintype "power_in")
		)
		(pad "M7" smd circle
			(at -1.2 2.8 180)
			(size 0.45 0.45)
			(layers "F.Cu" "F.Mask" "F.Paste")
			(net 80 "/Peripherals/MIPI2_D2_N")
			(pinfunction "PB8B/PCLKC5_1/LLC_GPLL0C_IN/ADC_CN3")
			(pintype "bidirectional")
		)
		(pad "M8" smd circle
			(at -0.4 2.8 180)
			(size 0.45 0.45)
			(layers "F.Cu" "F.Mask" "F.Paste")
			(net 1 "GND")
			(pinfunction "PB38B")
			(pintype "bidirectional")
		)
		(pad "M9" smd circle
			(at 0.4 2.8 180)
			(size 0.45 0.45)
			(layers "F.Cu" "F.Mask" "F.Paste")
			(net 1 "GND")
			(pinfunction "PB38A")
			(pintype "bidirectional")
		)
		(pad "M10" smd circle
			(at 1.2 2.8 180)
			(size 0.45 0.45)
			(layers "F.Cu" "F.Mask" "F.Paste")
			(net 167 "/DDR3/DDR3_BA2")
			(pinfunction "PB46A")
			(pintype "bidirectional")
		)
		(pad "M11" smd circle
			(at 2 2.8 180)
			(size 0.45 0.45)
			(layers "F.Cu" "F.Mask" "F.Paste")
			(net 1 "GND")
			(pinfunction "PB78B/ADC_CN11")
			(pintype "bidirectional")
		)
		(pad "M12" smd circle
			(at 2.8 2.8 180)
			(size 0.45 0.45)
			(layers "F.Cu" "F.Mask" "F.Paste")
			(net 162 "/DDR3/~{DDR3_RAS}")
			(pinfunction "PB78A/ADC_CP11")
			(pintype "bidirectional")
		)
		(pad "M13" smd circle
			(at 3.6 2.8 180)
			(size 0.45 0.45)
			(layers "F.Cu" "F.Mask" "F.Paste")
			(net 148 "/DDR3/DDR3_A6")
			(pinfunction "PB82A/ADC_CP15")
			(pintype "bidirectional")
		)
		(pad "M14" smd circle
			(at 4.4 2.8 180)
			(size 0.45 0.45)
			(layers "F.Cu" "F.Mask" "F.Paste")
			(net 154 "/DDR3/DDR3_A11")
			(pinfunction "PB74A/PCLKT3_3/ADC_CP14")
			(pintype "bidirectional")
		)
		(pad "M15" smd circle
			(at 5.2 2.8 180)
			(size 0.45 0.45)
			(layers "F.Cu" "F.Mask" "F.Paste")
			(net 1 "GND")
			(pinfunction "PB84B/LRC_GPLL0C_IN/VREF3_2")
			(pintype "bidirectional")
		)
		(pad "M16" smd circle
			(at 6 2.8 180)
			(size 0.45 0.45)
			(layers "F.Cu" "F.Mask" "F.Paste")
			(net 151 "/DDR3/DDR3_A4")
			(pinfunction "PB84A/LRC_GPLL0T_IN")
			(pintype "bidirectional")
		)
		(pad "N1" smd circle
			(at -6 3.6 180)
			(size 0.45 0.45)
			(layers "F.Cu" "F.Mask" "F.Paste")
			(net 219 "/SDI/SDI_STAT3")
			(pinfunction "PL49B")
			(pintype "bidirectional")
		)
		(pad "N2" smd circle
			(at -5.2 3.6 180)
			(size 0.45 0.45)
			(layers "F.Cu" "F.Mask" "F.Paste")
			(net 214 "/SDI/SDI_STAT0")
			(pinfunction "PL49A")
			(pintype "bidirectional")
		)
		(pad "N3" smd circle
			(at -4.4 3.6 180)
			(size 0.45 0.45)
			(layers "F.Cu" "F.Mask" "F.Paste")
			(net 84 "/Peripherals/MIPI2_D0_N")
			(pinfunction "PB4B/CDR_RXN0/ADC_CN0/COMP1N")
			(pintype "bidirectional")
		)
		(pad "N4" smd circle
			(at -3.6 3.6 180)
			(size 0.45 0.45)
			(layers "F.Cu" "F.Mask" "F.Paste")
			(net 83 "/Peripherals/MIPI2_D1_P")
			(pinfunction "PB6A/PCLKT5_0/CDR_RXP1/ADC_CP1/COMP2P")
			(pintype "bidirectional")
		)
		(pad "N5" smd circle
			(at -2.8 3.6 180)
			(size 0.45 0.45)
			(layers "F.Cu" "F.Mask" "F.Paste")
			(net 3 "+1V2")
			(pinfunction "VCCIO5")
			(pintype "power_in")
		)
		(pad "N6" smd circle
			(at -2 3.6 180)
			(size 0.45 0.45)
			(layers "F.Cu" "F.Mask" "F.Paste")
			(net 248 "+1V5")
			(pinfunction "VCCIO4")
			(pintype "power_in")
		)
		(pad "N7" smd circle
			(at -1.2 3.6 180)
			(size 0.45 0.45)
			(layers "F.Cu" "F.Mask" "F.Paste")
			(net 1 "GND")
			(pinfunction "VSS")
			(pintype "passive")
		)
		(pad "N8" smd circle
			(at -0.4 3.6 180)
			(size 0.45 0.45)
			(layers "F.Cu" "F.Mask" "F.Paste")
			(net 158 "/DDR3/DDR3_A13")
			(pinfunction "PB36A")
			(pintype "bidirectional")
		)
		(pad "N9" smd circle
			(at 0.4 3.6 180)
			(size 0.45 0.45)
			(layers "F.Cu" "F.Mask" "F.Paste")
			(net 164 "/DDR3/~{DDR3_RESET}")
			(pinfunction "PB36B")
			(pintype "bidirectional")
		)
		(pad "N10" smd circle
			(at 1.2 3.6 180)
			(size 0.45 0.45)
			(layers "F.Cu" "F.Mask" "F.Paste")
			(net 168 "/DDR3/~{DDR3_CS}")
			(pinfunction "PB46B/VREF4_2")
			(pintype "bidirectional")
		)
		(pad "N11" smd circle
			(at 2 3.6 180)
			(size 0.45 0.45)
			(layers "F.Cu" "F.Mask" "F.Paste")
			(net 1 "GND")
			(pinfunction "PB64B/ADC_CN4")
			(pintype "bidirectional")
		)
		(pad "N12" smd circle
			(at 2.8 3.6 180)
			(size 0.45 0.45)
			(layers "F.Cu" "F.Mask" "F.Paste")
			(net 1 "GND")
			(pinfunction "PB64A/ADC_CP4")
			(pintype "bidirectional")
		)
		(pad "N13" smd circle
			(at 3.6 3.6 180)
			(size 0.45 0.45)
			(layers "F.Cu" "F.Mask" "F.Paste")
			(net 165 "/DDR3/DDR3_CKE")
			(pinfunction "PB70B/COMP2IN\n")
			(pintype "bidirectional")
		)
		(pad "N14" smd circle
			(at 4.4 3.6 180)
			(size 0.45 0.45)
			(layers "F.Cu" "F.Mask" "F.Paste")
			(net 1 "GND")
			(pinfunction "PB74B/PCLKC3_3/ADC_CN14")
			(pintype "bidirectional")
		)
		(pad "N15" smd circle
			(at 5.2 3.6 180)
			(size 0.45 0.45)
			(layers "F.Cu" "F.Mask" "F.Paste")
			(net 160 "/DDR3/DDR3_A12")
			(pinfunction "PB76B/COMP3IN")
			(pintype "bidirectional")
		)
		(pad "N16" smd circle
			(at 6 3.6 180)
			(size 0.45 0.45)
			(layers "F.Cu" "F.Mask" "F.Paste")
			(net 145 "/DDR3/DDR3_A1")
			(pinfunction "PB76A/COMP3IP")
			(pintype "bidirectional")
		)
		(pad "P1" smd circle
			(at -6 4.4 180)
			(size 0.45 0.45)
			(layers "F.Cu" "F.Mask" "F.Paste")
			(net 87 "/Peripherals/MIPI2_CLK_P")
			(pinfunction "PB12A/PCLKT5_3")
			(pintype "bidirectional")
		)
		(pad "P2" smd circle
			(at -5.2 4.4 180)
			(size 0.45 0.45)
			(layers "F.Cu" "F.Mask" "F.Paste")
			(net 86 "/Peripherals/MIPI2_CLK_N")
			(pinfunction "PB12B/PCLKC5_3/VREF5_2")
			(pintype "bidirectional")
		)
		(pad "P3" smd circle
			(at -4.4 4.4 180)
			(size 0.45 0.45)
			(layers "F.Cu" "F.Mask" "F.Paste")
			(net 85 "/Peripherals/MIPI2_D0_P")
			(pinfunction "PB4A/CDR_RXP0/VREF5_1/ADC_CP0/COMP1P\n")
			(pintype "bidirectional")
		)
		(pad "P4" smd circle
			(at -3.6 4.4 180)
			(size 0.45 0.45)
			(layers "F.Cu" "F.Mask" "F.Paste")
			(net 1 "GND")
			(pinfunction "PB24B/PCLKC4_2\n")
			(pintype "bidirectional")
		)
		(pad "P5" smd circle
			(at -2.8 4.4 180)
			(size 0.45 0.45)
			(layers "F.Cu" "F.Mask" "F.Paste")
			(net 220 "/DDR3/DDR3_LDQS_N")
			(pinfunction "PB22B")
			(pintype "bidirectional")
		)
		(pad "P6" smd circle
			(at -2 4.4 180)
			(size 0.45 0.45)
			(layers "F.Cu" "F.Mask" "F.Paste")
			(net 163 "/DDR3/~{DDR3_WE}")
			(pinfunction "PB32A")
			(pintype "bidirectional")
		)
		(pad "P7" smd circle
			(at -1.2 4.4 180)
			(size 0.45 0.45)
			(layers "F.Cu" "F.Mask" "F.Paste")
			(net 147 "/DDR3/DDR3_A0")
			(pinfunction "PB32B")
			(pintype "bidirectional")
		)
		(pad "P8" smd circle
			(at -0.4 4.4 180)
			(size 0.45 0.45)
			(layers "F.Cu" "F.Mask" "F.Paste")
			(net 146 "/DDR3/DDR3_A3")
			(pinfunction "PB42B")
			(pintype "bidirectional")
		)
		(pad "P9" smd circle
			(at 0.4 4.4 180)
			(size 0.45 0.45)
			(layers "F.Cu" "F.Mask" "F.Paste")
			(net 157 "/DDR3/DDR3_BA0")
			(pinfunction "PB44B/PCLKC4_0")
			(pintype "bidirectional")
		)
		(pad "P10" smd circle
			(at 1.2 4.4 180)
			(size 0.45 0.45)
			(layers "F.Cu" "F.Mask" "F.Paste")
			(net 1 "GND")
			(pinfunction "PB56A/ADC_CP7\n")
			(pintype "bidirectional")
		)
		(pad "P11" smd circle
			(at 2 4.4 180)
			(size 0.45 0.45)
			(layers "F.Cu" "F.Mask" "F.Paste")
			(net 248 "+1V5")
			(pinfunction "PB54B/PCLKC3_0/ADC_CN5\n")
			(pintype "bidirectional")
		)
		(pad "P12" smd circle
			(at 2.8 4.4 180)
			(size 0.45 0.45)
			(layers "F.Cu" "F.Mask" "F.Paste")
			(net 248 "+1V5")
			(pinfunction "VCCIO3")
			(pintype "bidirectional")
		)
		(pad "P13" smd circle
			(at 3.6 4.4 180)
			(size 0.45 0.45)
			(layers "F.Cu" "F.Mask" "F.Paste")
			(net 1 "GND")
			(pinfunction "VSS")
			(pintype "passive")
		)
		(pad "P14" smd circle
			(at 4.4 4.4 180)
			(size 0.45 0.45)
			(layers "F.Cu" "F.Mask" "F.Paste")
			(net 1 "GND")
			(pinfunction "PB70A/COMP2IP")
			(pintype "bidirectional")
		)
		(pad "P15" smd circle
			(at 5.2 4.4 180)
			(size 0.45 0.45)
			(layers "F.Cu" "F.Mask" "F.Paste")
			(net 152 "/DDR3/DDR3_A10")
			(pinfunction "PB72A/PCLKT3_2/ADC_CP13")
			(pintype "bidirectional")
		)
		(pad "P16" smd circle
			(at 6 4.4 180)
			(size 0.45 0.45)
			(layers "F.Cu" "F.Mask" "F.Paste")
			(net 159 "/DDR3/DDR3_BA1")
			(pinfunction "PB72B/PCLKC3_2/ADC_CN13")
			(pintype "bidirectional")
		)
		(pad "R1" smd circle
			(at -6 5.2 180)
			(size 0.45 0.45)
			(layers "F.Cu" "F.Mask" "F.Paste")
			(net 5 "Vref")
			(pinfunction "PB16A/VREF4_1")
			(pintype "bidirectional")
		)
		(pad "R2" smd circle
			(at -5.2 5.2 180)
			(size 0.45 0.45)
			(layers "F.Cu" "F.Mask" "F.Paste")
			(net 248 "+1V5")
			(pinfunction "PB16B")
			(pintype "bidirectional")
		)
		(pad "R3" smd circle
			(at -4.4 5.2 180)
			(size 0.45 0.45)
			(layers "F.Cu" "F.Mask" "F.Paste")
			(net 234 "/DDR3/DDR3_DQ2")
			(pinfunction "PB18A/PCLKT4_3\n")
			(pintype "bidirectional")
		)
		(pad "R4" smd circle
			(at -3.6 5.2 180)
			(size 0.45 0.45)
			(layers "F.Cu" "F.Mask" "F.Paste")
			(net 224 "/DDR3/DDR3_DQ5")
			(pinfunction "PB24A/PCLKT4_2")
			(pintype "bidirectional")
		)
		(pad "R5" smd circle
			(at -2.8 5.2 180)
			(size 0.45 0.45)
			(layers "F.Cu" "F.Mask" "F.Paste")
			(net 223 "/DDR3/DDR3_LDQS_P")
			(pinfunction "PB22A")
			(pintype "bidirectional")
		)
		(pad "R6" smd circle
			(at -2 5.2 180)
			(size 0.45 0.45)
			(layers "F.Cu" "F.Mask" "F.Paste")
			(net 222 "/DDR3/DDR3_DQ3")
			(pinfunction "PB26B")
			(pintype "bidirectional")
		)
		(pad "R7" smd circle
			(at -1.2 5.2 180)
			(size 0.45 0.45)
			(layers "F.Cu" "F.Mask" "F.Paste")
			(net 232 "/DDR3/DDR3_LDM")
			(pinfunction "PB28B")
			(pintype "bidirectional")
		)
		(pad "R8" smd circle
			(at -0.4 5.2 180)
			(size 0.45 0.45)
			(layers "F.Cu" "F.Mask" "F.Paste")
			(net 1 "GND")
			(pinfunction "PB42A")
			(pintype "bidirectional")
		)
		(pad "R9" smd circle
			(at 0.4 5.2 180)
			(size 0.45 0.45)
			(layers "F.Cu" "F.Mask" "F.Paste")
			(net 1 "GND")
			(pinfunction "PB44A/PCLKT4_0")
			(pintype "bidirectional")
		)
		(pad "R10" smd circle
			(at 1.2 5.2 180)
			(size 0.45 0.45)
			(layers "F.Cu" "F.Mask" "F.Paste")
			(net 240 "/DDR3/DDR3_DQ13")
			(pinfunction "PB56B/ADC_CN7\n")
			(pintype "bidirectional")
		)
		(pad "R11" smd circle
			(at 2 5.2 180)
			(size 0.45 0.45)
			(layers "F.Cu" "F.Mask" "F.Paste")
			(net 5 "Vref")
			(pinfunction "PB54A/PCLKT3_0/VREF3_1/ADC_CP5")
			(pintype "bidirectional")
		)
		(pad "R12" smd circle
			(at 2.8 5.2 180)
			(size 0.45 0.45)
			(layers "F.Cu" "F.Mask" "F.Paste")
			(net 227 "/DDR3/DDR3_UDQS_P")
			(pinfunction "PB60A/ADC_CP9")
			(pintype "bidirectional")
		)
		(pad "R13" smd circle
			(at 3.6 5.2 180)
			(size 0.45 0.45)
			(layers "F.Cu" "F.Mask" "F.Paste")
			(net 228 "/DDR3/DDR3_DQ11")
			(pinfunction "PB62A/ADC_CP10")
			(pintype "bidirectional")
		)
		(pad "R14" smd circle
			(at 4.4 5.2 180)
			(size 0.45 0.45)
			(layers "F.Cu" "F.Mask" "F.Paste")
			(net 229 "/DDR3/DDR3_DQ12")
			(pinfunction "PB62B/ADC_CN10")
			(pintype "bidirectional")
		)
		(pad "R15" smd circle
			(at 5.2 5.2 180)
			(size 0.45 0.45)
			(layers "F.Cu" "F.Mask" "F.Paste")
			(net 241 "/DDR3/DDR3_DQ14")
			(pinfunction "PB68B/ADC_CN8")
			(pintype "bidirectional")
		)
		(pad "R16" smd circle
			(at 6 5.2 180)
			(size 0.45 0.45)
			(layers "F.Cu" "F.Mask" "F.Paste")
			(net 226 "/DDR3/DDR3_DQ8")
			(pinfunction "PB68A/ADC_CP8")
			(pintype "bidirectional")
		)
		(pad "T1" smd circle
			(at -6 6 180)
			(size 0.45 0.45)
			(layers "F.Cu" "F.Mask" "F.Paste")
			(net 1 "GND")
			(pinfunction "VSS")
			(pintype "passive")
		)
		(pad "T2" smd circle
			(at -5.2 6 180)
			(size 0.45 0.45)
			(layers "F.Cu" "F.Mask" "F.Paste")
			(net 235 "/DDR3/DDR3_DQ4")
			(pinfunction "PB18B/PCLKC4_3\n")
			(pintype "bidirectional")
		)
		(pad "T3" smd circle
			(at -4.4 6 180)
			(size 0.45 0.45)
			(layers "F.Cu" "F.Mask" "F.Paste")
			(net 236 "/DDR3/DDR3_DQ6")
			(pinfunction "PB20A")
			(pintype "bidirectional")
		)
		(pad "T4" smd circle
			(at -3.6 6 180)
			(size 0.45 0.45)
			(layers "F.Cu" "F.Mask" "F.Paste")
			(net 221 "/DDR3/DDR3_DQ0")
			(pinfunction "PB20B")
			(pintype "bidirectional")
		)
		(pad "T5" smd circle
			(at -2.8 6 180)
			(size 0.45 0.45)
			(layers "F.Cu" "F.Mask" "F.Paste")
			(net 225 "/DDR3/DDR3_DQ7")
			(pinfunction "PB26A")
			(pintype "bidirectional")
		)
		(pad "T6" smd circle
			(at -2 6 180)
			(size 0.45 0.45)
			(layers "F.Cu" "F.Mask" "F.Paste")
			(net 233 "/DDR3/DDR3_DQ1")
			(pinfunction "PB28A")
			(pintype "bidirectional")
		)
		(pad "T7" smd circle
			(at -1.2 6 180)
			(size 0.45 0.45)
			(layers "F.Cu" "F.Mask" "F.Paste")
			(net 166 "/DDR3/DDR3_ODT")
			(pinfunction "PB30A")
			(pintype "bidirectional")
		)
		(pad "T8" smd circle
			(at -0.4 6 180)
			(size 0.45 0.45)
			(layers "F.Cu" "F.Mask" "F.Paste")
			(net 161 "/DDR3/~{DDR3_CAS}")
			(pinfunction "PB30B")
			(pintype "bidirectional")
		)
		(pad "T9" smd circle
			(at 0.4 6 180)
			(size 0.45 0.45)
			(layers "F.Cu" "F.Mask" "F.Paste")
			(net 143 "/DDR3/DDR3_CK_P")
			(pinfunction "PB40A/PCLKT4_1")
			(pintype "bidirectional")
		)
		(pad "T10" smd circle
			(at 1.2 6 180)
			(size 0.45 0.45)
			(layers "F.Cu" "F.Mask" "F.Paste")
			(net 142 "/DDR3/DDR3_CK_N")
			(pinfunction "PB40B/PCLKC4_1")
			(pintype "bidirectional")
		)
		(pad "T11" smd circle
			(at 2 6 180)
			(size 0.45 0.45)
			(layers "F.Cu" "F.Mask" "F.Paste")
			(net 231 "/DDR3/DDR3_DQ15")
			(pinfunction "PB58B/PCLKC3_1/ADC_CN6\n")
			(pintype "bidirectional")
		)
		(pad "T12" smd circle
			(at 2.8 6 180)
			(size 0.45 0.45)
			(layers "F.Cu" "F.Mask" "F.Paste")
			(net 238 "/DDR3/DDR3_DQ9")
			(pinfunction "PB58A/PCLKT3_1/ADC_CP6\n")
			(pintype "bidirectional")
		)
		(pad "T13" smd circle
			(at 3.6 6 180)
			(size 0.45 0.45)
			(layers "F.Cu" "F.Mask" "F.Paste")
			(net 239 "/DDR3/DDR3_UDQS_N")
			(pinfunction "PB60B/ADC_CN9")
			(pintype "bidirectional")
		)
		(pad "T14" smd circle
			(at 4.4 6 180)
			(size 0.45 0.45)
			(layers "F.Cu" "F.Mask" "F.Paste")
			(net 230 "/DDR3/DDR3_UDM")
			(pinfunction "PB66A/COMP1IP")
			(pintype "bidirectional")
		)
		(pad "T15" smd circle
			(at 5.2 6 180)
			(size 0.45 0.45)
			(layers "F.Cu" "F.Mask" "F.Paste")
			(net 237 "/DDR3/DDR3_DQ10")
			(pinfunction "PB66B/COMP1IN")
			(pintype "bidirectional")
		)
		(pad "T16" smd circle
			(at 6 6 180)
			(size 0.45 0.45)
			(layers "F.Cu" "F.Mask" "F.Paste")
			(net 1 "GND")
			(pinfunction "VSS")
			(pintype "passive")
		)
	)
	(footprint "antmicro-footprints:R_0805_2012Metric"
		(layer "F.Cu")
		(at 148.78 73.15)
		(property "Reference" "R41"
			(at 1.75 0.39 0)
			(layer "F.SilkS")
			(effects
				(font
					(size 0.65 0.65)
					(thickness 0.15)
				)
				(justify left bottom)
			)
		)
		(property "Value" "R_0R_0805"
			(at 0 1.8 0)
			(layer "F.Fab")
			(hide yes)
			(effects
				(font
					(size 0.7 0.7)
					(thickness 0.15)
				)
				(justify left bottom)
			)
		)
		(property "Datasheet" "https://www.vishay.com/docs/20035/dcrcwe3.pdf"
			(at 0 0 0)
			(layer "F.Fab")
			(hide yes)
			(effects
				(font
					(size 1.27 1.27)
					(thickness 0.15)
				)
			)
		)
		(property "Description" "Zero Ohm Resistor, Jumper, 0805 [2012 Metric], Thick Film, 125 mW, 2.5 A, Surface Mount Device"
			(at 0 0 0)
			(layer "F.Fab")
			(hide yes)
			(effects
				(font
					(size 1.27 1.27)
					(thickness 0.15)
				)
			)
		)
		(property "Author" "Antmicro"
			(at 0 0 0)
			(layer "F.Fab")
			(hide yes)
			(effects
				(font
					(size 1 1)
					(thickness 0.15)
				)
			)
		)
		(property "Current" "2.5A"
			(at 0 0 0)
			(layer "F.Fab")
			(hide yes)
			(effects
				(font
					(size 1 1)
					(thickness 0.15)
				)
			)
		)
		(property "License" "Apache-2.0"
			(at 0 0 0)
			(layer "F.Fab")
			(hide yes)
			(effects
				(font
					(size 1 1)
					(thickness 0.15)
				)
			)
		)
		(property "MPN" "CRCW08050000Z0EA"
			(at 0 0 0)
			(layer "F.Fab")
			(hide yes)
			(effects
				(font
					(size 1 1)
					(thickness 0.15)
				)
			)
		)
		(property "Manufacturer" "Vishay"
			(at 0 0 0)
			(layer "F.Fab")
			(hide yes)
			(effects
				(font
					(size 1 1)
					(thickness 0.15)
				)
			)
		)
		(property "Tolerance" "~"
			(at 0 0 0)
			(layer "F.Fab")
			(hide yes)
			(effects
				(font
					(size 1 1)
					(thickness 0.15)
				)
			)
		)
		(property "Val" "0R"
			(at 0 0 0)
			(layer "F.Fab")
			(hide yes)
			(effects
				(font
					(size 1 1)
					(thickness 0.15)
				)
			)
		)
		(sheetname "/Power Supply/")
		(sheetfile "supply.kicad_sch")
		(attr smd)
		(fp_line
			(start -0.32 0.699)
			(end 0.28 0.699)
			(stroke
				(width 0.15)
				(type solid)
			)
			(layer "F.SilkS")
		)
		(fp_line
			(start -0.3 -0.701)
			(end 0.298 -0.701)
			(stroke
				(width 0.15)
				(type solid)
			)
			(layer "F.SilkS")
		)
		(fp_rect
			(start 1.95 -0.9)
			(end -1.95 0.9)
			(stroke
				(width 0.05)
				(type default)
			)
			(fill no)
			(layer "F.CrtYd")
		)
		(fp_line
			(start -0.951 -0.682)
			(end 0.949 -0.682)
			(stroke
				(width 0.15)
				(type solid)
			)
			(layer "F.Fab")
		)
		(fp_line
			(start -0.951 -0.677)
			(end -0.951 0.675)
			(stroke
				(width 0.15)
				(type solid)
			)
			(layer "F.Fab")
		)
		(fp_line
			(start -0.951 0.68)
			(end 0.949 0.68)
			(stroke
				(width 0.15)
				(type solid)
			)
			(layer "F.Fab")
		)
		(fp_line
			(start 0.949 -0.677)
			(end 0.949 0.675)
			(stroke
				(width 0.15)
				(type solid)
			)
			(layer "F.Fab")
		)
		(fp_text user "Author: Antmicro"
			(at -1.9 4.4 0)
			(layer "F.Fab")
			(effects
				(font
					(size 0.7 0.7)
					(thickness 0.15)
				)
				(justify left bottom)
			)
		)
		(fp_text user "License: Apache-2.0"
			(at -1.9 5.75 0)
			(layer "F.Fab")
			(effects
				(font
					(size 0.7 0.7)
					(thickness 0.15)
				)
				(justify left bottom)
			)
		)
		(fp_text user "${REFERENCE}"
			(at -1.9 3.1 0)
			(layer "F.Fab")
			(effects
				(font
					(size 0.7 0.7)
					(thickness 0.15)
				)
				(justify left bottom)
			)
		)
		(pad "1" smd roundrect
			(at -1.1 0)
			(size 1.2 1.3)
			(layers "F.Cu" "F.Mask" "F.Paste")
			(roundrect_rratio 0.25)
			(net 273 "/Power Supply/1V0_OUT")
			(pintype "passive")
		)
		(pad "2" smd roundrect
			(at 1.1 0)
			(size 1.2 1.3)
			(layers "F.Cu" "F.Mask" "F.Paste")
			(roundrect_rratio 0.25)
			(net 4 "1V0_Power")
			(pintype "passive")
		)
	)
	(footprint "antmicro-footprints:SOT-23-3"
		(layer "F.Cu")
		(at 154.18 65.95 90)
		(property "Reference" "Q3"
			(at -1.8 -1.8 90)
			(layer "F.SilkS")
			(effects
				(font
					(size 0.65 0.65)
					(thickness 0.15)
				)
				(justify left bottom)
			)
		)
		(property "Value" "AO3401A"
			(at -1.9 2.7 90)
			(layer "F.Fab")
			(hide yes)
			(effects
				(font
					(size 0.7 0.7)
					(thickness 0.15)
				)
				(justify left bottom)
			)
		)
		(property "Datasheet" "http://aosmd.com/res/data_sheets/AO3401A.pdf"
			(at 0 0 90)
			(layer "F.Fab")
			(hide yes)
			(effects
				(font
					(size 1.27 1.27)
					(thickness 0.15)
				)
			)
		)
		(property "Description" "Power MOSFET, P Channel, 30 V, 4 A, 0.07 ohm, SOT-23, Surface Mount"
			(at 0 0 90)
			(layer "F.Fab")
			(hide yes)
			(effects
				(font
					(size 1.27 1.27)
					(thickness 0.15)
				)
			)
		)
		(property "Author" "Antmicro"
			(at 220.13 -88.23 0)
			(layer "F.Fab")
			(hide yes)
			(effects
				(font
					(size 1 1)
					(thickness 0.15)
				)
			)
		)
		(property "License" "Apache-2.0"
			(at 220.13 -88.23 0)
			(layer "F.Fab")
			(hide yes)
			(effects
				(font
					(size 1 1)
					(thickness 0.15)
				)
			)
		)
		(property "MPN" "AO3401A"
			(at 220.13 -88.23 0)
			(layer "F.Fab")
			(hide yes)
			(effects
				(font
					(size 1 1)
					(thickness 0.15)
				)
			)
		)
		(property "Manufacturer" "AOSMD"
			(at 220.13 -88.23 0)
			(layer "F.Fab")
			(hide yes)
			(effects
				(font
					(size 1 1)
					(thickness 0.15)
				)
			)
		)
		(sheetname "/Power Supply/")
		(sheetfile "supply.kicad_sch")
		(attr smd)
		(fp_line
			(start 0.7 -1.5)
			(end -0.7 -1.5)
			(stroke
				(width 0.15)
				(type solid)
			)
			(layer "F.SilkS")
		)
		(fp_line
			(start -0.85 -1.35)
			(end -0.7 -1.5)
			(stroke
				(width 0.15)
				(type solid)
			)
			(layer "F.SilkS")
		)
		(fp_line
			(start -1.45 -1.35)
			(end -0.85 -1.35)
			(stroke
				(width 0.15)
				(type solid)
			)
			(layer "F.SilkS")
		)
		(fp_line
			(start 0.7 -0.4)
			(end 0.7 -1.5)
			(stroke
				(width 0.15)
				(type solid)
			)
			(layer "F.SilkS")
		)
		(fp_line
			(start 0.7 0.4)
			(end 0.7 1.5)
			(stroke
				(width 0.15)
				(type solid)
			)
			(layer "F.SilkS")
		)
		(fp_line
			(start 0.7 1.5)
			(end -0.7 1.5)
			(stroke
				(width 0.15)
				(type solid)
			)
			(layer "F.SilkS")
		)
		(fp_line
			(start -0.7 1.5)
			(end -0.7 1.35)
			(stroke
				(width 0.15)
				(type solid)
			)
			(layer "F.SilkS")
		)
		(fp_line
			(start 0.825 -1.6)
			(end 0.825 -0.45)
			(stroke
				(width 0.05)
				(type solid)
			)
			(layer "F.CrtYd")
		)
		(fp_line
			(start -0.9 -1.6)
			(end 0.825 -1.6)
			(stroke
				(width 0.05)
				(type solid)
			)
			(layer "F.CrtYd")
		)
		(fp_line
			(start -0.9 -1.6)
			(end -0.9 -1.4)
			(stroke
				(width 0.05)
				(type solid)
			)
			(layer "F.CrtYd")
		)
		(fp_line
			(start -0.9 -1.4)
			(end -1.75 -1.4)
			(stroke
				(width 0.05)
				(type solid)
			)
			(layer "F.CrtYd")
		)
		(fp_line
			(start -0.85 -0.5)
			(end -1.75 -0.5)
			(stroke
				(width 0.05)
				(type solid)
			)
			(layer "F.CrtYd")
		)
		(fp_line
			(start -1.75 -0.5)
			(end -1.75 -1.4)
			(stroke
				(width 0.05)
				(type solid)
			)
			(layer "F.CrtYd")
		)
		(fp_line
			(start 1.75 -0.45)
			(end 1.75 0.45)
			(stroke
				(width 0.05)
				(type solid)
			)
			(layer "F.CrtYd")
		)
		(fp_line
			(start 0.825 -0.45)
			(end 1.75 -0.45)
			(stroke
				(width 0.05)
				(type solid)
			)
			(layer "F.CrtYd")
		)
		(fp_line
			(start 1.75 0.45)
			(end 0.85 0.45)
			(stroke
				(width 0.05)
				(type solid)
			)
			(layer "F.CrtYd")
		)
		(fp_line
			(start 0.85 0.45)
			(end 0.85 1.65)
			(stroke
				(width 0.05)
				(type solid)
			)
			(layer "F.CrtYd")
		)
		(fp_line
			(start -0.85 0.5)
			(end -0.85 -0.5)
			(stroke
				(width 0.05)
				(type solid)
			)
			(layer "F.CrtYd")
		)
		(fp_line
			(start -1.75 0.5)
			(end -0.85 0.5)
			(stroke
				(width 0.05)
				(type solid)
			)
			(layer "F.CrtYd")
		)
		(fp_line
			(start -0.85 1.4)
			(end -1.75 1.4)
			(stroke
				(width 0.05)
				(type solid)
			)
			(layer "F.CrtYd")
		)
		(fp_line
			(start -1.75 1.4)
			(end -1.75 0.5)
			(stroke
				(width 0.05)
				(type solid)
			)
			(layer "F.CrtYd")
		)
		(fp_line
			(start 0.85 1.65)
			(end -0.85 1.65)
			(stroke
				(width 0.05)
				(type solid)
			)
			(layer "F.CrtYd")
		)
		(fp_line
			(start -0.85 1.65)
			(end -0.85 1.4)
			(stroke
				(width 0.05)
				(type solid)
			)
			(layer "F.CrtYd")
		)
		(fp_line
			(start -0.437 -1.526)
			(end 0.688 -1.526)
			(stroke
				(width 0.15)
				(type solid)
			)
			(layer "F.Fab")
		)
		(fp_line
			(start -0.437 -1.526)
			(end -0.712 -1.325)
			(stroke
				(width 0.15)
				(type solid)
			)
			(layer "F.Fab")
		)
		(fp_line
			(start -0.712 -1.325)
			(end -0.712 1.523)
			(stroke
				(width 0.15)
				(type solid)
			)
			(layer "F.Fab")
		)
		(fp_line
			(start 0.688 1.519)
			(end 0.688 -1.52)
			(stroke
				(width 0.15)
				(type solid)
			)
			(layer "F.Fab")
		)
		(fp_line
			(start -0.712 1.519)
			(end 0.688 1.519)
			(stroke
				(width 0.15)
				(type solid)
			)
			(layer "F.Fab")
		)
		(pad "1" smd roundrect
			(at -1.1 -0.951 90)
			(size 1 0.6)
			(layers "F.Cu" "F.Mask" "F.Paste")
			(roundrect_rratio 0.15)
			(net 260 "Net-(Q3-G)")
			(pinfunction "G")
			(pintype "input")
		)
		(pad "2" smd roundrect
			(at -1.1 0.949 90)
			(size 1 0.6)
			(layers "F.Cu" "F.Mask" "F.Paste")
			(roundrect_rratio 0.15)
			(net 304 "/Power Supply/5V_I")
			(pinfunction "S")
			(pintype "passive")
		)
		(pad "3" smd roundrect
			(at 1.1 -0.0005 90)
			(size 1 0.6)
			(layers "F.Cu" "F.Mask" "F.Paste")
			(roundrect_rratio 0.15)
			(net 325 "USB_POWER_IN")
			(pinfunction "D")
			(pintype "passive")
		)
	)
	(footprint "antmicro-footprints:R_0402_1005Metric"
		(layer "F.Cu")
		(at 108.4 107.2 90)
		(descr "Resistor SMD 0402")
		(tags "resistor SMD 0402")
		(property "Reference" "R141"
			(at -3.84 0.43 90)
			(layer "F.SilkS")
			(effects
				(font
					(size 0.65 0.65)
					(thickness 0.15)
				)
				(justify left bottom)
			)
		)
		(property "Value" "R_0R_0402"
			(at 0 1.4 90)
			(layer "F.Fab")
			(hide yes)
			(effects
				(font
					(size 0.7 0.7)
					(thickness 0.15)
				)
				(justify left bottom)
			)
		)
		(property "Datasheet" "https://industrial.panasonic.com/cdbs/www-data/pdf/RDA0000/AOA0000C301.pdf"
			(at 0 0 90)
			(layer "F.Fab")
			(hide yes)
			(effects
				(font
					(size 1.27 1.27)
					(thickness 0.15)
				)
			)
		)
		(property "Description" "SMD Chip Resistor, Jumper, 0 ohm, 100 mW, 0402 [1005 Metric], Thick Film, General Purpose"
			(at 0 0 90)
			(layer "F.Fab")
			(hide yes)
			(effects
				(font
					(size 1.27 1.27)
					(thickness 0.15)
				)
			)
		)
		(property "Author" "Antmicro"
			(at 215.6 -1.2 0)
			(layer "F.Fab")
			(hide yes)
			(effects
				(font
					(size 1 1)
					(thickness 0.15)
				)
			)
		)
		(property "Current" "1A"
			(at 215.6 -1.2 0)
			(layer "F.Fab")
			(hide yes)
			(effects
				(font
					(size 1 1)
					(thickness 0.15)
				)
			)
		)
		(property "License" "Apache-2.0"
			(at 215.6 -1.2 0)
			(layer "F.Fab")
			(hide yes)
			(effects
				(font
					(size 1 1)
					(thickness 0.15)
				)
			)
		)
		(property "MPN" "ERJ2GE0R00X"
			(at 215.6 -1.2 0)
			(layer "F.Fab")
			(hide yes)
			(effects
				(font
					(size 1 1)
					(thickness 0.15)
				)
			)
		)
		(property "Manufacturer" "Panasonic"
			(at 215.6 -1.2 0)
			(layer "F.Fab")
			(hide yes)
			(effects
				(font
					(size 1 1)
					(thickness 0.15)
				)
			)
		)
		(property "Tolerance" "~"
			(at 215.6 -1.2 0)
			(layer "F.Fab")
			(hide yes)
			(effects
				(font
					(size 1 1)
					(thickness 0.15)
				)
			)
		)
		(property "Val" "0R"
			(at 215.6 -1.2 0)
			(layer "F.Fab")
			(hide yes)
			(effects
				(font
					(size 1 1)
					(thickness 0.15)
				)
			)
		)
		(sheetname "/FPGA/")
		(sheetfile "fpga.kicad_sch")
		(attr smd)
		(fp_rect
			(start -0.925 -0.47)
			(end 0.925 0.47)
			(stroke
				(width 0.05)
				(type default)
			)
			(fill no)
			(layer "F.CrtYd")
		)
		(fp_rect
			(start -0.5 -0.25)
			(end 0.5 0.25)
			(stroke
				(width 0.15)
				(type solid)
			)
			(fill no)
			(layer "F.Fab")
		)
		(fp_text user "Author: Antmicro"
			(at -0.95 4.169 90)
			(layer "F.Fab")
			(effects
				(font
					(size 0.7 0.7)
					(thickness 0.15)
				)
				(justify left bottom)
			)
		)
		(fp_text user "${REFERENCE}"
			(at -0.95 3.168 90)
			(layer "F.Fab")
			(effects
				(font
					(size 0.7 0.7)
					(thickness 0.15)
				)
				(justify left bottom)
			)
		)
		(fp_text user "License: Apache-2.0"
			(at -0.95 5.169 90)
			(layer "F.Fab")
			(effects
				(font
					(size 0.7 0.7)
					(thickness 0.15)
				)
				(justify left bottom)
			)
		)
		(pad "1" smd roundrect
			(at -0.48 0 90)
			(size 0.59 0.64)
			(layers "F.Cu" "F.Mask" "F.Paste")
			(roundrect_rratio 0.25)
			(net 363 "/FPGA/DONE_SOFT")
			(pintype "passive")
		)
		(pad "2" smd roundrect
			(at 0.48 0 90)
			(size 0.59 0.64)
			(layers "F.Cu" "F.Mask" "F.Paste")
			(roundrect_rratio 0.25)
			(net 358 "Net-(U17-GPIO2{slash}~{SS2})")
			(pintype "passive")
		)
	)
	(footprint "antmicro-footprints:TP_SMD_0.75mm"
		(layer "F.Cu")
		(at 106.3492 99.7 -90)
		(property "Reference" "TP18"
			(at -0.31 2.8892 0)
			(layer "F.SilkS")
			(effects
				(font
					(size 0.65 0.65)
					(thickness 0.15)
				)
				(justify left top)
			)
		)
		(property "Value" "TP_0.75mm_SMD"
			(at 0 1.2 90)
			(layer "F.Fab")
			(hide yes)
			(effects
				(font
					(size 0.7 0.7)
					(thickness 0.15)
				)
				(justify right bottom)
			)
		)
		(property "Description" "SMT test point"
			(at 0 0 90)
			(layer "F.Fab")
			(hide yes)
			(effects
				(font
					(size 1.27 1.27)
					(thickness 0.15)
				)
			)
		)
		(property "Author" "Antmicro"
			(at 6.6492 206.0492 0)
			(layer "F.Fab")
			(hide yes)
			(effects
				(font
					(size 1 1)
					(thickness 0.15)
				)
			)
		)
		(property "License" "Apache-2.0"
			(at 6.6492 206.0492 0)
			(layer "F.Fab")
			(hide yes)
			(effects
				(font
					(size 1 1)
					(thickness 0.15)
				)
			)
		)
		(property "MPN" ""
			(at 6.6492 206.0492 0)
			(layer "F.Fab")
			(hide yes)
			(effects
				(font
					(size 1 1)
					(thickness 0.15)
				)
			)
		)
		(property "Manufacturer" ""
			(at 6.6492 206.0492 0)
			(layer "F.Fab")
			(hide yes)
			(effects
				(font
					(size 1 1)
					(thickness 0.15)
				)
			)
		)
		(sheetname "/FPGA/")
		(sheetfile "fpga.kicad_sch")
		(attr exclude_from_pos_files)
		(fp_circle
			(center 0 0)
			(end 0.475 0)
			(stroke
				(width 0.05)
				(type default)
			)
			(fill no)
			(layer "F.CrtYd")
		)
		(fp_text user "License: Apache-2.0"
			(at -0.4 5.101 90)
			(layer "F.Fab")
			(effects
				(font
					(size 0.7 0.7)
					(thickness 0.15)
				)
				(justify right top)
			)
		)
		(fp_text user "${REFERENCE}"
			(at -0.4 2.7 90)
			(layer "F.Fab")
			(effects
				(font
					(size 0.7 0.7)
					(thickness 0.15)
				)
				(justify right top)
			)
		)
		(fp_text user "Author: Antmicro"
			(at -0.4 3.901 90)
			(layer "F.Fab")
			(effects
				(font
					(size 0.7 0.7)
					(thickness 0.15)
				)
				(justify right top)
			)
		)
		(pad "1" smd circle
			(at 0 0 270)
			(size 0.75 0.75)
			(layers "F.Cu" "F.Mask")
			(net 27 "/FPGA/SPI_DQ3")
			(pinfunction "1")
			(pintype "passive")
		)
	)
	(footprint "antmicro-footprints:TP_SMD_0.75mm"
		(layer "F.Cu")
		(at 146.54 56.6508)
		(property "Reference" "TP11"
			(at -0.11 -0.5108 0)
			(layer "F.SilkS")
			(effects
				(font
					(size 0.65 0.65)
					(thickness 0.15)
				)
				(justify left bottom)
			)
		)
		(property "Value" "TP_0.75mm_SMD"
			(at 0 1.2 0)
			(layer "F.Fab")
			(hide yes)
			(effects
				(font
					(size 0.7 0.7)
					(thickness 0.15)
				)
				(justify left bottom)
			)
		)
		(property "Description" "SMT test point"
			(at 0 0 0)
			(layer "F.Fab")
			(hide yes)
			(effects
				(font
					(size 1.27 1.27)
					(thickness 0.15)
				)
			)
		)
		(property "Author" "Antmicro"
			(at 0 0 0)
			(layer "F.Fab")
			(hide yes)
			(effects
				(font
					(size 1 1)
					(thickness 0.15)
				)
			)
		)
		(property "License" "Apache-2.0"
			(at 0 0 0)
			(layer "F.Fab")
			(hide yes)
			(effects
				(font
					(size 1 1)
					(thickness 0.15)
				)
			)
		)
		(property "MPN" ""
			(at 0 0 0)
			(layer "F.Fab")
			(hide yes)
			(effects
				(font
					(size 1 1)
					(thickness 0.15)
				)
			)
		)
		(property "Manufacturer" ""
			(at 0 0 0)
			(layer "F.Fab")
			(hide yes)
			(effects
				(font
					(size 1 1)
					(thickness 0.15)
				)
			)
		)
		(sheetname "/Power Supply/")
		(sheetfile "supply.kicad_sch")
		(attr exclude_from_pos_files)
		(fp_circle
			(center 0 0)
			(end 0.475 0)
			(stroke
				(width 0.05)
				(type default)
			)
			(fill no)
			(layer "F.CrtYd")
		)
		(fp_text user "${REFERENCE}"
			(at -0.4 2.7 0)
			(layer "F.Fab")
			(effects
				(font
					(size 0.7 0.7)
					(thickness 0.15)
				)
				(justify left bottom)
			)
		)
		(fp_text user "Author: Antmicro"
			(at -0.4 3.901 0)
			(layer "F.Fab")
			(effects
				(font
					(size 0.7 0.7)
					(thickness 0.15)
				)
				(justify left bottom)
			)
		)
		(fp_text user "License: Apache-2.0"
			(at -0.4 5.101 0)
			(layer "F.Fab")
			(effects
				(font
					(size 0.7 0.7)
					(thickness 0.15)
				)
				(justify left bottom)
			)
		)
		(pad "1" smd circle
			(at 0 0)
			(size 0.75 0.75)
			(layers "F.Cu" "F.Mask")
			(net 374 "Net-(U6-EN)")
			(pinfunction "1")
			(pintype "passive")
		)
	)
	(footprint "antmicro-footprints:L_Coilcraft-XEL4030"
		(layer "F.Cu")
		(at 143.08 73.3)
		(property "Reference" "L1"
			(at -3.85 0.14 0)
			(layer "F.SilkS")
			(effects
				(font
					(size 0.65 0.65)
					(thickness 0.15)
				)
				(justify left bottom)
			)
		)
		(property "Value" "L_3u3_5.9A_XEL4030"
			(at 0 3.35 0)
			(layer "F.Fab")
			(hide yes)
			(effects
				(font
					(size 0.7 0.7)
					(thickness 0.15)
				)
				(justify left bottom)
			)
		)
		(property "Datasheet" "https://www.coilcraft.com/getmedia/8245f050-f190-4295-8c41-7c03d662ee3d/xel4030.pdf"
			(at 0 0 0)
			(layer "F.Fab")
			(hide yes)
			(effects
				(font
					(size 1.27 1.27)
					(thickness 0.15)
				)
			)
		)
		(property "Description" "Power Inductor (SMT), AEC-Q200, 3.3 µH, 6.6 A, Shielded, 5.9 A, XEL4030"
			(at 0 0 0)
			(layer "F.Fab")
			(hide yes)
			(effects
				(font
					(size 1.27 1.27)
					(thickness 0.15)
				)
			)
		)
		(property "Author" "Antmicro"
			(at 0 0 0)
			(layer "F.Fab")
			(hide yes)
			(effects
				(font
					(size 1 1)
					(thickness 0.15)
				)
			)
		)
		(property "IMax" "6.6 A"
			(at 0 0 0)
			(layer "F.Fab")
			(hide yes)
			(effects
				(font
					(size 1 1)
					(thickness 0.15)
				)
			)
		)
		(property "ISat" "5.9 A"
			(at 0 0 0)
			(layer "F.Fab")
			(hide yes)
			(effects
				(font
					(size 1 1)
					(thickness 0.15)
				)
			)
		)
		(property "License" "Apache-2.0"
			(at 0 0 0)
			(layer "F.Fab")
			(hide yes)
			(effects
				(font
					(size 1 1)
					(thickness 0.15)
				)
			)
		)
		(property "MPN" "XEL4030-332MEC"
			(at 0 0 0)
			(layer "F.Fab")
			(hide yes)
			(effects
				(font
					(size 1 1)
					(thickness 0.15)
				)
			)
		)
		(property "Manufacturer" "Coilcraft"
			(at 0 0 0)
			(layer "F.Fab")
			(hide yes)
			(effects
				(font
					(size 1 1)
					(thickness 0.15)
				)
			)
		)
		(property "Size" "4.0x4.0"
			(at 0 0 0)
			(layer "F.Fab")
			(hide yes)
			(effects
				(font
					(size 1 1)
					(thickness 0.15)
				)
			)
		)
		(property "Val" "3u3/6.6A"
			(at 0 0 0)
			(layer "F.Fab")
			(hide yes)
			(effects
				(font
					(size 1 1)
					(thickness 0.15)
				)
			)
		)
		(sheetname "/Power Supply/")
		(sheetfile "supply.kicad_sch")
		(attr smd)
		(fp_line
			(start -2.2 -2.2)
			(end 2.2 -2.2)
			(stroke
				(width 0.15)
				(type solid)
			)
			(layer "F.SilkS")
		)
		(fp_line
			(start -2.2 2.2)
			(end -2.2 -2.2)
			(stroke
				(width 0.15)
				(type solid)
			)
			(layer "F.SilkS")
		)
		(fp_line
			(start -2.2 2.2)
			(end 2.2 2.2)
			(stroke
				(width 0.15)
				(type solid)
			)
			(layer "F.SilkS")
		)
		(fp_line
			(start 2.2 2.2)
			(end 2.2 -2.2)
			(stroke
				(width 0.15)
				(type solid)
			)
			(layer "F.SilkS")
		)
		(fp_rect
			(start -2.4 -2.4)
			(end 2.4 2.4)
			(stroke
				(width 0.05)
				(type solid)
			)
			(fill no)
			(layer "F.CrtYd")
		)
		(fp_rect
			(start -2.15 -2.15)
			(end 2.15 2.15)
			(stroke
				(width 0.15)
				(type solid)
			)
			(fill no)
			(layer "F.Fab")
		)
		(fp_text user "${REFERENCE}"
			(at -2.4 6.55 0)
			(layer "F.Fab")
			(effects
				(font
					(size 0.7 0.7)
					(thickness 0.15)
				)
				(justify left bottom)
			)
		)
		(fp_text user "License: Apache-2.0"
			(at -2.4 7.75 0)
			(layer "F.Fab")
			(effects
				(font
					(size 0.7 0.7)
					(thickness 0.15)
				)
				(justify left bottom)
			)
		)
		(fp_text user "Author: Antmicro"
			(at -2.4 5.35 0)
			(layer "F.Fab")
			(effects
				(font
					(size 0.7 0.7)
					(thickness 0.15)
				)
				(justify left bottom)
			)
		)
		(pad "1" smd roundrect
			(at -1.185 0)
			(size 0.98 3.4)
			(layers "F.Cu" "F.Mask" "F.Paste")
			(roundrect_rratio 0.1)
			(net 276 "/Power Supply/1V0_SW")
			(pintype "passive")
		)
		(pad "2" smd roundrect
			(at 1.185 0)
			(size 0.98 3.4)
			(layers "F.Cu" "F.Mask" "F.Paste")
			(roundrect_rratio 0.1)
			(net 273 "/Power Supply/1V0_OUT")
			(pintype "passive")
		)
	)
	(footprint "antmicro-footprints:C_0603_1608Metric"
		(layer "F.Cu")
		(at 140.84 64.8 90)
		(descr "Capacitor SMD 0603")
		(tags "capacitor 0603")
		(property "Reference" "C33"
			(at -0.84 -5.01 90)
			(layer "F.SilkS")
			(effects
				(font
					(size 0.65 0.65)
					(thickness 0.15)
				)
				(justify left bottom)
			)
		)
		(property "Value" "C_22u_0603"
			(at 0 1.6 90)
			(layer "F.Fab")
			(hide yes)
			(effects
				(font
					(size 0.7 0.7)
					(thickness 0.15)
				)
				(justify left bottom)
			)
		)
		(property "Datasheet" "https://www.murata.com/products/productdetail?partno=GRM188R60J226MEA0%23"
			(at 0 0 90)
			(layer "F.Fab")
			(hide yes)
			(effects
				(font
					(size 1.27 1.27)
					(thickness 0.15)
				)
			)
		)
		(property "Description" "SMD Multilayer Ceramic Capacitor, 22 µF, 6.3 V, 0603 [1608 Metric], ± 20%, X5R, GRM Series"
			(at 0 0 90)
			(layer "F.Fab")
			(hide yes)
			(effects
				(font
					(size 1.27 1.27)
					(thickness 0.15)
				)
			)
		)
		(property "Author" "Antmicro"
			(at 205.64 -76.04 0)
			(layer "F.Fab")
			(hide yes)
			(effects
				(font
					(size 1 1)
					(thickness 0.15)
				)
			)
		)
		(property "Dielectric" ""
			(at 205.64 -76.04 0)
			(layer "F.Fab")
			(hide yes)
			(effects
				(font
					(size 1 1)
					(thickness 0.15)
				)
			)
		)
		(property "License" "Apache-2.0"
			(at 205.64 -76.04 0)
			(layer "F.Fab")
			(hide yes)
			(effects
				(font
					(size 1 1)
					(thickness 0.15)
				)
			)
		)
		(property "MPN" "GRM188R60J226MEA0D"
			(at 205.64 -76.04 0)
			(layer "F.Fab")
			(hide yes)
			(effects
				(font
					(size 1 1)
					(thickness 0.15)
				)
			)
		)
		(property "Manufacturer" "Murata"
			(at 205.64 -76.04 0)
			(layer "F.Fab")
			(hide yes)
			(effects
				(font
					(size 1 1)
					(thickness 0.15)
				)
			)
		)
		(property "Val" "22u"
			(at 205.64 -76.04 0)
			(layer "F.Fab")
			(hide yes)
			(effects
				(font
					(size 1 1)
					(thickness 0.15)
				)
			)
		)
		(property "Voltage" ""
			(at 205.64 -76.04 0)
			(layer "F.Fab")
			(hide yes)
			(effects
				(font
					(size 1 1)
					(thickness 0.15)
				)
			)
		)
		(sheetname "/Power Supply/")
		(sheetfile "supply.kicad_sch")
		(attr smd)
		(fp_line
			(start -0.15 -0.4)
			(end 0.15 -0.4)
			(stroke
				(width 0.15)
				(type solid)
			)
			(layer "F.SilkS")
		)
		(fp_line
			(start -0.15 0.4)
			(end 0.15 0.4)
			(stroke
				(width 0.15)
				(type solid)
			)
			(layer "F.SilkS")
		)
		(fp_rect
			(start -1.25 -0.65)
			(end 1.25 0.65)
			(stroke
				(width 0.05)
				(type solid)
			)
			(fill no)
			(layer "F.CrtYd")
		)
		(fp_rect
			(start -0.8 -0.4)
			(end 0.8 0.4)
			(stroke
				(width 0.15)
				(type solid)
			)
			(fill no)
			(layer "F.Fab")
		)
		(fp_text user "License: Apache-2.0"
			(at -1.682 5.895 90)
			(layer "F.Fab")
			(effects
				(font
					(size 0.7 0.7)
					(thickness 0.15)
				)
				(justify left bottom)
			)
		)
		(fp_text user "Author: Antmicro"
			(at -1.682 4.894 90)
			(layer "F.Fab")
			(effects
				(font
					(size 0.7 0.7)
					(thickness 0.15)
				)
				(justify left bottom)
			)
		)
		(fp_text user "${REFERENCE}"
			(at -1.682 3.895 90)
			(layer "F.Fab")
			(effects
				(font
					(size 0.7 0.7)
					(thickness 0.15)
				)
				(justify left bottom)
			)
		)
		(pad "1" smd roundrect
			(at -0.7 0 90)
			(size 0.8 1)
			(layers "F.Cu" "F.Mask" "F.Paste")
			(roundrect_rratio 0.2)
			(net 1 "GND")
			(pintype "passive")
		)
		(pad "2" smd roundrect
			(at 0.7 0 90)
			(size 0.8 1)
			(layers "F.Cu" "F.Mask" "F.Paste")
			(roundrect_rratio 0.2)
			(net 274 "/Power Supply/1V5_OUT")
			(pintype "passive")
		)
	)
	(footprint "antmicro-footprints:R_0603_1608Metric"
		(layer "F.Cu")
		(at 164.29 76.6)
		(descr "Resistor SMD 0603")
		(tags "resistor SMD 0603")
		(property "Reference" "R118"
			(at -1.26 -0.76 0)
			(layer "F.SilkS")
			(effects
				(font
					(size 0.65 0.65)
					(thickness 0.15)
				)
				(justify left bottom)
			)
		)
		(property "Value" "R_15k_0603"
			(at 0 1.6 0)
			(layer "F.Fab")
			(hide yes)
			(effects
				(font
					(size 0.7 0.7)
					(thickness 0.15)
				)
				(justify left bottom)
			)
		)
		(property "Datasheet" "https://www.bourns.com/docs/product-datasheets/cr.pdf"
			(at 0 0 0)
			(layer "F.Fab")
			(hide yes)
			(effects
				(font
					(size 1.27 1.27)
					(thickness 0.15)
				)
			)
		)
		(property "Description" "SMD Chip Resistor, 15 kohm, ± 1%, 100 mW, 0603 [1608 Metric], Thick Film, General Purpose"
			(at 0 0 0)
			(layer "F.Fab")
			(hide yes)
			(effects
				(font
					(size 1.27 1.27)
					(thickness 0.15)
				)
			)
		)
		(property "Author" "Antmicro"
			(at 0 0 0)
			(layer "F.Fab")
			(hide yes)
			(effects
				(font
					(size 1 1)
					(thickness 0.15)
				)
			)
		)
		(property "License" "Apache-2.0"
			(at 0 0 0)
			(layer "F.Fab")
			(hide yes)
			(effects
				(font
					(size 1 1)
					(thickness 0.15)
				)
			)
		)
		(property "MPN" "CR0603-FX-1502ELF"
			(at 0 0 0)
			(layer "F.Fab")
			(hide yes)
			(effects
				(font
					(size 1 1)
					(thickness 0.15)
				)
			)
		)
		(property "Manufacturer" "Bourns"
			(at 0 0 0)
			(layer "F.Fab")
			(hide yes)
			(effects
				(font
					(size 1 1)
					(thickness 0.15)
				)
			)
		)
		(property "Tolerance" "1%"
			(at 0 0 0)
			(layer "F.Fab")
			(hide yes)
			(effects
				(font
					(size 1 1)
					(thickness 0.15)
				)
			)
		)
		(property "Val" "15k"
			(at 0 0 0)
			(layer "F.Fab")
			(hide yes)
			(effects
				(font
					(size 1 1)
					(thickness 0.15)
				)
			)
		)
		(sheetname "/Peripherals/")
		(sheetfile "peripherals.kicad_sch")
		(attr smd)
		(fp_line
			(start -0.15 -0.4)
			(end 0.15 -0.4)
			(stroke
				(width 0.15)
				(type solid)
			)
			(layer "F.SilkS")
		)
		(fp_line
			(start -0.15 0.4)
			(end 0.15 0.4)
			(stroke
				(width 0.15)
				(type solid)
			)
			(layer "F.SilkS")
		)
		(fp_rect
			(start -1.25 -0.65)
			(end 1.25 0.65)
			(stroke
				(width 0.05)
				(type solid)
			)
			(fill no)
			(layer "F.CrtYd")
		)
		(fp_rect
			(start -0.8 -0.4)
			(end 0.8 0.4)
			(stroke
				(width 0.15)
				(type solid)
			)
			(fill no)
			(layer "F.Fab")
		)
		(fp_text user "${REFERENCE}"
			(at -1.25 3.898 0)
			(layer "F.Fab")
			(effects
				(font
					(size 0.7 0.7)
					(thickness 0.15)
				)
				(justify left bottom)
			)
		)
		(fp_text user "Author: Antmicro"
			(at -1.25 4.9 0)
			(layer "F.Fab")
			(effects
				(font
					(size 0.7 0.7)
					(thickness 0.15)
				)
				(justify left bottom)
			)
		)
		(fp_text user "License: Apache-2.0"
			(at -1.25 5.9 0)
			(layer "F.Fab")
			(effects
				(font
					(size 0.7 0.7)
					(thickness 0.15)
				)
				(justify left bottom)
			)
		)
		(pad "1" smd roundrect
			(at -0.7 0)
			(size 0.8 1)
			(layers "F.Cu" "F.Mask" "F.Paste")
			(roundrect_rratio 0.2)
			(net 1 "GND")
			(pintype "passive")
		)
		(pad "2" smd roundrect
			(at 0.7 0)
			(size 0.8 1)
			(layers "F.Cu" "F.Mask" "F.Paste")
			(roundrect_rratio 0.2)
			(net 356 "Net-(U19-ILIM)")
			(pintype "passive")
		)
	)
	(footprint "antmicro-footprints:TP_SMD_0.75mm"
		(layer "F.Cu")
		(at 136.29 114.3 90)
		(property "Reference" "TP8"
			(at -2.64 0.34 90)
			(layer "F.SilkS")
			(effects
				(font
					(size 0.65 0.65)
					(thickness 0.15)
				)
				(justify left bottom)
			)
		)
		(property "Value" "TP_0.75mm_SMD"
			(at 0 1.2 90)
			(layer "F.Fab")
			(hide yes)
			(effects
				(font
					(size 0.7 0.7)
					(thickness 0.15)
				)
				(justify left bottom)
			)
		)
		(property "Description" "SMT test point"
			(at 0 0 90)
			(layer "F.Fab")
			(hide yes)
			(effects
				(font
					(size 1.27 1.27)
					(thickness 0.15)
				)
			)
		)
		(property "Author" "Antmicro"
			(at 250.59 -21.99 0)
			(layer "F.Fab")
			(hide yes)
			(effects
				(font
					(size 1 1)
					(thickness 0.15)
				)
			)
		)
		(property "License" "Apache-2.0"
			(at 250.59 -21.99 0)
			(layer "F.Fab")
			(hide yes)
			(effects
				(font
					(size 1 1)
					(thickness 0.15)
				)
			)
		)
		(property "MPN" ""
			(at 250.59 -21.99 0)
			(layer "F.Fab")
			(hide yes)
			(effects
				(font
					(size 1 1)
					(thickness 0.15)
				)
			)
		)
		(property "Manufacturer" ""
			(at 250.59 -21.99 0)
			(layer "F.Fab")
			(hide yes)
			(effects
				(font
					(size 1 1)
					(thickness 0.15)
				)
			)
		)
		(sheetname "/Power Supply/")
		(sheetfile "supply.kicad_sch")
		(attr exclude_from_pos_files)
		(fp_circle
			(center 0 0)
			(end 0.475 0)
			(stroke
				(width 0.05)
				(type default)
			)
			(fill no)
			(layer "F.CrtYd")
		)
		(fp_text user "License: Apache-2.0"
			(at -0.4 5.101 90)
			(layer "F.Fab")
			(effects
				(font
					(size 0.7 0.7)
					(thickness 0.15)
				)
				(justify left bottom)
			)
		)
		(fp_text user "Author: Antmicro"
			(at -0.4 3.901 90)
			(layer "F.Fab")
			(effects
				(font
					(size 0.7 0.7)
					(thickness 0.15)
				)
				(justify left bottom)
			)
		)
		(fp_text user "${REFERENCE}"
			(at -0.4 2.7 90)
			(layer "F.Fab")
			(effects
				(font
					(size 0.7 0.7)
					(thickness 0.15)
				)
				(justify left bottom)
			)
		)
		(pad "1" smd circle
			(at 0 0 90)
			(size 0.75 0.75)
			(layers "F.Cu" "F.Mask")
			(net 3 "+1V2")
			(pinfunction "1")
			(pintype "passive")
		)
	)
	(footprint "antmicro-footprints:R_0402_1005Metric"
		(layer "F.Cu")
		(at 145.84 114.95 90)
		(descr "Resistor SMD 0402")
		(tags "resistor SMD 0402")
		(property "Reference" "R25"
			(at -0.99 2.79 270)
			(layer "F.SilkS")
			(effects
				(font
					(size 0.65 0.65)
					(thickness 0.15)
				)
				(justify left bottom)
			)
		)
		(property "Value" "R_0R_0402"
			(at 0 1.4 90)
			(layer "F.Fab")
			(hide yes)
			(effects
				(font
					(size 0.7 0.7)
					(thickness 0.15)
				)
				(justify left bottom)
			)
		)
		(property "Datasheet" "https://industrial.panasonic.com/cdbs/www-data/pdf/RDA0000/AOA0000C301.pdf"
			(at 0 0 90)
			(layer "F.Fab")
			(hide yes)
			(effects
				(font
					(size 1.27 1.27)
					(thickness 0.15)
				)
			)
		)
		(property "Description" "SMD Chip Resistor, Jumper, 0 ohm, 100 mW, 0402 [1005 Metric], Thick Film, General Purpose"
			(at 0 0 90)
			(layer "F.Fab")
			(hide yes)
			(effects
				(font
					(size 1.27 1.27)
					(thickness 0.15)
				)
			)
		)
		(property "Author" "Antmicro"
			(at 260.79 -30.89 0)
			(layer "F.Fab")
			(hide yes)
			(effects
				(font
					(size 1 1)
					(thickness 0.15)
				)
			)
		)
		(property "Current" "1A"
			(at 260.79 -30.89 0)
			(layer "F.Fab")
			(hide yes)
			(effects
				(font
					(size 1 1)
					(thickness 0.15)
				)
			)
		)
		(property "License" "Apache-2.0"
			(at 260.79 -30.89 0)
			(layer "F.Fab")
			(hide yes)
			(effects
				(font
					(size 1 1)
					(thickness 0.15)
				)
			)
		)
		(property "MPN" "ERJ2GE0R00X"
			(at 260.79 -30.89 0)
			(layer "F.Fab")
			(hide yes)
			(effects
				(font
					(size 1 1)
					(thickness 0.15)
				)
			)
		)
		(property "Manufacturer" "Panasonic"
			(at 260.79 -30.89 0)
			(layer "F.Fab")
			(hide yes)
			(effects
				(font
					(size 1 1)
					(thickness 0.15)
				)
			)
		)
		(property "Tolerance" "~"
			(at 260.79 -30.89 0)
			(layer "F.Fab")
			(hide yes)
			(effects
				(font
					(size 1 1)
					(thickness 0.15)
				)
			)
		)
		(property "Val" "0R"
			(at 260.79 -30.89 0)
			(layer "F.Fab")
			(hide yes)
			(effects
				(font
					(size 1 1)
					(thickness 0.15)
				)
			)
		)
		(sheetname "/Power Supply/")
		(sheetfile "supply.kicad_sch")
		(attr smd)
		(fp_rect
			(start -0.925 -0.47)
			(end 0.925 0.47)
			(stroke
				(width 0.05)
				(type default)
			)
			(fill no)
			(layer "F.CrtYd")
		)
		(fp_rect
			(start -0.5 -0.25)
			(end 0.5 0.25)
			(stroke
				(width 0.15)
				(type solid)
			)
			(fill no)
			(layer "F.Fab")
		)
		(fp_text user "${REFERENCE}"
			(at -0.95 3.168 90)
			(layer "F.Fab")
			(effects
				(font
					(size 0.7 0.7)
					(thickness 0.15)
				)
				(justify left bottom)
			)
		)
		(fp_text user "License: Apache-2.0"
			(at -0.95 5.169 90)
			(layer "F.Fab")
			(effects
				(font
					(size 0.7 0.7)
					(thickness 0.15)
				)
				(justify left bottom)
			)
		)
		(fp_text user "Author: Antmicro"
			(at -0.95 4.169 90)
			(layer "F.Fab")
			(effects
				(font
					(size 0.7 0.7)
					(thickness 0.15)
				)
				(justify left bottom)
			)
		)
		(pad "1" smd roundrect
			(at -0.48 0 90)
			(size 0.59 0.64)
			(layers "F.Cu" "F.Mask" "F.Paste")
			(roundrect_rratio 0.25)
			(net 265 "Net-(U9-V_{IN})")
			(pintype "passive")
		)
		(pad "2" smd roundrect
			(at 0.48 0 90)
			(size 0.59 0.64)
			(layers "F.Cu" "F.Mask" "F.Paste")
			(roundrect_rratio 0.25)
			(net 269 "Net-(U9-EN)")
			(pintype "passive")
		)
	)
	(footprint "antmicro-footprints:LED_0603_1608Metric_G"
		(layer "F.Cu")
		(at 172.63 82.55 180)
		(descr "LED SMD 0603 Green")
		(tags "LED SMD 0603 Green")
		(property "Reference" "D10"
			(at -1.4 1.01 90)
			(layer "F.SilkS")
			(effects
				(font
					(size 0.65 0.65)
					(thickness 0.15)
				)
				(justify right top)
			)
		)
		(property "Value" "LED_G_0603_LTST-C190GKT"
			(at 0 1.6 0)
			(layer "F.Fab")
			(hide yes)
			(effects
				(font
					(size 0.7 0.7)
					(thickness 0.15)
				)
				(justify right top)
			)
		)
		(property "Datasheet" "https://media.digikey.com/pdf/Data%20Sheets/Lite-On%20PDFs/LTST-C190GKT.pdf"
			(at 0 0 0)
			(layer "F.Fab")
			(hide yes)
			(effects
				(font
					(size 1.27 1.27)
					(thickness 0.15)
				)
			)
		)
		(property "Description" "LED, Green, SMD, 0603, 20 mA, 2.1 V, 569 nm"
			(at 0 0 0)
			(layer "F.Fab")
			(hide yes)
			(effects
				(font
					(size 1.27 1.27)
					(thickness 0.15)
				)
			)
		)
		(property "Author" "Antmicro"
			(at 0 0 0)
			(layer "F.Fab")
			(hide yes)
			(effects
				(font
					(size 1 1)
					(thickness 0.15)
				)
			)
		)
		(property "License" "Apache-2.0"
			(at 0 0 0)
			(layer "F.Fab")
			(hide yes)
			(effects
				(font
					(size 1 1)
					(thickness 0.15)
				)
			)
		)
		(property "MPN" "LTST-C190GKT"
			(at 0 0 0)
			(layer "F.Fab")
			(hide yes)
			(effects
				(font
					(size 1 1)
					(thickness 0.15)
				)
			)
		)
		(property "Manufacturer" "Lite-On"
			(at 0 0 0)
			(layer "F.Fab")
			(hide yes)
			(effects
				(font
					(size 1 1)
					(thickness 0.15)
				)
			)
		)
		(property "Color" "Green"
			(at 0 0 180)
			(unlocked yes)
			(layer "F.Fab")
			(hide yes)
			(effects
				(font
					(size 1 1)
					(thickness 0.15)
				)
			)
		)
		(sheetname "/Peripherals/")
		(sheetfile "peripherals.kicad_sch")
		(attr smd)
		(fp_line
			(start 0.22 0.35)
			(end -0.22 0.35)
			(stroke
				(width 0.15)
				(type solid)
			)
			(layer "F.SilkS")
		)
		(fp_line
			(start 0.22 -0.35)
			(end -0.22 -0.35)
			(stroke
				(width 0.15)
				(type solid)
			)
			(layer "F.SilkS")
		)
		(fp_line
			(start 0.105328 0.201008)
			(end 0.105328 -0.198992)
			(stroke
				(width 0.1)
				(type solid)
			)
			(layer "F.SilkS")
		)
		(fp_line
			(start 0.105328 0.201008)
			(end -0.094672 0.001008)
			(stroke
				(width 0.1)
				(type solid)
			)
			(layer "F.SilkS")
		)
		(fp_line
			(start 0.105328 0.001008)
			(end 0.24 0.001)
			(stroke
				(width 0.1)
				(type solid)
			)
			(layer "F.SilkS")
		)
		(fp_line
			(start -0.094672 0.201008)
			(end -0.094672 -0.198992)
			(stroke
				(width 0.1)
				(type solid)
			)
			(layer "F.SilkS")
		)
		(fp_line
			(start -0.094672 0.001008)
			(end 0.105328 -0.198992)
			(stroke
				(width 0.1)
				(type solid)
			)
			(layer "F.SilkS")
		)
		(fp_line
			(start -0.094672 0.001008)
			(end -0.24 0.001008)
			(stroke
				(width 0.1)
				(type solid)
			)
			(layer "F.SilkS")
		)
		(fp_line
			(start -1.18 -0.319)
			(end -1.18 0.321)
			(stroke
				(width 0.15)
				(type solid)
			)
			(layer "F.SilkS")
		)
		(fp_rect
			(start 1.25 0.65)
			(end -1.25 -0.65)
			(stroke
				(width 0.05)
				(type solid)
			)
			(fill no)
			(layer "F.CrtYd")
		)
		(fp_line
			(start 0.599 0)
			(end 0.201 0)
			(stroke
				(width 0.15)
				(type solid)
			)
			(layer "F.Fab")
		)
		(fp_line
			(start 0.201 0.2)
			(end 0.201 0)
			(stroke
				(width 0.15)
				(type solid)
			)
			(layer "F.Fab")
		)
		(fp_line
			(start 0.201 0)
			(end 0.201 -0.202)
			(stroke
				(width 0.15)
				(type solid)
			)
			(layer "F.Fab")
		)
		(fp_line
			(start 0.201 -0.202)
			(end -0.101 0)
			(stroke
				(width 0.15)
				(type solid)
			)
			(layer "F.Fab")
		)
		(fp_line
			(start -0.101 0)
			(end 0.201 0.2)
			(stroke
				(width 0.15)
				(type solid)
			)
			(layer "F.Fab")
		)
		(fp_line
			(start -0.199 0.2)
			(end -0.199 0.1)
			(stroke
				(width 0.15)
				(type solid)
			)
			(layer "F.Fab")
		)
		(fp_line
			(start -0.199 0)
			(end -0.597 0)
			(stroke
				(width 0.15)
				(type solid)
			)
			(layer "F.Fab")
		)
		(fp_line
			(start -0.199 -0.202)
			(end -0.199 0.1)
			(stroke
				(width 0.15)
				(type solid)
			)
			(layer "F.Fab")
		)
		(fp_rect
			(start 0.848 0.4)
			(end -0.85 -0.402)
			(stroke
				(width 0.15)
				(type solid)
			)
			(fill no)
			(layer "F.Fab")
		)
		(fp_text user "License: Apache-2.0"
			(at -1.4224 3.599 0)
			(layer "F.Fab")
			(effects
				(font
					(size 0.7 0.7)
					(thickness 0.15)
				)
				(justify right top)
			)
		)
		(fp_text user "Author: Antmicro"
			(at -1.4224 4.799 0)
			(layer "F.Fab")
			(effects
				(font
					(size 0.7 0.7)
					(thickness 0.15)
				)
				(justify right top)
			)
		)
		(fp_text user "${REFERENCE}"
			(at -1.4224 5.999 0)
			(layer "F.Fab")
			(effects
				(font
					(size 0.7 0.7)
					(thickness 0.15)
				)
				(justify right top)
			)
		)
		(pad "1" smd roundrect
			(at -0.7 0)
			(size 0.8 1)
			(layers "F.Cu" "F.Mask" "F.Paste")
			(roundrect_rratio 0.2)
			(net 1 "GND")
			(pinfunction "C")
			(pintype "passive")
		)
		(pad "2" smd roundrect
			(at 0.7 0)
			(size 0.8 1)
			(layers "F.Cu" "F.Mask" "F.Paste")
			(roundrect_rratio 0.2)
			(net 256 "Net-(D10-A)")
			(pinfunction "A")
			(pintype "passive")
		)
	)
	(footprint "antmicro-footprints:TSOT23-6"
		(layer "F.Cu")
		(at 164.461 66.097)
		(property "Reference" "U7"
			(at 1.849 1.443 0)
			(layer "F.SilkS")
			(effects
				(font
					(size 0.65 0.65)
					(thickness 0.15)
				)
				(justify left bottom)
			)
		)
		(property "Value" "AP62301WU-7"
			(at -0.005 2.6 0)
			(layer "F.Fab")
			(hide yes)
			(effects
				(font
					(size 0.7 0.7)
					(thickness 0.15)
				)
				(justify left bottom)
			)
		)
		(property "Datasheet" "https://www.diodes.com/assets/Datasheets/AP62300_AP62301_AP62300T.pdf"
			(at 0 0 0)
			(layer "F.Fab")
			(hide yes)
			(effects
				(font
					(size 1.27 1.27)
					(thickness 0.15)
				)
			)
		)
		(property "Description" "DC-DC Switching Synchronous Buck Regulator, Adjustable, 4.2V-18Vin, 0.8V-7V/3A out, TSOT-26-6"
			(at 0 0 0)
			(layer "F.Fab")
			(hide yes)
			(effects
				(font
					(size 1.27 1.27)
					(thickness 0.15)
				)
			)
		)
		(property "Author" "Antmicro"
			(at 98.39 230.59 90)
			(layer "F.Fab")
			(hide yes)
			(effects
				(font
					(size 1 1)
					(thickness 0.15)
				)
			)
		)
		(property "License" "Apache-2.0"
			(at 98.39 230.59 90)
			(layer "F.Fab")
			(hide yes)
			(effects
				(font
					(size 1 1)
					(thickness 0.15)
				)
			)
		)
		(property "MPN" "AP62301WU-7"
			(at 98.39 230.59 90)
			(layer "F.Fab")
			(hide yes)
			(effects
				(font
					(size 1 1)
					(thickness 0.15)
				)
			)
		)
		(property "Manufacturer" "Diodes Incorporated"
			(at 98.39 230.59 90)
			(layer "F.Fab")
			(hide yes)
			(effects
				(font
					(size 1 1)
					(thickness 0.15)
				)
			)
		)
		(sheetname "/Power Supply/")
		(sheetfile "supply.kicad_sch")
		(attr smd)
		(fp_line
			(start -1 -1.5)
			(end -1 -1.375)
			(stroke
				(width 0.15)
				(type solid)
			)
			(layer "F.SilkS")
		)
		(fp_line
			(start -1 1.55)
			(end -1 1.4)
			(stroke
				(width 0.15)
				(type solid)
			)
			(layer "F.SilkS")
		)
		(fp_line
			(start 1 -1.497)
			(end -1 -1.5)
			(stroke
				(width 0.15)
				(type solid)
			)
			(layer "F.SilkS")
		)
		(fp_line
			(start 1 -1.497)
			(end 1 -1.375)
			(stroke
				(width 0.15)
				(type solid)
			)
			(layer "F.SilkS")
		)
		(fp_line
			(start 1 1.55)
			(end -1 1.55)
			(stroke
				(width 0.15)
				(type solid)
			)
			(layer "F.SilkS")
		)
		(fp_line
			(start 1 1.55)
			(end 1 1.4)
			(stroke
				(width 0.15)
				(type solid)
			)
			(layer "F.SilkS")
		)
		(fp_circle
			(center -1.44 -1.5)
			(end -1.39 -1.5)
			(stroke
				(width 0.15)
				(type solid)
			)
			(fill yes)
			(layer "F.SilkS")
		)
		(fp_rect
			(start 1.93 -1.7)
			(end -1.93 1.7)
			(stroke
				(width 0.05)
				(type solid)
			)
			(fill no)
			(layer "F.CrtYd")
		)
		(fp_line
			(start -0.45 -1.521)
			(end -0.876 -1.096)
			(stroke
				(width 0.15)
				(type solid)
			)
			(layer "F.Fab")
		)
		(fp_rect
			(start 0.875 1.528)
			(end -0.875 -1.525)
			(stroke
				(width 0.15)
				(type solid)
			)
			(fill no)
			(layer "F.Fab")
		)
		(fp_text user "Author: Antmicro"
			(at -1.93 5 0)
			(layer "F.Fab")
			(effects
				(font
					(size 0.7 0.7)
					(thickness 0.15)
				)
				(justify left bottom)
			)
		)
		(fp_text user "${REFERENCE}"
			(at -1.93 3.8 0)
			(layer "F.Fab")
			(effects
				(font
					(size 0.7 0.7)
					(thickness 0.15)
				)
				(justify left bottom)
			)
		)
		(fp_text user "License: Apache-2.0"
			(at -1.93 6.199 0)
			(layer "F.Fab")
			(effects
				(font
					(size 0.7 0.7)
					(thickness 0.15)
				)
				(justify left bottom)
			)
		)
		(pad "1" smd rect
			(at -1.301 -0.947 270)
			(size 0.7 1.2)
			(layers "F.Cu" "F.Mask" "F.Paste")
			(net 1 "GND")
			(pinfunction "GND")
			(pintype "power_in")
		)
		(pad "2" smd rect
			(at -1.301 0.004 270)
			(size 0.7 1.2)
			(layers "F.Cu" "F.Mask" "F.Paste")
			(net 278 "/Power Supply/3V3_SW")
			(pinfunction "SW")
			(pintype "power_out")
		)
		(pad "3" smd rect
			(at -1.301 0.954 270)
			(size 0.7 1.2)
			(layers "F.Cu" "F.Mask" "F.Paste")
			(net 328 "/Power Supply/5V_3V3_IN")
			(pinfunction "VIN")
			(pintype "power_in")
		)
		(pad "4" smd rect
			(at 1.299 0.954 270)
			(size 0.7 1.2)
			(layers "F.Cu" "F.Mask" "F.Paste")
			(net 270 "Net-(U7-FB)")
			(pinfunction "FB")
			(pintype "input")
		)
		(pad "5" smd rect
			(at 1.299 0.004 270)
			(size 0.7 1.2)
			(layers "F.Cu" "F.Mask" "F.Paste")
			(net 375 "Net-(U7-EN)")
			(pinfunction "EN")
			(pintype "input")
		)
		(pad "6" smd rect
			(at 1.299 -0.947 270)
			(size 0.7 1.2)
			(layers "F.Cu" "F.Mask" "F.Paste")
			(net 140 "Net-(U7-BST)")
			(pinfunction "BST")
			(pintype "output")
		)
	)
	(footprint "antmicro-footprints:C_0603_1608Metric"
		(layer "F.Cu")
		(at 159.78 65.19 90)
		(descr "Capacitor SMD 0603")
		(tags "capacitor 0603")
		(property "Reference" "C25"
			(at -0.99 -0.7 90)
			(layer "F.SilkS")
			(effects
				(font
					(size 0.65 0.65)
					(thickness 0.15)
				)
				(justify left bottom)
			)
		)
		(property "Value" "C_22u_0603"
			(at 0 1.6 90)
			(layer "F.Fab")
			(hide yes)
			(effects
				(font
					(size 0.7 0.7)
					(thickness 0.15)
				)
				(justify left bottom)
			)
		)
		(property "Datasheet" "https://www.murata.com/products/productdetail?partno=GRM188R60J226MEA0%23"
			(at 0 0 90)
			(layer "F.Fab")
			(hide yes)
			(effects
				(font
					(size 1.27 1.27)
					(thickness 0.15)
				)
			)
		)
		(property "Description" "SMD Multilayer Ceramic Capacitor, 22 µF, 6.3 V, 0603 [1608 Metric], ± 20%, X5R, GRM Series"
			(at 0 0 90)
			(layer "F.Fab")
			(hide yes)
			(effects
				(font
					(size 1.27 1.27)
					(thickness 0.15)
				)
			)
		)
		(property "Author" "Antmicro"
			(at 224.97 -94.59 0)
			(layer "F.Fab")
			(hide yes)
			(effects
				(font
					(size 1 1)
					(thickness 0.15)
				)
			)
		)
		(property "Dielectric" ""
			(at 224.97 -94.59 0)
			(layer "F.Fab")
			(hide yes)
			(effects
				(font
					(size 1 1)
					(thickness 0.15)
				)
			)
		)
		(property "License" "Apache-2.0"
			(at 224.97 -94.59 0)
			(layer "F.Fab")
			(hide yes)
			(effects
				(font
					(size 1 1)
					(thickness 0.15)
				)
			)
		)
		(property "MPN" "GRM188R60J226MEA0D"
			(at 224.97 -94.59 0)
			(layer "F.Fab")
			(hide yes)
			(effects
				(font
					(size 1 1)
					(thickness 0.15)
				)
			)
		)
		(property "Manufacturer" "Murata"
			(at 224.97 -94.59 0)
			(layer "F.Fab")
			(hide yes)
			(effects
				(font
					(size 1 1)
					(thickness 0.15)
				)
			)
		)
		(property "Val" "22u"
			(at 224.97 -94.59 0)
			(layer "F.Fab")
			(hide yes)
			(effects
				(font
					(size 1 1)
					(thickness 0.15)
				)
			)
		)
		(property "Voltage" ""
			(at 224.97 -94.59 0)
			(layer "F.Fab")
			(hide yes)
			(effects
				(font
					(size 1 1)
					(thickness 0.15)
				)
			)
		)
		(sheetname "/Power Supply/")
		(sheetfile "supply.kicad_sch")
		(attr smd)
		(fp_line
			(start -0.15 -0.4)
			(end 0.15 -0.4)
			(stroke
				(width 0.15)
				(type solid)
			)
			(layer "F.SilkS")
		)
		(fp_line
			(start -0.15 0.4)
			(end 0.15 0.4)
			(stroke
				(width 0.15)
				(type solid)
			)
			(layer "F.SilkS")
		)
		(fp_rect
			(start -1.25 -0.65)
			(end 1.25 0.65)
			(stroke
				(width 0.05)
				(type solid)
			)
			(fill no)
			(layer "F.CrtYd")
		)
		(fp_rect
			(start -0.8 -0.4)
			(end 0.8 0.4)
			(stroke
				(width 0.15)
				(type solid)
			)
			(fill no)
			(layer "F.Fab")
		)
		(fp_text user "Author: Antmicro"
			(at -1.682 4.894 90)
			(layer "F.Fab")
			(effects
				(font
					(size 0.7 0.7)
					(thickness 0.15)
				)
				(justify left bottom)
			)
		)
		(fp_text user "License: Apache-2.0"
			(at -1.682 5.895 90)
			(layer "F.Fab")
			(effects
				(font
					(size 0.7 0.7)
					(thickness 0.15)
				)
				(justify left bottom)
			)
		)
		(fp_text user "${REFERENCE}"
			(at -1.682 3.895 90)
			(layer "F.Fab")
			(effects
				(font
					(size 0.7 0.7)
					(thickness 0.15)
				)
				(justify left bottom)
			)
		)
		(pad "1" smd roundrect
			(at -0.7 0 90)
			(size 0.8 1)
			(layers "F.Cu" "F.Mask" "F.Paste")
			(roundrect_rratio 0.2)
			(net 1 "GND")
			(pintype "passive")
		)
		(pad "2" smd roundrect
			(at 0.7 0 90)
			(size 0.8 1)
			(layers "F.Cu" "F.Mask" "F.Paste")
			(roundrect_rratio 0.2)
			(net 275 "/Power Supply/3V3_OUT")
			(pintype "passive")
		)
	)
	(footprint "antmicro-footprints:C_0603_1608Metric"
		(layer "F.Cu")
		(at 147.14 114.65 -90)
		(descr "Capacitor SMD 0603")
		(tags "capacitor 0603")
		(property "Reference" "C18"
			(at -1.51 -2.49 90)
			(layer "F.SilkS")
			(effects
				(font
					(size 0.65 0.65)
					(thickness 0.15)
				)
				(justify right bottom)
			)
		)
		(property "Value" "C_1u_0603"
			(at 0 1.6 90)
			(layer "F.Fab")
			(hide yes)
			(effects
				(font
					(size 0.7 0.7)
					(thickness 0.15)
				)
				(justify right bottom)
			)
		)
		(property "Datasheet" "https://spicat.kyocera-avx.com/product/mlcc/chartview/0603YD105KAT2A/"
			(at 0 0 270)
			(layer "F.Fab")
			(hide yes)
			(effects
				(font
					(size 1.27 1.27)
					(thickness 0.15)
				)
			)
		)
		(property "Description" "SMD Multilayer Ceramic Capacitor, 1 µF, 16 V, 0603 [1608 Metric], ± 10%, X5R, AVX 0603 MLCC"
			(at 0 0 270)
			(layer "F.Fab")
			(hide yes)
			(effects
				(font
					(size 1.27 1.27)
					(thickness 0.15)
				)
			)
		)
		(property "Author" "Antmicro"
			(at 32.49 261.79 0)
			(layer "F.Fab")
			(hide yes)
			(effects
				(font
					(size 1 1)
					(thickness 0.15)
				)
			)
		)
		(property "Dielectric" ""
			(at 32.49 261.79 0)
			(layer "F.Fab")
			(hide yes)
			(effects
				(font
					(size 1 1)
					(thickness 0.15)
				)
			)
		)
		(property "License" "Apache-2.0"
			(at 32.49 261.79 0)
			(layer "F.Fab")
			(hide yes)
			(effects
				(font
					(size 1 1)
					(thickness 0.15)
				)
			)
		)
		(property "MPN" "0603YD105KAT2A"
			(at 32.49 261.79 0)
			(layer "F.Fab")
			(hide yes)
			(effects
				(font
					(size 1 1)
					(thickness 0.15)
				)
			)
		)
		(property "Manufacturer" "KYOCERA AVX"
			(at 32.49 261.79 0)
			(layer "F.Fab")
			(hide yes)
			(effects
				(font
					(size 1 1)
					(thickness 0.15)
				)
			)
		)
		(property "Val" "1u"
			(at 32.49 261.79 0)
			(layer "F.Fab")
			(hide yes)
			(effects
				(font
					(size 1 1)
					(thickness 0.15)
				)
			)
		)
		(property "Voltage" ""
			(at 32.49 261.79 0)
			(layer "F.Fab")
			(hide yes)
			(effects
				(font
					(size 1 1)
					(thickness 0.15)
				)
			)
		)
		(sheetname "/Power Supply/")
		(sheetfile "supply.kicad_sch")
		(attr smd)
		(fp_line
			(start -0.15 0.4)
			(end 0.15 0.4)
			(stroke
				(width 0.15)
				(type solid)
			)
			(layer "F.SilkS")
		)
		(fp_line
			(start -0.15 -0.4)
			(end 0.15 -0.4)
			(stroke
				(width 0.15)
				(type solid)
			)
			(layer "F.SilkS")
		)
		(fp_rect
			(start -1.25 -0.65)
			(end 1.25 0.65)
			(stroke
				(width 0.05)
				(type solid)
			)
			(fill no)
			(layer "F.CrtYd")
		)
		(fp_rect
			(start -0.8 -0.4)
			(end 0.8 0.4)
			(stroke
				(width 0.15)
				(type solid)
			)
			(fill no)
			(layer "F.Fab")
		)
		(fp_text user "License: Apache-2.0"
			(at -1.682 5.895 270)
			(layer "F.Fab")
			(effects
				(font
					(size 0.7 0.7)
					(thickness 0.15)
				)
				(justify left bottom)
			)
		)
		(fp_text user "Author: Antmicro"
			(at -1.682 4.894 270)
			(layer "F.Fab")
			(effects
				(font
					(size 0.7 0.7)
					(thickness 0.15)
				)
				(justify left bottom)
			)
		)
		(fp_text user "${REFERENCE}"
			(at -1.682 3.895 270)
			(layer "F.Fab")
			(effects
				(font
					(size 0.7 0.7)
					(thickness 0.15)
				)
				(justify left bottom)
			)
		)
		(pad "1" smd roundrect
			(at -0.7 0 270)
			(size 0.8 1)
			(layers "F.Cu" "F.Mask" "F.Paste")
			(roundrect_rratio 0.2)
			(net 1 "GND")
			(pintype "passive")
		)
		(pad "2" smd roundrect
			(at 0.7 0 270)
			(size 0.8 1)
			(layers "F.Cu" "F.Mask" "F.Paste")
			(roundrect_rratio 0.2)
			(net 2 "+3V3")
			(pintype "passive")
		)
	)
	(footprint "antmicro-footprints:C_0402_1005Metric"
		(layer "F.Cu")
		(at 161.915 84.15 180)
		(descr "Capacitor SMD 0402")
		(tags "capacitor SMD 0402")
		(property "Reference" "C110"
			(at 1.885 -0.39 0)
			(layer "F.SilkS")
			(effects
				(font
					(size 0.65 0.65)
					(thickness 0.15)
				)
				(justify right bottom)
			)
		)
		(property "Value" "C_100n_0402"
			(at 0 1.4 0)
			(layer "F.Fab")
			(hide yes)
			(effects
				(font
					(size 0.7 0.7)
					(thickness 0.15)
				)
				(justify right bottom)
			)
		)
		(property "Datasheet" "https://www.murata.com/products/productdetail?partno=GRM155R61H104KE14%23"
			(at 0 0 180)
			(layer "F.Fab")
			(hide yes)
			(effects
				(font
					(size 1.27 1.27)
					(thickness 0.15)
				)
			)
		)
		(property "Description" "SMD Multilayer Ceramic Capacitor, 0.1 µF, 50 V, 0402 [1005 Metric], ± 10%, X5R, GRM Series"
			(at 0 0 180)
			(layer "F.Fab")
			(hide yes)
			(effects
				(font
					(size 1.27 1.27)
					(thickness 0.15)
				)
			)
		)
		(property "Author" "Antmicro"
			(at 323.83 168.3 0)
			(layer "F.Fab")
			(hide yes)
			(effects
				(font
					(size 1 1)
					(thickness 0.15)
				)
			)
		)
		(property "Dielectric" "X5R"
			(at 323.83 168.3 0)
			(layer "F.Fab")
			(hide yes)
			(effects
				(font
					(size 1 1)
					(thickness 0.15)
				)
			)
		)
		(property "License" "Apache-2.0"
			(at 323.83 168.3 0)
			(layer "F.Fab")
			(hide yes)
			(effects
				(font
					(size 1 1)
					(thickness 0.15)
				)
			)
		)
		(property "MPN" "GRM155R61H104KE14D"
			(at 323.83 168.3 0)
			(layer "F.Fab")
			(hide yes)
			(effects
				(font
					(size 1 1)
					(thickness 0.15)
				)
			)
		)
		(property "Manufacturer" "Murata"
			(at 323.83 168.3 0)
			(layer "F.Fab")
			(hide yes)
			(effects
				(font
					(size 1 1)
					(thickness 0.15)
				)
			)
		)
		(property "Val" "100n"
			(at 323.83 168.3 0)
			(layer "F.Fab")
			(hide yes)
			(effects
				(font
					(size 1 1)
					(thickness 0.15)
				)
			)
		)
		(property "Voltage" "50V"
			(at 323.83 168.3 0)
			(layer "F.Fab")
			(hide yes)
			(effects
				(font
					(size 1 1)
					(thickness 0.15)
				)
			)
		)
		(sheetname "/Peripherals/")
		(sheetfile "peripherals.kicad_sch")
		(attr smd)
		(fp_rect
			(start -0.925 -0.47)
			(end 0.925 0.47)
			(stroke
				(width 0.05)
				(type default)
			)
			(fill no)
			(layer "F.CrtYd")
		)
		(fp_line
			(start 0.504 0.248)
			(end -0.494 0.248)
			(stroke
				(width 0.15)
				(type solid)
			)
			(layer "F.Fab")
		)
		(fp_line
			(start 0.504 -0.25)
			(end 0.504 0.248)
			(stroke
				(width 0.15)
				(type solid)
			)
			(layer "F.Fab")
		)
		(fp_line
			(start -0.494 0.248)
			(end -0.494 -0.25)
			(stroke
				(width 0.15)
				(type solid)
			)
			(layer "F.Fab")
		)
		(fp_line
			(start -0.494 -0.25)
			(end 0.504 -0.25)
			(stroke
				(width 0.15)
				(type solid)
			)
			(layer "F.Fab")
		)
		(fp_text user "Author: Antmicro"
			(at -0.939 3.399 180)
			(layer "F.Fab")
			(effects
				(font
					(size 0.7 0.7)
					(thickness 0.15)
				)
				(justify left bottom)
			)
		)
		(fp_text user "License: Apache-2.0"
			(at -0.939 5.799 180)
			(layer "F.Fab")
			(effects
				(font
					(size 0.7 0.7)
					(thickness 0.15)
				)
				(justify left bottom)
			)
		)
		(fp_text user "${REFERENCE}"
			(at -0.939 4.599 180)
			(layer "F.Fab")
			(effects
				(font
					(size 0.7 0.7)
					(thickness 0.15)
				)
				(justify left bottom)
			)
		)
		(pad "1" smd roundrect
			(at -0.48 0 180)
			(size 0.59 0.64)
			(layers "F.Cu" "F.Mask" "F.Paste")
			(roundrect_rratio 0.25)
			(net 1 "GND")
			(pintype "passive")
		)
		(pad "2" smd roundrect
			(at 0.48 0 180)
			(size 0.59 0.64)
			(layers "F.Cu" "F.Mask" "F.Paste")
			(roundrect_rratio 0.25)
			(net 14 "+5V")
			(pintype "passive")
		)
	)
	(footprint "antmicro-footprints:R_0603_1608Metric"
		(layer "F.Cu")
		(at 158.29 76.6)
		(descr "Resistor SMD 0603")
		(tags "resistor SMD 0603")
		(property "Reference" "R117"
			(at -4.06 0.54 0)
			(layer "F.SilkS")
			(effects
				(font
					(size 0.65 0.65)
					(thickness 0.15)
				)
				(justify left bottom)
			)
		)
		(property "Value" "R_0R_0603"
			(at 0 1.6 0)
			(layer "F.Fab")
			(hide yes)
			(effects
				(font
					(size 0.7 0.7)
					(thickness 0.15)
				)
				(justify left bottom)
			)
		)
		(property "Datasheet" "https://www.bourns.com/docs/product-datasheets/cr.pdf?sfvrsn=574d41f6_14"
			(at 0 0 0)
			(layer "F.Fab")
			(hide yes)
			(effects
				(font
					(size 1.27 1.27)
					(thickness 0.15)
				)
			)
		)
		(property "Description" "Zero Ohm Resistor, Jumper, 0603 [1608 Metric], Thick Film, 100 mW, 1 A, Surface Mount Device, CR"
			(at 0 0 0)
			(layer "F.Fab")
			(hide yes)
			(effects
				(font
					(size 1.27 1.27)
					(thickness 0.15)
				)
			)
		)
		(property "Author" "Antmicro"
			(at 0 0 0)
			(layer "F.Fab")
			(hide yes)
			(effects
				(font
					(size 1 1)
					(thickness 0.15)
				)
			)
		)
		(property "Current" "1A"
			(at 0 0 0)
			(layer "F.Fab")
			(hide yes)
			(effects
				(font
					(size 1 1)
					(thickness 0.15)
				)
			)
		)
		(property "License" "Apache-2.0"
			(at 0 0 0)
			(layer "F.Fab")
			(hide yes)
			(effects
				(font
					(size 1 1)
					(thickness 0.15)
				)
			)
		)
		(property "MPN" "CR0603-J/-000ELF"
			(at 0 0 0)
			(layer "F.Fab")
			(hide yes)
			(effects
				(font
					(size 1 1)
					(thickness 0.15)
				)
			)
		)
		(property "Manufacturer" "Bourns"
			(at 0 0 0)
			(layer "F.Fab")
			(hide yes)
			(effects
				(font
					(size 1 1)
					(thickness 0.15)
				)
			)
		)
		(property "Tolerance" "~"
			(at 0 0 0)
			(layer "F.Fab")
			(hide yes)
			(effects
				(font
					(size 1 1)
					(thickness 0.15)
				)
			)
		)
		(property "Val" "0R"
			(at 0 0 0)
			(layer "F.Fab")
			(hide yes)
			(effects
				(font
					(size 1 1)
					(thickness 0.15)
				)
			)
		)
		(sheetname "/Peripherals/")
		(sheetfile "peripherals.kicad_sch")
		(attr smd)
		(fp_line
			(start -0.15 -0.4)
			(end 0.15 -0.4)
			(stroke
				(width 0.15)
				(type solid)
			)
			(layer "F.SilkS")
		)
		(fp_line
			(start -0.15 0.4)
			(end 0.15 0.4)
			(stroke
				(width 0.15)
				(type solid)
			)
			(layer "F.SilkS")
		)
		(fp_rect
			(start -1.25 -0.65)
			(end 1.25 0.65)
			(stroke
				(width 0.05)
				(type solid)
			)
			(fill no)
			(layer "F.CrtYd")
		)
		(fp_rect
			(start -0.8 -0.4)
			(end 0.8 0.4)
			(stroke
				(width 0.15)
				(type solid)
			)
			(fill no)
			(layer "F.Fab")
		)
		(fp_text user "Author: Antmicro"
			(at -1.25 4.9 0)
			(layer "F.Fab")
			(effects
				(font
					(size 0.7 0.7)
					(thickness 0.15)
				)
				(justify left bottom)
			)
		)
		(fp_text user "License: Apache-2.0"
			(at -1.25 5.9 0)
			(layer "F.Fab")
			(effects
				(font
					(size 0.7 0.7)
					(thickness 0.15)
				)
				(justify left bottom)
			)
		)
		(fp_text user "${REFERENCE}"
			(at -1.25 3.898 0)
			(layer "F.Fab")
			(effects
				(font
					(size 0.7 0.7)
					(thickness 0.15)
				)
				(justify left bottom)
			)
		)
		(pad "1" smd roundrect
			(at -0.7 0)
			(size 0.8 1)
			(layers "F.Cu" "F.Mask" "F.Paste")
			(roundrect_rratio 0.2)
			(net 100 "SCL")
			(pintype "passive")
		)
		(pad "2" smd roundrect
			(at 0.7 0)
			(size 0.8 1)
			(layers "F.Cu" "F.Mask" "F.Paste")
			(roundrect_rratio 0.2)
			(net 313 "Net-(J8-Pad4)")
			(pintype "passive")
		)
	)
	(footprint "antmicro-footprints:C_0603_1608Metric"
		(layer "F.Cu")
		(at 161.69 76.6 180)
		(descr "Capacitor SMD 0603")
		(tags "capacitor 0603")
		(property "Reference" "C114"
			(at -1.34 0.76 0)
			(layer "F.SilkS")
			(effects
				(font
					(size 0.65 0.65)
					(thickness 0.15)
				)
				(justify right bottom)
			)
		)
		(property "Value" "C_1u_0603"
			(at 0 1.6 0)
			(layer "F.Fab")
			(hide yes)
			(effects
				(font
					(size 0.7 0.7)
					(thickness 0.15)
				)
				(justify right bottom)
			)
		)
		(property "Datasheet" "https://spicat.kyocera-avx.com/product/mlcc/chartview/0603YD105KAT2A/"
			(at 0 0 180)
			(layer "F.Fab")
			(hide yes)
			(effects
				(font
					(size 1.27 1.27)
					(thickness 0.15)
				)
			)
		)
		(property "Description" "SMD Multilayer Ceramic Capacitor, 1 µF, 16 V, 0603 [1608 Metric], ± 10%, X5R, AVX 0603 MLCC"
			(at 0 0 180)
			(layer "F.Fab")
			(hide yes)
			(effects
				(font
					(size 1.27 1.27)
					(thickness 0.15)
				)
			)
		)
		(property "Author" "Antmicro"
			(at 323.38 153.2 0)
			(layer "F.Fab")
			(hide yes)
			(effects
				(font
					(size 1 1)
					(thickness 0.15)
				)
			)
		)
		(property "Dielectric" ""
			(at 323.38 153.2 0)
			(layer "F.Fab")
			(hide yes)
			(effects
				(font
					(size 1 1)
					(thickness 0.15)
				)
			)
		)
		(property "License" "Apache-2.0"
			(at 323.38 153.2 0)
			(layer "F.Fab")
			(hide yes)
			(effects
				(font
					(size 1 1)
					(thickness 0.15)
				)
			)
		)
		(property "MPN" "0603YD105KAT2A"
			(at 323.38 153.2 0)
			(layer "F.Fab")
			(hide yes)
			(effects
				(font
					(size 1 1)
					(thickness 0.15)
				)
			)
		)
		(property "Manufacturer" "KYOCERA AVX"
			(at 323.38 153.2 0)
			(layer "F.Fab")
			(hide yes)
			(effects
				(font
					(size 1 1)
					(thickness 0.15)
				)
			)
		)
		(property "Val" "1u"
			(at 323.38 153.2 0)
			(layer "F.Fab")
			(hide yes)
			(effects
				(font
					(size 1 1)
					(thickness 0.15)
				)
			)
		)
		(property "Voltage" ""
			(at 323.38 153.2 0)
			(layer "F.Fab")
			(hide yes)
			(effects
				(font
					(size 1 1)
					(thickness 0.15)
				)
			)
		)
		(sheetname "/Peripherals/")
		(sheetfile "peripherals.kicad_sch")
		(attr smd)
		(fp_line
			(start -0.15 0.4)
			(end 0.15 0.4)
			(stroke
				(width 0.15)
				(type solid)
			)
			(layer "F.SilkS")
		)
		(fp_line
			(start -0.15 -0.4)
			(end 0.15 -0.4)
			(stroke
				(width 0.15)
				(type solid)
			)
			(layer "F.SilkS")
		)
		(fp_rect
			(start -1.25 -0.65)
			(end 1.25 0.65)
			(stroke
				(width 0.05)
				(type solid)
			)
			(fill no)
			(layer "F.CrtYd")
		)
		(fp_rect
			(start -0.8 -0.4)
			(end 0.8 0.4)
			(stroke
				(width 0.15)
				(type solid)
			)
			(fill no)
			(layer "F.Fab")
		)
		(fp_text user "License: Apache-2.0"
			(at -1.682 5.895 180)
			(layer "F.Fab")
			(effects
				(font
					(size 0.7 0.7)
					(thickness 0.15)
				)
				(justify left bottom)
			)
		)
		(fp_text user "Author: Antmicro"
			(at -1.682 4.894 180)
			(layer "F.Fab")
			(effects
				(font
					(size 0.7 0.7)
					(thickness 0.15)
				)
				(justify left bottom)
			)
		)
		(fp_text user "${REFERENCE}"
			(at -1.682 3.895 180)
			(layer "F.Fab")
			(effects
				(font
					(size 0.7 0.7)
					(thickness 0.15)
				)
				(justify left bottom)
			)
		)
		(pad "1" smd roundrect
			(at -0.7 0 180)
			(size 0.8 1)
			(layers "F.Cu" "F.Mask" "F.Paste")
			(roundrect_rratio 0.2)
			(net 1 "GND")
			(pintype "passive")
		)
		(pad "2" smd roundrect
			(at 0.7 0 180)
			(size 0.8 1)
			(layers "F.Cu" "F.Mask" "F.Paste")
			(roundrect_rratio 0.2)
			(net 310 "/Peripherals/QWIIC_3V3")
			(pintype "passive")
		)
	)
	(footprint "antmicro-footprints:TP_SMD_0.75mm"
		(layer "F.Cu")
		(at 136.39 111.9 90)
		(property "Reference" "TP6"
			(at -1.44 -0.56 90)
			(layer "F.SilkS")
			(effects
				(font
					(size 0.65 0.65)
					(thickness 0.15)
				)
				(justify left bottom)
			)
		)
		(property "Value" "TP_0.75mm_SMD"
			(at 0 1.2 90)
			(layer "F.Fab")
			(hide yes)
			(effects
				(font
					(size 0.7 0.7)
					(thickness 0.15)
				)
				(justify left bottom)
			)
		)
		(property "Description" "SMT test point"
			(at 0 0 90)
			(layer "F.Fab")
			(hide yes)
			(effects
				(font
					(size 1.27 1.27)
					(thickness 0.15)
				)
			)
		)
		(property "Author" "Antmicro"
			(at 248.29 -24.49 0)
			(layer "F.Fab")
			(hide yes)
			(effects
				(font
					(size 1 1)
					(thickness 0.15)
				)
			)
		)
		(property "License" "Apache-2.0"
			(at 248.29 -24.49 0)
			(layer "F.Fab")
			(hide yes)
			(effects
				(font
					(size 1 1)
					(thickness 0.15)
				)
			)
		)
		(property "MPN" ""
			(at 248.29 -24.49 0)
			(layer "F.Fab")
			(hide yes)
			(effects
				(font
					(size 1 1)
					(thickness 0.15)
				)
			)
		)
		(property "Manufacturer" ""
			(at 248.29 -24.49 0)
			(layer "F.Fab")
			(hide yes)
			(effects
				(font
					(size 1 1)
					(thickness 0.15)
				)
			)
		)
		(sheetname "/Power Supply/")
		(sheetfile "supply.kicad_sch")
		(attr exclude_from_pos_files)
		(fp_circle
			(center 0 0)
			(end 0.475 0)
			(stroke
				(width 0.05)
				(type default)
			)
			(fill no)
			(layer "F.CrtYd")
		)
		(fp_text user "${REFERENCE}"
			(at -0.4 2.7 90)
			(layer "F.Fab")
			(effects
				(font
					(size 0.7 0.7)
					(thickness 0.15)
				)
				(justify left bottom)
			)
		)
		(fp_text user "License: Apache-2.0"
			(at -0.4 5.101 90)
			(layer "F.Fab")
			(effects
				(font
					(size 0.7 0.7)
					(thickness 0.15)
				)
				(justify left bottom)
			)
		)
		(fp_text user "Author: Antmicro"
			(at -0.4 3.901 90)
			(layer "F.Fab")
			(effects
				(font
					(size 0.7 0.7)
					(thickness 0.15)
				)
				(justify left bottom)
			)
		)
		(pad "1" smd circle
			(at 0 0 90)
			(size 0.75 0.75)
			(layers "F.Cu" "F.Mask")
			(net 50 "+1V8")
			(pinfunction "1")
			(pintype "passive")
		)
	)
	(footprint "antmicro-footprints:R_0402_1005Metric"
		(layer "F.Cu")
		(at 110.79 102.4)
		(descr "Resistor SMD 0402")
		(tags "resistor SMD 0402")
		(property "Reference" "R85"
			(at 0.94 0.44 0)
			(layer "F.SilkS")
			(effects
				(font
					(size 0.65 0.65)
					(thickness 0.15)
				)
				(justify left bottom)
			)
		)
		(property "Value" "R_0R_0402"
			(at 0 1.4 0)
			(layer "F.Fab")
			(hide yes)
			(effects
				(font
					(size 0.7 0.7)
					(thickness 0.15)
				)
				(justify left bottom)
			)
		)
		(property "Datasheet" "https://industrial.panasonic.com/cdbs/www-data/pdf/RDA0000/AOA0000C301.pdf"
			(at 0 0 0)
			(layer "F.Fab")
			(hide yes)
			(effects
				(font
					(size 1.27 1.27)
					(thickness 0.15)
				)
			)
		)
		(property "Description" "SMD Chip Resistor, Jumper, 0 ohm, 100 mW, 0402 [1005 Metric], Thick Film, General Purpose"
			(at 0 0 0)
			(layer "F.Fab")
			(hide yes)
			(effects
				(font
					(size 1.27 1.27)
					(thickness 0.15)
				)
			)
		)
		(property "Author" "Antmicro"
			(at 0 0 0)
			(layer "F.Fab")
			(hide yes)
			(effects
				(font
					(size 1 1)
					(thickness 0.15)
				)
			)
		)
		(property "Current" "1A"
			(at 0 0 0)
			(layer "F.Fab")
			(hide yes)
			(effects
				(font
					(size 1 1)
					(thickness 0.15)
				)
			)
		)
		(property "License" "Apache-2.0"
			(at 0 0 0)
			(layer "F.Fab")
			(hide yes)
			(effects
				(font
					(size 1 1)
					(thickness 0.15)
				)
			)
		)
		(property "MPN" "ERJ2GE0R00X"
			(at 0 0 0)
			(layer "F.Fab")
			(hide yes)
			(effects
				(font
					(size 1 1)
					(thickness 0.15)
				)
			)
		)
		(property "Manufacturer" "Panasonic"
			(at 0 0 0)
			(layer "F.Fab")
			(hide yes)
			(effects
				(font
					(size 1 1)
					(thickness 0.15)
				)
			)
		)
		(property "Tolerance" "~"
			(at 0 0 0)
			(layer "F.Fab")
			(hide yes)
			(effects
				(font
					(size 1 1)
					(thickness 0.15)
				)
			)
		)
		(property "Val" "0R"
			(at 0 0 0)
			(layer "F.Fab")
			(hide yes)
			(effects
				(font
					(size 1 1)
					(thickness 0.15)
				)
			)
		)
		(sheetname "/FPGA/")
		(sheetfile "fpga.kicad_sch")
		(attr smd)
		(fp_rect
			(start -0.925 -0.47)
			(end 0.925 0.47)
			(stroke
				(width 0.05)
				(type default)
			)
			(fill no)
			(layer "F.CrtYd")
		)
		(fp_rect
			(start -0.5 -0.25)
			(end 0.5 0.25)
			(stroke
				(width 0.15)
				(type solid)
			)
			(fill no)
			(layer "F.Fab")
		)
		(fp_text user "Author: Antmicro"
			(at -0.95 4.169 0)
			(layer "F.Fab")
			(effects
				(font
					(size 0.7 0.7)
					(thickness 0.15)
				)
				(justify left bottom)
			)
		)
		(fp_text user "License: Apache-2.0"
			(at -0.95 5.169 0)
			(layer "F.Fab")
			(effects
				(font
					(size 0.7 0.7)
					(thickness 0.15)
				)
				(justify left bottom)
			)
		)
		(fp_text user "${REFERENCE}"
			(at -0.95 3.168 0)
			(layer "F.Fab")
			(effects
				(font
					(size 0.7 0.7)
					(thickness 0.15)
				)
				(justify left bottom)
			)
		)
		(pad "1" smd roundrect
			(at -0.48 0)
			(size 0.59 0.64)
			(layers "F.Cu" "F.Mask" "F.Paste")
			(roundrect_rratio 0.25)
			(net 330 "Net-(U17-A0)")
			(pintype "passive")
		)
		(pad "2" smd roundrect
			(at 0.48 0)
			(size 0.59 0.64)
			(layers "F.Cu" "F.Mask" "F.Paste")
			(roundrect_rratio 0.25)
			(net 1 "GND")
			(pintype "passive")
		)
	)
	(footprint "antmicro-footprints:C_0603_1608Metric"
		(layer "F.Cu")
		(at 146.23 70.12 90)
		(descr "Capacitor SMD 0603")
		(tags "capacitor 0603")
		(property "Reference" "C11"
			(at -0.9 -0.51 90)
			(layer "F.SilkS")
			(effects
				(font
					(size 0.65 0.65)
					(thickness 0.15)
				)
				(justify left bottom)
			)
		)
		(property "Value" "C_10u_0603"
			(at 0 1.6 90)
			(layer "F.Fab")
			(hide yes)
			(effects
				(font
					(size 0.7 0.7)
					(thickness 0.15)
				)
				(justify left bottom)
			)
		)
		(property "Datasheet" "https://www.murata.com/products/productdetail?partno=GRM188R61A106KE69%23"
			(at 0 0 90)
			(layer "F.Fab")
			(hide yes)
			(effects
				(font
					(size 1.27 1.27)
					(thickness 0.15)
				)
			)
		)
		(property "Description" "SMD Multilayer Ceramic Capacitor, 10 µF, 10 V, 0603 [1608 Metric], ± 10%, X5R, GRM Series"
			(at 0 0 90)
			(layer "F.Fab")
			(hide yes)
			(effects
				(font
					(size 1.27 1.27)
					(thickness 0.15)
				)
			)
		)
		(property "Author" "Antmicro"
			(at 216.37 -76.09 0)
			(layer "F.Fab")
			(hide yes)
			(effects
				(font
					(size 1 1)
					(thickness 0.15)
				)
			)
		)
		(property "License" "Apache-2.0"
			(at 216.37 -76.09 0)
			(layer "F.Fab")
			(hide yes)
			(effects
				(font
					(size 1 1)
					(thickness 0.15)
				)
			)
		)
		(property "MPN" "GRM188R61A106KE69D"
			(at 216.37 -76.09 0)
			(layer "F.Fab")
			(hide yes)
			(effects
				(font
					(size 1 1)
					(thickness 0.15)
				)
			)
		)
		(property "Manufacturer" "Murata"
			(at 216.37 -76.09 0)
			(layer "F.Fab")
			(hide yes)
			(effects
				(font
					(size 1 1)
					(thickness 0.15)
				)
			)
		)
		(property "Val" "10u"
			(at 216.37 -76.09 0)
			(layer "F.Fab")
			(hide yes)
			(effects
				(font
					(size 1 1)
					(thickness 0.15)
				)
			)
		)
		(property "Voltage" ""
			(at 216.37 -76.09 0)
			(layer "F.Fab")
			(hide yes)
			(effects
				(font
					(size 1 1)
					(thickness 0.15)
				)
			)
		)
		(property "Dielectric" "template_dielectric"
			(at 0 0 90)
			(unlocked yes)
			(layer "F.Fab")
			(hide yes)
			(effects
				(font
					(size 1 1)
					(thickness 0.15)
				)
			)
		)
		(sheetname "/Power Supply/")
		(sheetfile "supply.kicad_sch")
		(attr smd)
		(fp_line
			(start -0.15 -0.4)
			(end 0.15 -0.4)
			(stroke
				(width 0.15)
				(type solid)
			)
			(layer "F.SilkS")
		)
		(fp_line
			(start -0.15 0.4)
			(end 0.15 0.4)
			(stroke
				(width 0.15)
				(type solid)
			)
			(layer "F.SilkS")
		)
		(fp_rect
			(start -1.25 -0.65)
			(end 1.25 0.65)
			(stroke
				(width 0.05)
				(type solid)
			)
			(fill no)
			(layer "F.CrtYd")
		)
		(fp_rect
			(start -0.8 -0.4)
			(end 0.8 0.4)
			(stroke
				(width 0.15)
				(type solid)
			)
			(fill no)
			(layer "F.Fab")
		)
		(fp_text user "License: Apache-2.0"
			(at -1.682 5.895 90)
			(layer "F.Fab")
			(effects
				(font
					(size 0.7 0.7)
					(thickness 0.15)
				)
				(justify left bottom)
			)
		)
		(fp_text user "${REFERENCE}"
			(at -1.682 3.895 90)
			(layer "F.Fab")
			(effects
				(font
					(size 0.7 0.7)
					(thickness 0.15)
				)
				(justify left bottom)
			)
		)
		(fp_text user "Author: Antmicro"
			(at -1.682 4.894 90)
			(layer "F.Fab")
			(effects
				(font
					(size 0.7 0.7)
					(thickness 0.15)
				)
				(justify left bottom)
			)
		)
		(pad "1" smd roundrect
			(at -0.7 0 90)
			(size 0.8 1)
			(layers "F.Cu" "F.Mask" "F.Paste")
			(roundrect_rratio 0.2)
			(net 1 "GND")
			(pintype "passive")
		)
		(pad "2" smd roundrect
			(at 0.7 0 90)
			(size 0.8 1)
			(layers "F.Cu" "F.Mask" "F.Paste")
			(roundrect_rratio 0.2)
			(net 326 "/Power Supply/5V_1V0_IN")
			(pintype "passive")
		)
	)
	(footprint "antmicro-footprints:LED_0603_1608Metric_G"
		(layer "F.Cu")
		(at 165.63 119.15 90)
		(descr "LED SMD 0603 Green")
		(tags "LED SMD 0603 Green")
		(property "Reference" "D3"
			(at -0.09 0.8 90)
			(layer "F.SilkS")
			(effects
				(font
					(size 0.65 0.65)
					(thickness 0.15)
				)
				(justify left top)
			)
		)
		(property "Value" "LED_G_0603_LTST-C190GKT"
			(at 0 1.6 90)
			(layer "F.Fab")
			(hide yes)
			(effects
				(font
					(size 0.7 0.7)
					(thickness 0.15)
				)
				(justify left top)
			)
		)
		(property "Datasheet" "https://media.digikey.com/pdf/Data%20Sheets/Lite-On%20PDFs/LTST-C190GKT.pdf"
			(at 0 0 90)
			(layer "F.Fab")
			(hide yes)
			(effects
				(font
					(size 1.27 1.27)
					(thickness 0.15)
				)
			)
		)
		(property "Description" "LED, Green, SMD, 0603, 20 mA, 2.1 V, 569 nm"
			(at 0 0 90)
			(layer "F.Fab")
			(hide yes)
			(effects
				(font
					(size 1.27 1.27)
					(thickness 0.15)
				)
			)
		)
		(property "Author" "Antmicro"
			(at 46.48 284.78 0)
			(layer "F.Fab")
			(hide yes)
			(effects
				(font
					(size 1 1)
					(thickness 0.15)
				)
			)
		)
		(property "License" "Apache-2.0"
			(at 46.48 284.78 0)
			(layer "F.Fab")
			(hide yes)
			(effects
				(font
					(size 1 1)
					(thickness 0.15)
				)
			)
		)
		(property "MPN" "LTST-C190GKT"
			(at 46.48 284.78 0)
			(layer "F.Fab")
			(hide yes)
			(effects
				(font
					(size 1 1)
					(thickness 0.15)
				)
			)
		)
		(property "Manufacturer" "Lite-On"
			(at 46.48 284.78 0)
			(layer "F.Fab")
			(hide yes)
			(effects
				(font
					(size 1 1)
					(thickness 0.15)
				)
			)
		)
		(property "Color" "Green"
			(at 0 0 90)
			(unlocked yes)
			(layer "F.Fab")
			(hide yes)
			(effects
				(font
					(size 1 1)
					(thickness 0.15)
				)
			)
		)
		(sheetname "/Peripherals/")
		(sheetfile "peripherals.kicad_sch")
		(attr smd)
		(fp_line
			(start 0.22 -0.35)
			(end -0.22 -0.35)
			(stroke
				(width 0.15)
				(type solid)
			)
			(layer "F.SilkS")
		)
		(fp_line
			(start -1.18 -0.319)
			(end -1.18 0.321)
			(stroke
				(width 0.15)
				(type solid)
			)
			(layer "F.SilkS")
		)
		(fp_line
			(start 0.105328 0.001008)
			(end 0.24 0.001)
			(stroke
				(width 0.1)
				(type solid)
			)
			(layer "F.SilkS")
		)
		(fp_line
			(start -0.094672 0.001008)
			(end 0.105328 -0.198992)
			(stroke
				(width 0.1)
				(type solid)
			)
			(layer "F.SilkS")
		)
		(fp_line
			(start -0.094672 0.001008)
			(end -0.24 0.001008)
			(stroke
				(width 0.1)
				(type solid)
			)
			(layer "F.SilkS")
		)
		(fp_line
			(start 0.105328 0.201008)
			(end 0.105328 -0.198992)
			(stroke
				(width 0.1)
				(type solid)
			)
			(layer "F.SilkS")
		)
		(fp_line
			(start 0.105328 0.201008)
			(end -0.094672 0.001008)
			(stroke
				(width 0.1)
				(type solid)
			)
			(layer "F.SilkS")
		)
		(fp_line
			(start -0.094672 0.201008)
			(end -0.094672 -0.198992)
			(stroke
				(width 0.1)
				(type solid)
			)
			(layer "F.SilkS")
		)
		(fp_line
			(start 0.22 0.35)
			(end -0.22 0.35)
			(stroke
				(width 0.15)
				(type solid)
			)
			(layer "F.SilkS")
		)
		(fp_rect
			(start 1.25 0.65)
			(end -1.25 -0.65)
			(stroke
				(width 0.05)
				(type solid)
			)
			(fill no)
			(layer "F.CrtYd")
		)
		(fp_line
			(start 0.201 -0.202)
			(end -0.101 0)
			(stroke
				(width 0.15)
				(type solid)
			)
			(layer "F.Fab")
		)
		(fp_line
			(start -0.199 -0.202)
			(end -0.199 0.1)
			(stroke
				(width 0.15)
				(type solid)
			)
			(layer "F.Fab")
		)
		(fp_line
			(start 0.599 0)
			(end 0.201 0)
			(stroke
				(width 0.15)
				(type solid)
			)
			(layer "F.Fab")
		)
		(fp_line
			(start 0.201 0)
			(end 0.201 -0.202)
			(stroke
				(width 0.15)
				(type solid)
			)
			(layer "F.Fab")
		)
		(fp_line
			(start -0.101 0)
			(end 0.201 0.2)
			(stroke
				(width 0.15)
				(type solid)
			)
			(layer "F.Fab")
		)
		(fp_line
			(start -0.199 0)
			(end -0.597 0)
			(stroke
				(width 0.15)
				(type solid)
			)
			(layer "F.Fab")
		)
		(fp_line
			(start 0.201 0.2)
			(end 0.201 0)
			(stroke
				(width 0.15)
				(type solid)
			)
			(layer "F.Fab")
		)
		(fp_line
			(start -0.199 0.2)
			(end -0.199 0.1)
			(stroke
				(width 0.15)
				(type solid)
			)
			(layer "F.Fab")
		)
		(fp_rect
			(start 0.848 0.4)
			(end -0.85 -0.402)
			(stroke
				(width 0.15)
				(type solid)
			)
			(fill no)
			(layer "F.Fab")
		)
		(fp_text user "${REFERENCE}"
			(at -1.4224 5.999 90)
			(layer "F.Fab")
			(effects
				(font
					(size 0.7 0.7)
					(thickness 0.15)
				)
				(justify left bottom)
			)
		)
		(fp_text user "License: Apache-2.0"
			(at -1.4224 3.599 90)
			(layer "F.Fab")
			(effects
				(font
					(size 0.7 0.7)
					(thickness 0.15)
				)
				(justify left bottom)
			)
		)
		(fp_text user "Author: Antmicro"
			(at -1.4224 4.799 90)
			(layer "F.Fab")
			(effects
				(font
					(size 0.7 0.7)
					(thickness 0.15)
				)
				(justify left bottom)
			)
		)
		(pad "1" smd roundrect
			(at -0.7 0 270)
			(size 0.8 1)
			(layers "F.Cu" "F.Mask" "F.Paste")
			(roundrect_rratio 0.2)
			(net 1 "GND")
			(pinfunction "C")
			(pintype "passive")
		)
		(pad "2" smd roundrect
			(at 0.7 0 270)
			(size 0.8 1)
			(layers "F.Cu" "F.Mask" "F.Paste")
			(roundrect_rratio 0.2)
			(net 63 "Net-(D3-A)")
			(pinfunction "A")
			(pintype "passive")
		)
	)
	(footprint "antmicro-footprints:C_0603_1608Metric"
		(layer "F.Cu")
		(at 138.84 105 -90)
		(descr "Capacitor SMD 0603")
		(tags "capacitor 0603")
		(property "Reference" "C29"
			(at -3.46 -0.39 90)
			(layer "F.SilkS")
			(effects
				(font
					(size 0.65 0.65)
					(thickness 0.15)
				)
				(justify right bottom)
			)
		)
		(property "Value" "C_1u_0603"
			(at 0 1.6 90)
			(layer "F.Fab")
			(hide yes)
			(effects
				(font
					(size 0.7 0.7)
					(thickness 0.15)
				)
				(justify right bottom)
			)
		)
		(property "Datasheet" "https://spicat.kyocera-avx.com/product/mlcc/chartview/0603YD105KAT2A/"
			(at 0 0 90)
			(layer "F.Fab")
			(hide yes)
			(effects
				(font
					(size 1.27 1.27)
					(thickness 0.15)
				)
			)
		)
		(property "Description" "SMD Multilayer Ceramic Capacitor, 1 µF, 16 V, 0603 [1608 Metric], ± 10%, X5R, AVX 0603 MLCC"
			(at 0 0 90)
			(layer "F.Fab")
			(hide yes)
			(effects
				(font
					(size 1.27 1.27)
					(thickness 0.15)
				)
			)
		)
		(property "Author" "Antmicro"
			(at 33.84 243.84 0)
			(layer "F.Fab")
			(hide yes)
			(effects
				(font
					(size 1 1)
					(thickness 0.15)
				)
			)
		)
		(property "Dielectric" ""
			(at 33.84 243.84 0)
			(layer "F.Fab")
			(hide yes)
			(effects
				(font
					(size 1 1)
					(thickness 0.15)
				)
			)
		)
		(property "License" "Apache-2.0"
			(at 33.84 243.84 0)
			(layer "F.Fab")
			(hide yes)
			(effects
				(font
					(size 1 1)
					(thickness 0.15)
				)
			)
		)
		(property "MPN" "0603YD105KAT2A"
			(at 33.84 243.84 0)
			(layer "F.Fab")
			(hide yes)
			(effects
				(font
					(size 1 1)
					(thickness 0.15)
				)
			)
		)
		(property "Manufacturer" "KYOCERA AVX"
			(at 33.84 243.84 0)
			(layer "F.Fab")
			(hide yes)
			(effects
				(font
					(size 1 1)
					(thickness 0.15)
				)
			)
		)
		(property "Val" "1u"
			(at 33.84 243.84 0)
			(layer "F.Fab")
			(hide yes)
			(effects
				(font
					(size 1 1)
					(thickness 0.15)
				)
			)
		)
		(property "Voltage" ""
			(at 33.84 243.84 0)
			(layer "F.Fab")
			(hide yes)
			(effects
				(font
					(size 1 1)
					(thickness 0.15)
				)
			)
		)
		(sheetname "/Power Supply/")
		(sheetfile "supply.kicad_sch")
		(attr smd)
		(fp_line
			(start -0.15 0.4)
			(end 0.15 0.4)
			(stroke
				(width 0.15)
				(type solid)
			)
			(layer "F.SilkS")
		)
		(fp_line
			(start -0.15 -0.4)
			(end 0.15 -0.4)
			(stroke
				(width 0.15)
				(type solid)
			)
			(layer "F.SilkS")
		)
		(fp_rect
			(start -1.25 -0.65)
			(end 1.25 0.65)
			(stroke
				(width 0.05)
				(type solid)
			)
			(fill no)
			(layer "F.CrtYd")
		)
		(fp_rect
			(start -0.8 -0.4)
			(end 0.8 0.4)
			(stroke
				(width 0.15)
				(type solid)
			)
			(fill no)
			(layer "F.Fab")
		)
		(fp_text user "Author: Antmicro"
			(at -1.682 4.894 270)
			(layer "F.Fab")
			(effects
				(font
					(size 0.7 0.7)
					(thickness 0.15)
				)
				(justify left bottom)
			)
		)
		(fp_text user "${REFERENCE}"
			(at -1.682 3.895 270)
			(layer "F.Fab")
			(effects
				(font
					(size 0.7 0.7)
					(thickness 0.15)
				)
				(justify left bottom)
			)
		)
		(fp_text user "License: Apache-2.0"
			(at -1.682 5.895 270)
			(layer "F.Fab")
			(effects
				(font
					(size 0.7 0.7)
					(thickness 0.15)
				)
				(justify left bottom)
			)
		)
		(pad "1" smd roundrect
			(at -0.7 0 270)
			(size 0.8 1)
			(layers "F.Cu" "F.Mask" "F.Paste")
			(roundrect_rratio 0.2)
			(net 1 "GND")
			(pintype "passive")
		)
		(pad "2" smd roundrect
			(at 0.7 0 270)
			(size 0.8 1)
			(layers "F.Cu" "F.Mask" "F.Paste")
			(roundrect_rratio 0.2)
			(net 49 "1V0_Clean")
			(pintype "passive")
		)
	)
	(footprint "antmicro-footprints:R_0402_1005Metric"
		(layer "F.Cu")
		(at 138.49 109.6)
		(descr "Resistor SMD 0402")
		(tags "resistor SMD 0402")
		(property "Reference" "R36"
			(at -3.66 0.34 0)
			(layer "F.SilkS")
			(effects
				(font
					(size 0.65 0.65)
					(thickness 0.15)
				)
				(justify left bottom)
			)
		)
		(property "Value" "R_15k_0402"
			(at 0 1.4 0)
			(layer "F.Fab")
			(hide yes)
			(effects
				(font
					(size 0.7 0.7)
					(thickness 0.15)
				)
				(justify left bottom)
			)
		)
		(property "Datasheet" "https://www.bourns.com/docs/product-datasheets/cr.pdf"
			(at 0 0 0)
			(layer "F.Fab")
			(hide yes)
			(effects
				(font
					(size 1.27 1.27)
					(thickness 0.15)
				)
			)
		)
		(property "Description" "SMD Chip Resistor, 15 kohm, ± 1%, 62.5 mW, 0402 [1005 Metric], Thick Film, General Purpose"
			(at 0 0 0)
			(layer "F.Fab")
			(hide yes)
			(effects
				(font
					(size 1.27 1.27)
					(thickness 0.15)
				)
			)
		)
		(property "Author" "Antmicro"
			(at 0 0 0)
			(layer "F.Fab")
			(hide yes)
			(effects
				(font
					(size 1 1)
					(thickness 0.15)
				)
			)
		)
		(property "License" "Apache-2.0"
			(at 0 0 0)
			(layer "F.Fab")
			(hide yes)
			(effects
				(font
					(size 1 1)
					(thickness 0.15)
				)
			)
		)
		(property "MPN" "CR0402-FX-1502GLF"
			(at 0 0 0)
			(layer "F.Fab")
			(hide yes)
			(effects
				(font
					(size 1 1)
					(thickness 0.15)
				)
			)
		)
		(property "Manufacturer" "Bourns"
			(at 0 0 0)
			(layer "F.Fab")
			(hide yes)
			(effects
				(font
					(size 1 1)
					(thickness 0.15)
				)
			)
		)
		(property "Tolerance" "1%"
			(at 0 0 0)
			(layer "F.Fab")
			(hide yes)
			(effects
				(font
					(size 1 1)
					(thickness 0.15)
				)
			)
		)
		(property "Val" "15k"
			(at 0 0 0)
			(layer "F.Fab")
			(hide yes)
			(effects
				(font
					(size 1 1)
					(thickness 0.15)
				)
			)
		)
		(sheetname "/Power Supply/")
		(sheetfile "supply.kicad_sch")
		(attr smd)
		(fp_rect
			(start -0.925 -0.47)
			(end 0.925 0.47)
			(stroke
				(width 0.05)
				(type default)
			)
			(fill no)
			(layer "F.CrtYd")
		)
		(fp_rect
			(start -0.5 -0.25)
			(end 0.5 0.25)
			(stroke
				(width 0.15)
				(type solid)
			)
			(fill no)
			(layer "F.Fab")
		)
		(fp_text user "${REFERENCE}"
			(at -0.95 3.168 0)
			(layer "F.Fab")
			(effects
				(font
					(size 0.7 0.7)
					(thickness 0.15)
				)
				(justify left bottom)
			)
		)
		(fp_text user "Author: Antmicro"
			(at -0.95 4.169 0)
			(layer "F.Fab")
			(effects
				(font
					(size 0.7 0.7)
					(thickness 0.15)
				)
				(justify left bottom)
			)
		)
		(fp_text user "License: Apache-2.0"
			(at -0.95 5.169 0)
			(layer "F.Fab")
			(effects
				(font
					(size 0.7 0.7)
					(thickness 0.15)
				)
				(justify left bottom)
			)
		)
		(pad "1" smd roundrect
			(at -0.48 0)
			(size 0.59 0.64)
			(layers "F.Cu" "F.Mask" "F.Paste")
			(roundrect_rratio 0.25)
			(net 1 "GND")
			(pintype "passive")
		)
		(pad "2" smd roundrect
			(at 0.48 0)
			(size 0.59 0.64)
			(layers "F.Cu" "F.Mask" "F.Paste")
			(roundrect_rratio 0.25)
			(net 283 "Net-(U10-ADJ)")
			(pintype "passive")
		)
	)
	(footprint "antmicro-footprints:C_0402_1005Metric"
		(layer "F.Cu")
		(at 87.6 79.4 180)
		(descr "Capacitor SMD 0402")
		(tags "capacitor SMD 0402")
		(property "Reference" "C56"
			(at 0.67 6.16 0)
			(layer "F.SilkS")
			(effects
				(font
					(size 0.65 0.65)
					(thickness 0.15)
				)
				(justify right bottom)
			)
		)
		(property "Value" "C_470n_0402"
			(at 0 1.4 0)
			(layer "F.Fab")
			(hide yes)
			(effects
				(font
					(size 0.7 0.7)
					(thickness 0.15)
				)
				(justify right bottom)
			)
		)
		(property "Datasheet" "https://product.tdk.com/en/search/capacitor/ceramic/mlcc/info?part_no=C1005X5R1E474M050BB"
			(at 0 0 180)
			(layer "F.Fab")
			(hide yes)
			(effects
				(font
					(size 1.27 1.27)
					(thickness 0.15)
				)
			)
		)
		(property "Description" "SMD Multilayer Ceramic Capacitor, 0.47 µF, 25 V, 0402 [1005 Metric], ± 20%, X5R, C"
			(at 0 0 180)
			(layer "F.Fab")
			(hide yes)
			(effects
				(font
					(size 1.27 1.27)
					(thickness 0.15)
				)
			)
		)
		(property "Author" "Antmicro"
			(at 175.2 158.8 0)
			(layer "F.Fab")
			(hide yes)
			(effects
				(font
					(size 1 1)
					(thickness 0.15)
				)
			)
		)
		(property "Dielectric" ""
			(at 175.2 158.8 0)
			(layer "F.Fab")
			(hide yes)
			(effects
				(font
					(size 1 1)
					(thickness 0.15)
				)
			)
		)
		(property "License" "Apache-2.0"
			(at 175.2 158.8 0)
			(layer "F.Fab")
			(hide yes)
			(effects
				(font
					(size 1 1)
					(thickness 0.15)
				)
			)
		)
		(property "MPN" "C1005X5R1E474M050BB"
			(at 175.2 158.8 0)
			(layer "F.Fab")
			(hide yes)
			(effects
				(font
					(size 1 1)
					(thickness 0.15)
				)
			)
		)
		(property "Manufacturer" "TDK"
			(at 175.2 158.8 0)
			(layer "F.Fab")
			(hide yes)
			(effects
				(font
					(size 1 1)
					(thickness 0.15)
				)
			)
		)
		(property "Val" "470n"
			(at 175.2 158.8 0)
			(layer "F.Fab")
			(hide yes)
			(effects
				(font
					(size 1 1)
					(thickness 0.15)
				)
			)
		)
		(property "Voltage" ""
			(at 175.2 158.8 0)
			(layer "F.Fab")
			(hide yes)
			(effects
				(font
					(size 1 1)
					(thickness 0.15)
				)
			)
		)
		(sheetname "/SDI/")
		(sheetfile "sdi.kicad_sch")
		(attr smd)
		(fp_rect
			(start -0.925 -0.47)
			(end 0.925 0.47)
			(stroke
				(width 0.05)
				(type default)
			)
			(fill no)
			(layer "F.CrtYd")
		)
		(fp_line
			(start 0.504 0.248)
			(end -0.494 0.248)
			(stroke
				(width 0.15)
				(type solid)
			)
			(layer "F.Fab")
		)
		(fp_line
			(start 0.504 -0.25)
			(end 0.504 0.248)
			(stroke
				(width 0.15)
				(type solid)
			)
			(layer "F.Fab")
		)
		(fp_line
			(start -0.494 0.248)
			(end -0.494 -0.25)
			(stroke
				(width 0.15)
				(type solid)
			)
			(layer "F.Fab")
		)
		(fp_line
			(start -0.494 -0.25)
			(end 0.504 -0.25)
			(stroke
				(width 0.15)
				(type solid)
			)
			(layer "F.Fab")
		)
		(fp_text user "License: Apache-2.0"
			(at -0.939 5.799 180)
			(layer "F.Fab")
			(effects
				(font
					(size 0.7 0.7)
					(thickness 0.15)
				)
				(justify left bottom)
			)
		)
		(fp_text user "Author: Antmicro"
			(at -0.939 3.399 180)
			(layer "F.Fab")
			(effects
				(font
					(size 0.7 0.7)
					(thickness 0.15)
				)
				(justify left bottom)
			)
		)
		(fp_text user "${REFERENCE}"
			(at -0.939 4.599 180)
			(layer "F.Fab")
			(effects
				(font
					(size 0.7 0.7)
					(thickness 0.15)
				)
				(justify left bottom)
			)
		)
		(pad "1" smd roundrect
			(at -0.48 0 180)
			(size 0.59 0.64)
			(layers "F.Cu" "F.Mask" "F.Paste")
			(roundrect_rratio 0.25)
			(net 291 "/SDI/AGC_N")
			(pintype "passive")
		)
		(pad "2" smd roundrect
			(at 0.48 0 180)
			(size 0.59 0.64)
			(layers "F.Cu" "F.Mask" "F.Paste")
			(roundrect_rratio 0.25)
			(net 1 "GND")
			(pintype "passive")
		)
	)
	(footprint "antmicro-footprints:R_0402_1005Metric"
		(layer "F.Cu")
		(at 88 77.9 -90)
		(descr "Resistor SMD 0402")
		(tags "resistor SMD 0402")
		(property "Reference" "R53"
			(at -7.66 1.17 90)
			(layer "F.SilkS")
			(effects
				(font
					(size 0.65 0.65)
					(thickness 0.15)
				)
				(justify right bottom)
			)
		)
		(property "Value" "R_37R4_0402"
			(at 0 1.4 90)
			(layer "F.Fab")
			(hide yes)
			(effects
				(font
					(size 0.7 0.7)
					(thickness 0.15)
				)
				(justify right bottom)
			)
		)
		(property "Datasheet" "https://www.bourns.com/docs/product-datasheets/cr.pdf"
			(at 0 0 270)
			(layer "F.Fab")
			(hide yes)
			(effects
				(font
					(size 1.27 1.27)
					(thickness 0.15)
				)
			)
		)
		(property "Description" "SMD Chip Resistor, 37.4 ohm, ± 1%, 100 mW, 0402 [1005 Metric], Thick Film, Precision"
			(at 0 0 270)
			(layer "F.Fab")
			(hide yes)
			(effects
				(font
					(size 1.27 1.27)
					(thickness 0.15)
				)
			)
		)
		(property "Author" "Antmicro"
			(at 10.1 165.9 0)
			(layer "F.Fab")
			(hide yes)
			(effects
				(font
					(size 1 1)
					(thickness 0.15)
				)
			)
		)
		(property "License" "Apache-2.0"
			(at 10.1 165.9 0)
			(layer "F.Fab")
			(hide yes)
			(effects
				(font
					(size 1 1)
					(thickness 0.15)
				)
			)
		)
		(property "MPN" "CR0402-FX-37R4GLF"
			(at 10.1 165.9 0)
			(layer "F.Fab")
			(hide yes)
			(effects
				(font
					(size 1 1)
					(thickness 0.15)
				)
			)
		)
		(property "Manufacturer" "Bourns"
			(at 10.1 165.9 0)
			(layer "F.Fab")
			(hide yes)
			(effects
				(font
					(size 1 1)
					(thickness 0.15)
				)
			)
		)
		(property "Tolerance" "1%"
			(at 10.1 165.9 0)
			(layer "F.Fab")
			(hide yes)
			(effects
				(font
					(size 1 1)
					(thickness 0.15)
				)
			)
		)
		(property "Val" "37R4"
			(at 10.1 165.9 0)
			(layer "F.Fab")
			(hide yes)
			(effects
				(font
					(size 1 1)
					(thickness 0.15)
				)
			)
		)
		(sheetname "/SDI/")
		(sheetfile "sdi.kicad_sch")
		(attr smd)
		(fp_rect
			(start -0.925 -0.47)
			(end 0.925 0.47)
			(stroke
				(width 0.05)
				(type default)
			)
			(fill no)
			(layer "F.CrtYd")
		)
		(fp_rect
			(start -0.5 -0.25)
			(end 0.5 0.25)
			(stroke
				(width 0.15)
				(type solid)
			)
			(fill no)
			(layer "F.Fab")
		)
		(fp_text user "License: Apache-2.0"
			(at -0.95 5.169 270)
			(layer "F.Fab")
			(effects
				(font
					(size 0.7 0.7)
					(thickness 0.15)
				)
				(justify left bottom)
			)
		)
		(fp_text user "Author: Antmicro"
			(at -0.95 4.169 270)
			(layer "F.Fab")
			(effects
				(font
					(size 0.7 0.7)
					(thickness 0.15)
				)
				(justify left bottom)
			)
		)
		(fp_text user "${REFERENCE}"
			(at -0.95 3.168 270)
			(layer "F.Fab")
			(effects
				(font
					(size 0.7 0.7)
					(thickness 0.15)
				)
				(justify left bottom)
			)
		)
		(pad "1" smd roundrect
			(at -0.48 0 270)
			(size 0.59 0.64)
			(layers "F.Cu" "F.Mask" "F.Paste")
			(roundrect_rratio 0.25)
			(net 293 "/SDI/SDI_N2")
			(pintype "passive")
		)
		(pad "2" smd roundrect
			(at 0.48 0 270)
			(size 0.59 0.64)
			(layers "F.Cu" "F.Mask" "F.Paste")
			(roundrect_rratio 0.25)
			(net 1 "GND")
			(pintype "passive")
		)
	)
	(footprint "antmicro-footprints:R_0402_1005Metric"
		(layer "F.Cu")
		(at 91.8 69.2 -90)
		(descr "Resistor SMD 0402")
		(tags "resistor SMD 0402")
		(property "Reference" "R54"
			(at -1.31 -0.48 270)
			(layer "F.SilkS")
			(effects
				(font
					(size 0.65 0.65)
					(thickness 0.15)
				)
				(justify left bottom)
			)
		)
		(property "Value" "R_100k_0402"
			(at 0 1.4 270)
			(layer "F.Fab")
			(hide yes)
			(effects
				(font
					(size 0.7 0.7)
					(thickness 0.15)
				)
				(justify left bottom)
			)
		)
		(property "Datasheet" "https://www.bourns.com/docs/product-datasheets/cr.pdf"
			(at 0 0 270)
			(layer "F.Fab")
			(hide yes)
			(effects
				(font
					(size 1.27 1.27)
					(thickness 0.15)
				)
			)
		)
		(property "Description" "SMD Chip Resistor, 100 kohm, ± 1%, 62.5 mW, 0402 [1005 Metric], Thick Film, General Purpose"
			(at 0 0 270)
			(layer "F.Fab")
			(hide yes)
			(effects
				(font
					(size 1.27 1.27)
					(thickness 0.15)
				)
			)
		)
		(property "Author" "Antmicro"
			(at 22.6 161 0)
			(layer "F.Fab")
			(hide yes)
			(effects
				(font
					(size 1 1)
					(thickness 0.15)
				)
			)
		)
		(property "License" "Apache-2.0"
			(at 22.6 161 0)
			(layer "F.Fab")
			(hide yes)
			(effects
				(font
					(size 1 1)
					(thickness 0.15)
				)
			)
		)
		(property "MPN" "CR0402-FX-1003GLF"
			(at 22.6 161 0)
			(layer "F.Fab")
			(hide yes)
			(effects
				(font
					(size 1 1)
					(thickness 0.15)
				)
			)
		)
		(property "Manufacturer" "Bourns"
			(at 22.6 161 0)
			(layer "F.Fab")
			(hide yes)
			(effects
				(font
					(size 1 1)
					(thickness 0.15)
				)
			)
		)
		(property "Tolerance" "1%"
			(at 22.6 161 0)
			(layer "F.Fab")
			(hide yes)
			(effects
				(font
					(size 1 1)
					(thickness 0.15)
				)
			)
		)
		(property "Val" "100k"
			(at 22.6 161 0)
			(layer "F.Fab")
			(hide yes)
			(effects
				(font
					(size 1 1)
					(thickness 0.15)
				)
			)
		)
		(sheetname "/SDI/")
		(sheetfile "sdi.kicad_sch")
		(attr smd)
		(fp_rect
			(start -0.925 -0.47)
			(end 0.925 0.47)
			(stroke
				(width 0.05)
				(type default)
			)
			(fill no)
			(layer "F.CrtYd")
		)
		(fp_rect
			(start -0.5 -0.25)
			(end 0.5 0.25)
			(stroke
				(width 0.15)
				(type solid)
			)
			(fill no)
			(layer "F.Fab")
		)
		(fp_text user "License: Apache-2.0"
			(at -0.95 5.169 270)
			(layer "F.Fab")
			(effects
				(font
					(size 0.7 0.7)
					(thickness 0.15)
				)
				(justify left bottom)
			)
		)
		(fp_text user "${REFERENCE}"
			(at -0.95 3.168 270)
			(layer "F.Fab")
			(effects
				(font
					(size 0.7 0.7)
					(thickness 0.15)
				)
				(justify left bottom)
			)
		)
		(fp_text user "Author: Antmicro"
			(at -0.95 4.169 270)
			(layer "F.Fab")
			(effects
				(font
					(size 0.7 0.7)
					(thickness 0.15)
				)
				(justify left bottom)
			)
		)
		(pad "1" smd roundrect
			(at -0.48 0 270)
			(size 0.59 0.64)
			(layers "F.Cu" "F.Mask" "F.Paste")
			(roundrect_rratio 0.25)
			(net 1 "GND")
			(pintype "passive")
		)
		(pad "2" smd roundrect
			(at 0.48 0 270)
			(size 0.59 0.64)
			(layers "F.Cu" "F.Mask" "F.Paste")
			(roundrect_rratio 0.25)
			(net 288 "Net-(U15B-LB_CONT)")
			(pintype "passive")
		)
	)
	(footprint "antmicro-footprints:C_0402_1005Metric"
		(layer "F.Cu")
		(at 159.925 88.3 -90)
		(descr "Capacitor SMD 0402")
		(tags "capacitor SMD 0402")
		(property "Reference" "C109"
			(at -3.76 -0.405 90)
			(layer "F.SilkS")
			(effects
				(font
					(size 0.65 0.65)
					(thickness 0.15)
				)
				(justify right bottom)
			)
		)
		(property "Value" "C_100n_0402"
			(at 0 1.4 90)
			(layer "F.Fab")
			(hide yes)
			(effects
				(font
					(size 0.7 0.7)
					(thickness 0.15)
				)
				(justify right bottom)
			)
		)
		(property "Datasheet" "https://www.murata.com/products/productdetail?partno=GRM155R61H104KE14%23"
			(at 0 0 270)
			(layer "F.Fab")
			(hide yes)
			(effects
				(font
					(size 1.27 1.27)
					(thickness 0.15)
				)
			)
		)
		(property "Description" "SMD Multilayer Ceramic Capacitor, 0.1 µF, 50 V, 0402 [1005 Metric], ± 10%, X5R, GRM Series"
			(at 0 0 270)
			(layer "F.Fab")
			(hide yes)
			(effects
				(font
					(size 1.27 1.27)
					(thickness 0.15)
				)
			)
		)
		(property "Author" "Antmicro"
			(at 71.625 248.225 0)
			(layer "F.Fab")
			(hide yes)
			(effects
				(font
					(size 1 1)
					(thickness 0.15)
				)
			)
		)
		(property "Dielectric" "X5R"
			(at 71.625 248.225 0)
			(layer "F.Fab")
			(hide yes)
			(effects
				(font
					(size 1 1)
					(thickness 0.15)
				)
			)
		)
		(property "License" "Apache-2.0"
			(at 71.625 248.225 0)
			(layer "F.Fab")
			(hide yes)
			(effects
				(font
					(size 1 1)
					(thickness 0.15)
				)
			)
		)
		(property "MPN" "GRM155R61H104KE14D"
			(at 71.625 248.225 0)
			(layer "F.Fab")
			(hide yes)
			(effects
				(font
					(size 1 1)
					(thickness 0.15)
				)
			)
		)
		(property "Manufacturer" "Murata"
			(at 71.625 248.225 0)
			(layer "F.Fab")
			(hide yes)
			(effects
				(font
					(size 1 1)
					(thickness 0.15)
				)
			)
		)
		(property "Val" "100n"
			(at 71.625 248.225 0)
			(layer "F.Fab")
			(hide yes)
			(effects
				(font
					(size 1 1)
					(thickness 0.15)
				)
			)
		)
		(property "Voltage" "50V"
			(at 71.625 248.225 0)
			(layer "F.Fab")
			(hide yes)
			(effects
				(font
					(size 1 1)
					(thickness 0.15)
				)
			)
		)
		(sheetname "/Peripherals/")
		(sheetfile "peripherals.kicad_sch")
		(attr smd)
		(fp_rect
			(start -0.925 -0.47)
			(end 0.925 0.47)
			(stroke
				(width 0.05)
				(type default)
			)
			(fill no)
			(layer "F.CrtYd")
		)
		(fp_line
			(start -0.494 0.248)
			(end -0.494 -0.25)
			(stroke
				(width 0.15)
				(type solid)
			)
			(layer "F.Fab")
		)
		(fp_line
			(start 0.504 0.248)
			(end -0.494 0.248)
			(stroke
				(width 0.15)
				(type solid)
			)
			(layer "F.Fab")
		)
		(fp_line
			(start -0.494 -0.25)
			(end 0.504 -0.25)
			(stroke
				(width 0.15)
				(type solid)
			)
			(layer "F.Fab")
		)
		(fp_line
			(start 0.504 -0.25)
			(end 0.504 0.248)
			(stroke
				(width 0.15)
				(type solid)
			)
			(layer "F.Fab")
		)
		(fp_text user "${REFERENCE}"
			(at -0.939 4.599 270)
			(layer "F.Fab")
			(effects
				(font
					(size 0.7 0.7)
					(thickness 0.15)
				)
				(justify left bottom)
			)
		)
		(fp_text user "License: Apache-2.0"
			(at -0.939 5.799 270)
			(layer "F.Fab")
			(effects
				(font
					(size 0.7 0.7)
					(thickness 0.15)
				)
				(justify left bottom)
			)
		)
		(fp_text user "Author: Antmicro"
			(at -0.939 3.399 270)
			(layer "F.Fab")
			(effects
				(font
					(size 0.7 0.7)
					(thickness 0.15)
				)
				(justify left bottom)
			)
		)
		(pad "1" smd roundrect
			(at -0.48 0 270)
			(size 0.59 0.64)
			(layers "F.Cu" "F.Mask" "F.Paste")
			(roundrect_rratio 0.25)
			(net 1 "GND")
			(pintype "passive")
		)
		(pad "2" smd roundrect
			(at 0.48 0 270)
			(size 0.59 0.64)
			(layers "F.Cu" "F.Mask" "F.Paste")
			(roundrect_rratio 0.25)
			(net 2 "+3V3")
			(pintype "passive")
		)
	)
	(footprint "antmicro-footprints:TP_SMD_0.75mm"
		(layer "F.Cu")
		(at 109.09 91.3 -90)
		(property "Reference" "TP21"
			(at -0.16 -1.24 270)
			(layer "F.SilkS")
			(effects
				(font
					(size 0.65 0.65)
					(thickness 0.15)
				)
				(justify left bottom)
			)
		)
		(property "Value" "TP_0.75mm_SMD"
			(at 0 1.2 90)
			(layer "F.Fab")
			(hide yes)
			(effects
				(font
					(size 0.7 0.7)
					(thickness 0.15)
				)
				(justify right bottom)
			)
		)
		(property "Description" "SMT test point"
			(at 0 0 270)
			(layer "F.Fab")
			(hide yes)
			(effects
				(font
					(size 1.27 1.27)
					(thickness 0.15)
				)
			)
		)
		(property "Author" "Antmicro"
			(at 17.79 200.39 0)
			(layer "F.Fab")
			(hide yes)
			(effects
				(font
					(size 1 1)
					(thickness 0.15)
				)
			)
		)
		(property "License" "Apache-2.0"
			(at 17.79 200.39 0)
			(layer "F.Fab")
			(hide yes)
			(effects
				(font
					(size 1 1)
					(thickness 0.15)
				)
			)
		)
		(property "MPN" ""
			(at 17.79 200.39 0)
			(layer "F.Fab")
			(hide yes)
			(effects
				(font
					(size 1 1)
					(thickness 0.15)
				)
			)
		)
		(property "Manufacturer" ""
			(at 17.79 200.39 0)
			(layer "F.Fab")
			(hide yes)
			(effects
				(font
					(size 1 1)
					(thickness 0.15)
				)
			)
		)
		(sheetname "/FPGA/")
		(sheetfile "fpga.kicad_sch")
		(attr exclude_from_pos_files)
		(fp_circle
			(center 0 0)
			(end 0.475 0)
			(stroke
				(width 0.05)
				(type default)
			)
			(fill no)
			(layer "F.CrtYd")
		)
		(fp_text user "License: Apache-2.0"
			(at -0.4 5.101 270)
			(layer "F.Fab")
			(effects
				(font
					(size 0.7 0.7)
					(thickness 0.15)
				)
				(justify left bottom)
			)
		)
		(fp_text user "${REFERENCE}"
			(at -0.4 2.7 270)
			(layer "F.Fab")
			(effects
				(font
					(size 0.7 0.7)
					(thickness 0.15)
				)
				(justify left bottom)
			)
		)
		(fp_text user "Author: Antmicro"
			(at -0.4 3.901 270)
			(layer "F.Fab")
			(effects
				(font
					(size 0.7 0.7)
					(thickness 0.15)
				)
				(justify left bottom)
			)
		)
		(pad "1" smd circle
			(at 0 0 270)
			(size 0.75 0.75)
			(layers "F.Cu" "F.Mask")
			(net 324 "Net-(U21-D4)")
			(pinfunction "1")
			(pintype "passive")
		)
	)
	(footprint "antmicro-footprints:TP_SMD_0.75mm"
		(layer "F.Cu")
		(at 167.09 66.1 -90)
		(property "Reference" "TP12"
			(at 0.44 -0.64 0)
			(layer "F.SilkS")
			(effects
				(font
					(size 0.65 0.65)
					(thickness 0.15)
				)
				(justify left bottom)
			)
		)
		(property "Value" "TP_0.75mm_SMD"
			(at 0 1.2 270)
			(layer "F.Fab")
			(hide yes)
			(effects
				(font
					(size 0.7 0.7)
					(thickness 0.15)
				)
				(justify left bottom)
			)
		)
		(property "Description" "SMT test point"
			(at 0 0 270)
			(layer "F.Fab")
			(hide yes)
			(effects
				(font
					(size 1.27 1.27)
					(thickness 0.15)
				)
			)
		)
		(property "Author" "Antmicro"
			(at 100.99 233.19 0)
			(layer "F.Fab")
			(hide yes)
			(effects
				(font
					(size 1 1)
					(thickness 0.15)
				)
			)
		)
		(property "License" "Apache-2.0"
			(at 100.99 233.19 0)
			(layer "F.Fab")
			(hide yes)
			(effects
				(font
					(size 1 1)
					(thickness 0.15)
				)
			)
		)
		(property "MPN" ""
			(at 100.99 233.19 0)
			(layer "F.Fab")
			(hide yes)
			(effects
				(font
					(size 1 1)
					(thickness 0.15)
				)
			)
		)
		(property "Manufacturer" ""
			(at 100.99 233.19 0)
			(layer "F.Fab")
			(hide yes)
			(effects
				(font
					(size 1 1)
					(thickness 0.15)
				)
			)
		)
		(sheetname "/Power Supply/")
		(sheetfile "supply.kicad_sch")
		(attr exclude_from_pos_files)
		(fp_circle
			(center 0 0)
			(end 0.475 0)
			(stroke
				(width 0.05)
				(type default)
			)
			(fill no)
			(layer "F.CrtYd")
		)
		(fp_text user "${REFERENCE}"
			(at -0.4 2.7 270)
			(layer "F.Fab")
			(effects
				(font
					(size 0.7 0.7)
					(thickness 0.15)
				)
				(justify left bottom)
			)
		)
		(fp_text user "Author: Antmicro"
			(at -0.4 3.901 270)
			(layer "F.Fab")
			(effects
				(font
					(size 0.7 0.7)
					(thickness 0.15)
				)
				(justify left bottom)
			)
		)
		(fp_text user "License: Apache-2.0"
			(at -0.4 5.101 270)
			(layer "F.Fab")
			(effects
				(font
					(size 0.7 0.7)
					(thickness 0.15)
				)
				(justify left bottom)
			)
		)
		(pad "1" smd circle
			(at 0 0 270)
			(size 0.75 0.75)
			(layers "F.Cu" "F.Mask")
			(net 375 "Net-(U7-EN)")
			(pinfunction "1")
			(pintype "passive")
		)
	)
	(footprint "antmicro-footprints:R_0402_1005Metric"
		(layer "F.Cu")
		(at 131.75 116.75 90)
		(descr "Resistor SMD 0402")
		(tags "resistor SMD 0402")
		(property "Reference" "R110"
			(at 0.81 0.28 90)
			(layer "F.SilkS")
			(effects
				(font
					(size 0.65 0.65)
					(thickness 0.15)
				)
				(justify left bottom)
			)
		)
		(property "Value" "R_0R_0402"
			(at 0 1.4 90)
			(layer "F.Fab")
			(hide yes)
			(effects
				(font
					(size 0.7 0.7)
					(thickness 0.15)
				)
				(justify left bottom)
			)
		)
		(property "Datasheet" "https://industrial.panasonic.com/cdbs/www-data/pdf/RDA0000/AOA0000C301.pdf"
			(at 0 0 90)
			(layer "F.Fab")
			(hide yes)
			(effects
				(font
					(size 1.27 1.27)
					(thickness 0.15)
				)
			)
		)
		(property "Description" "SMD Chip Resistor, Jumper, 0 ohm, 100 mW, 0402 [1005 Metric], Thick Film, General Purpose"
			(at 0 0 90)
			(layer "F.Fab")
			(hide yes)
			(effects
				(font
					(size 1.27 1.27)
					(thickness 0.15)
				)
			)
		)
		(property "Author" "Antmicro"
			(at 248.5 -15 0)
			(layer "F.Fab")
			(hide yes)
			(effects
				(font
					(size 1 1)
					(thickness 0.15)
				)
			)
		)
		(property "Current" "1A"
			(at 248.5 -15 0)
			(layer "F.Fab")
			(hide yes)
			(effects
				(font
					(size 1 1)
					(thickness 0.15)
				)
			)
		)
		(property "License" "Apache-2.0"
			(at 248.5 -15 0)
			(layer "F.Fab")
			(hide yes)
			(effects
				(font
					(size 1 1)
					(thickness 0.15)
				)
			)
		)
		(property "MPN" "ERJ2GE0R00X"
			(at 248.5 -15 0)
			(layer "F.Fab")
			(hide yes)
			(effects
				(font
					(size 1 1)
					(thickness 0.15)
				)
			)
		)
		(property "Manufacturer" "Panasonic"
			(at 248.5 -15 0)
			(layer "F.Fab")
			(hide yes)
			(effects
				(font
					(size 1 1)
					(thickness 0.15)
				)
			)
		)
		(property "Tolerance" "~"
			(at 248.5 -15 0)
			(layer "F.Fab")
			(hide yes)
			(effects
				(font
					(size 1 1)
					(thickness 0.15)
				)
			)
		)
		(property "Val" "0R"
			(at 248.5 -15 0)
			(layer "F.Fab")
			(hide yes)
			(effects
				(font
					(size 1 1)
					(thickness 0.15)
				)
			)
		)
		(sheetname "/Peripherals/")
		(sheetfile "peripherals.kicad_sch")
		(attr smd)
		(fp_rect
			(start -0.925 -0.47)
			(end 0.925 0.47)
			(stroke
				(width 0.05)
				(type default)
			)
			(fill no)
			(layer "F.CrtYd")
		)
		(fp_rect
			(start -0.5 -0.25)
			(end 0.5 0.25)
			(stroke
				(width 0.15)
				(type solid)
			)
			(fill no)
			(layer "F.Fab")
		)
		(fp_text user "License: Apache-2.0"
			(at -0.95 5.169 90)
			(layer "F.Fab")
			(effects
				(font
					(size 0.7 0.7)
					(thickness 0.15)
				)
				(justify left bottom)
			)
		)
		(fp_text user "Author: Antmicro"
			(at -0.95 4.169 90)
			(layer "F.Fab")
			(effects
				(font
					(size 0.7 0.7)
					(thickness 0.15)
				)
				(justify left bottom)
			)
		)
		(fp_text user "${REFERENCE}"
			(at -0.95 3.168 90)
			(layer "F.Fab")
			(effects
				(font
					(size 0.7 0.7)
					(thickness 0.15)
				)
				(justify left bottom)
			)
		)
		(pad "1" smd roundrect
			(at -0.48 0 90)
			(size 0.59 0.64)
			(layers "F.Cu" "F.Mask" "F.Paste")
			(roundrect_rratio 0.25)
			(net 302 "Net-(J6-Pad40)")
			(pintype "passive")
		)
		(pad "2" smd roundrect
			(at 0.48 0 90)
			(size 0.59 0.64)
			(layers "F.Cu" "F.Mask" "F.Paste")
			(roundrect_rratio 0.25)
			(net 100 "SCL")
			(pintype "passive")
		)
	)
	(footprint "antmicro-footprints:C_0603_1608Metric"
		(layer "F.Cu")
		(at 142.34 64.8 90)
		(descr "Capacitor SMD 0603")
		(tags "capacitor 0603")
		(property "Reference" "C27"
			(at -0.84 -5.51 90)
			(layer "F.SilkS")
			(effects
				(font
					(size 0.65 0.65)
					(thickness 0.15)
				)
				(justify left bottom)
			)
		)
		(property "Value" "C_22u_0603"
			(at 0 1.6 90)
			(layer "F.Fab")
			(hide yes)
			(effects
				(font
					(size 0.7 0.7)
					(thickness 0.15)
				)
				(justify left bottom)
			)
		)
		(property "Datasheet" "https://www.murata.com/products/productdetail?partno=GRM188R60J226MEA0%23"
			(at 0 0 90)
			(layer "F.Fab")
			(hide yes)
			(effects
				(font
					(size 1.27 1.27)
					(thickness 0.15)
				)
			)
		)
		(property "Description" "SMD Multilayer Ceramic Capacitor, 22 µF, 6.3 V, 0603 [1608 Metric], ± 20%, X5R, GRM Series"
			(at 0 0 90)
			(layer "F.Fab")
			(hide yes)
			(effects
				(font
					(size 1.27 1.27)
					(thickness 0.15)
				)
			)
		)
		(property "Author" "Antmicro"
			(at 207.14 -77.54 0)
			(layer "F.Fab")
			(hide yes)
			(effects
				(font
					(size 1 1)
					(thickness 0.15)
				)
			)
		)
		(property "Dielectric" ""
			(at 207.14 -77.54 0)
			(layer "F.Fab")
			(hide yes)
			(effects
				(font
					(size 1 1)
					(thickness 0.15)
				)
			)
		)
		(property "License" "Apache-2.0"
			(at 207.14 -77.54 0)
			(layer "F.Fab")
			(hide yes)
			(effects
				(font
					(size 1 1)
					(thickness 0.15)
				)
			)
		)
		(property "MPN" "GRM188R60J226MEA0D"
			(at 207.14 -77.54 0)
			(layer "F.Fab")
			(hide yes)
			(effects
				(font
					(size 1 1)
					(thickness 0.15)
				)
			)
		)
		(property "Manufacturer" "Murata"
			(at 207.14 -77.54 0)
			(layer "F.Fab")
			(hide yes)
			(effects
				(font
					(size 1 1)
					(thickness 0.15)
				)
			)
		)
		(property "Val" "22u"
			(at 207.14 -77.54 0)
			(layer "F.Fab")
			(hide yes)
			(effects
				(font
					(size 1 1)
					(thickness 0.15)
				)
			)
		)
		(property "Voltage" ""
			(at 207.14 -77.54 0)
			(layer "F.Fab")
			(hide yes)
			(effects
				(font
					(size 1 1)
					(thickness 0.15)
				)
			)
		)
		(sheetname "/Power Supply/")
		(sheetfile "supply.kicad_sch")
		(attr smd)
		(fp_line
			(start -0.15 -0.4)
			(end 0.15 -0.4)
			(stroke
				(width 0.15)
				(type solid)
			)
			(layer "F.SilkS")
		)
		(fp_line
			(start -0.15 0.4)
			(end 0.15 0.4)
			(stroke
				(width 0.15)
				(type solid)
			)
			(layer "F.SilkS")
		)
		(fp_rect
			(start -1.25 -0.65)
			(end 1.25 0.65)
			(stroke
				(width 0.05)
				(type solid)
			)
			(fill no)
			(layer "F.CrtYd")
		)
		(fp_rect
			(start -0.8 -0.4)
			(end 0.8 0.4)
			(stroke
				(width 0.15)
				(type solid)
			)
			(fill no)
			(layer "F.Fab")
		)
		(fp_text user "License: Apache-2.0"
			(at -1.682 5.895 90)
			(layer "F.Fab")
			(effects
				(font
					(size 0.7 0.7)
					(thickness 0.15)
				)
				(justify left bottom)
			)
		)
		(fp_text user "${REFERENCE}"
			(at -1.682 3.895 90)
			(layer "F.Fab")
			(effects
				(font
					(size 0.7 0.7)
					(thickness 0.15)
				)
				(justify left bottom)
			)
		)
		(fp_text user "Author: Antmicro"
			(at -1.682 4.894 90)
			(layer "F.Fab")
			(effects
				(font
					(size 0.7 0.7)
					(thickness 0.15)
				)
				(justify left bottom)
			)
		)
		(pad "1" smd roundrect
			(at -0.7 0 90)
			(size 0.8 1)
			(layers "F.Cu" "F.Mask" "F.Paste")
			(roundrect_rratio 0.2)
			(net 1 "GND")
			(pintype "passive")
		)
		(pad "2" smd roundrect
			(at 0.7 0 90)
			(size 0.8 1)
			(layers "F.Cu" "F.Mask" "F.Paste")
			(roundrect_rratio 0.2)
			(net 274 "/Power Supply/1V5_OUT")
			(pintype "passive")
		)
	)
	(footprint "antmicro-footprints:C_0603_1608Metric"
		(layer "F.Cu")
		(at 160.59 62.03)
		(descr "Capacitor SMD 0603")
		(tags "capacitor 0603")
		(property "Reference" "C34"
			(at -1.01 -0.49 0)
			(layer "F.SilkS")
			(effects
				(font
					(size 0.65 0.65)
					(thickness 0.15)
				)
				(justify left bottom)
			)
		)
		(property "Value" "C_22u_0603"
			(at 0 1.6 0)
			(layer "F.Fab")
			(hide yes)
			(effects
				(font
					(size 0.7 0.7)
					(thickness 0.15)
				)
				(justify left bottom)
			)
		)
		(property "Datasheet" "https://www.murata.com/products/productdetail?partno=GRM188R60J226MEA0%23"
			(at 0 0 0)
			(layer "F.Fab")
			(hide yes)
			(effects
				(font
					(size 1.27 1.27)
					(thickness 0.15)
				)
			)
		)
		(property "Description" "SMD Multilayer Ceramic Capacitor, 22 µF, 6.3 V, 0603 [1608 Metric], ± 20%, X5R, GRM Series"
			(at 0 0 0)
			(layer "F.Fab")
			(hide yes)
			(effects
				(font
					(size 1.27 1.27)
					(thickness 0.15)
				)
			)
		)
		(property "Author" "Antmicro"
			(at 0 0 0)
			(layer "F.Fab")
			(hide yes)
			(effects
				(font
					(size 1 1)
					(thickness 0.15)
				)
			)
		)
		(property "Dielectric" ""
			(at 0 0 0)
			(layer "F.Fab")
			(hide yes)
			(effects
				(font
					(size 1 1)
					(thickness 0.15)
				)
			)
		)
		(property "License" "Apache-2.0"
			(at 0 0 0)
			(layer "F.Fab")
			(hide yes)
			(effects
				(font
					(size 1 1)
					(thickness 0.15)
				)
			)
		)
		(property "MPN" "GRM188R60J226MEA0D"
			(at 0 0 0)
			(layer "F.Fab")
			(hide yes)
			(effects
				(font
					(size 1 1)
					(thickness 0.15)
				)
			)
		)
		(property "Manufacturer" "Murata"
			(at 0 0 0)
			(layer "F.Fab")
			(hide yes)
			(effects
				(font
					(size 1 1)
					(thickness 0.15)
				)
			)
		)
		(property "Val" "22u"
			(at 0 0 0)
			(layer "F.Fab")
			(hide yes)
			(effects
				(font
					(size 1 1)
					(thickness 0.15)
				)
			)
		)
		(property "Voltage" ""
			(at 0 0 0)
			(layer "F.Fab")
			(hide yes)
			(effects
				(font
					(size 1 1)
					(thickness 0.15)
				)
			)
		)
		(sheetname "/Power Supply/")
		(sheetfile "supply.kicad_sch")
		(attr smd)
		(fp_line
			(start -0.15 -0.4)
			(end 0.15 -0.4)
			(stroke
				(width 0.15)
				(type solid)
			)
			(layer "F.SilkS")
		)
		(fp_line
			(start -0.15 0.4)
			(end 0.15 0.4)
			(stroke
				(width 0.15)
				(type solid)
			)
			(layer "F.SilkS")
		)
		(fp_rect
			(start -1.25 -0.65)
			(end 1.25 0.65)
			(stroke
				(width 0.05)
				(type solid)
			)
			(fill no)
			(layer "F.CrtYd")
		)
		(fp_rect
			(start -0.8 -0.4)
			(end 0.8 0.4)
			(stroke
				(width 0.15)
				(type solid)
			)
			(fill no)
			(layer "F.Fab")
		)
		(fp_text user "Author: Antmicro"
			(at -1.682 4.894 0)
			(layer "F.Fab")
			(effects
				(font
					(size 0.7 0.7)
					(thickness 0.15)
				)
				(justify left bottom)
			)
		)
		(fp_text user "${REFERENCE}"
			(at -1.682 3.895 0)
			(layer "F.Fab")
			(effects
				(font
					(size 0.7 0.7)
					(thickness 0.15)
				)
				(justify left bottom)
			)
		)
		(fp_text user "License: Apache-2.0"
			(at -1.682 5.895 0)
			(layer "F.Fab")
			(effects
				(font
					(size 0.7 0.7)
					(thickness 0.15)
				)
				(justify left bottom)
			)
		)
		(pad "1" smd roundrect
			(at -0.7 0)
			(size 0.8 1)
			(layers "F.Cu" "F.Mask" "F.Paste")
			(roundrect_rratio 0.2)
			(net 1 "GND")
			(pintype "passive")
		)
		(pad "2" smd roundrect
			(at 0.7 0)
			(size 0.8 1)
			(layers "F.Cu" "F.Mask" "F.Paste")
			(roundrect_rratio 0.2)
			(net 275 "/Power Supply/3V3_OUT")
			(pintype "passive")
		)
	)
	(footprint "antmicro-footprints:SOIC-8_3.9x4.9x1.75mm_P1.27mm"
		(layer "F.Cu")
		(at 105.655 94.605 -90)
		(property "Reference" "U18"
			(at 0 -2.85 270)
			(layer "F.SilkS")
			(effects
				(font
					(size 0.7 0.7)
					(thickness 0.15)
				)
				(justify left bottom)
			)
		)
		(property "Value" "W25Q32JVSSIQ"
			(at 0 3.65 270)
			(layer "F.Fab")
			(effects
				(font
					(size 0.7 0.7)
					(thickness 0.15)
				)
				(justify left bottom)
			)
		)
		(property "Author" "Antmicro"
			(at 11.05 200.26 0)
			(layer "F.Fab")
			(hide yes)
			(effects
				(font
					(size 1 1)
					(thickness 0.15)
				)
			)
		)
		(property "License" "Apache-2.0"
			(at 11.05 200.26 0)
			(layer "F.Fab")
			(hide yes)
			(effects
				(font
					(size 1 1)
					(thickness 0.15)
				)
			)
		)
		(property "MPN" "W25Q32JVSSIQ"
			(at 11.05 200.26 0)
			(layer "F.Fab")
			(hide yes)
			(effects
				(font
					(size 1 1)
					(thickness 0.15)
				)
			)
		)
		(property "Manufacturer" "Winbond"
			(at 11.05 200.26 0)
			(layer "F.Fab")
			(hide yes)
			(effects
				(font
					(size 1 1)
					(thickness 0.15)
				)
			)
		)
		(sheetname "/FPGA/")
		(sheetfile "fpga.kicad_sch")
		(attr smd)
		(fp_line
			(start -1.95 2.45)
			(end 1.95 2.45)
			(stroke
				(width 0.15)
				(type solid)
			)
			(layer "F.SilkS")
		)
		(fp_line
			(start -1.95 -2.452)
			(end 1.95 -2.45)
			(stroke
				(width 0.15)
				(type solid)
			)
			(layer "F.SilkS")
		)
		(fp_circle
			(center -2.4 -2.45)
			(end -2.35 -2.4)
			(stroke
				(width 0.15)
				(type solid)
			)
			(fill yes)
			(layer "F.SilkS")
		)
		(fp_rect
			(start -3.625 -2.7)
			(end 3.625 2.7)
			(stroke
				(width 0.05)
				(type solid)
			)
			(fill no)
			(layer "F.CrtYd")
		)
		(fp_line
			(start -1.95 2.45)
			(end -1.95 -1.18)
			(stroke
				(width 0.15)
				(type solid)
			)
			(layer "F.Fab")
		)
		(fp_line
			(start 1.949 2.45)
			(end -1.95 2.45)
			(stroke
				(width 0.15)
				(type solid)
			)
			(layer "F.Fab")
		)
		(fp_line
			(start -1.95 -1.18)
			(end -0.683 -2.452)
			(stroke
				(width 0.15)
				(type solid)
			)
			(layer "F.Fab")
		)
		(fp_line
			(start -0.683 -2.452)
			(end 1.949 -2.452)
			(stroke
				(width 0.15)
				(type solid)
			)
			(layer "F.Fab")
		)
		(fp_line
			(start 1.949 -2.452)
			(end 1.949 2.45)
			(stroke
				(width 0.15)
				(type solid)
			)
			(layer "F.Fab")
		)
		(fp_text user "License: Apache-2.0"
			(at -3.476 5.099 270)
			(layer "F.Fab")
			(effects
				(font
					(size 0.7 0.7)
					(thickness 0.15)
				)
				(justify left bottom)
			)
		)
		(fp_text user "${REFERENCE}"
			(at -3.476 7.099 270)
			(layer "F.Fab")
			(effects
				(font
					(size 0.7 0.7)
					(thickness 0.15)
				)
				(justify left bottom)
			)
		)
		(fp_text user "Author: Antmicro"
			(at -3.476 6.099 270)
			(layer "F.Fab")
			(effects
				(font
					(size 0.7 0.7)
					(thickness 0.15)
				)
				(justify left bottom)
			)
		)
		(pad "1" smd roundrect
			(at -2.714 -1.905)
			(size 0.65 1.525)
			(layers "F.Cu" "F.Mask" "F.Paste")
			(roundrect_rratio 0.25)
			(net 306 "Net-(U18-~{CS})")
			(pinfunction "~{CS}")
			(pintype "input")
		)
		(pad "2" smd roundrect
			(at -2.714 -0.635)
			(size 0.65 1.525)
			(layers "F.Cu" "F.Mask" "F.Paste")
			(roundrect_rratio 0.25)
			(net 301 "Net-(U18-SO{slash}IO1)")
			(pinfunction "SO/IO1")
			(pintype "bidirectional")
		)
		(pad "3" smd roundrect
			(at -2.714 0.632)
			(size 0.65 1.525)
			(layers "F.Cu" "F.Mask" "F.Paste")
			(roundrect_rratio 0.25)
			(net 28 "/FPGA/SPI_DQ2")
			(pinfunction "~{WP}/IO2")
			(pintype "bidirectional")
		)
		(pad "4" smd roundrect
			(at -2.714 1.902)
			(size 0.65 1.525)
			(layers "F.Cu" "F.Mask" "F.Paste")
			(roundrect_rratio 0.25)
			(net 1 "GND")
			(pinfunction "VSS")
			(pintype "power_in")
		)
		(pad "5" smd roundrect
			(at 2.712 1.902)
			(size 0.65 1.525)
			(layers "F.Cu" "F.Mask" "F.Paste")
			(roundrect_rratio 0.25)
			(net 300 "Net-(U18-SI{slash}IO0)")
			(pinfunction "SI/IO0")
			(pintype "bidirectional")
		)
		(pad "6" smd roundrect
			(at 2.712 0.632)
			(size 0.65 1.525)
			(layers "F.Cu" "F.Mask" "F.Paste")
			(roundrect_rratio 0.25)
			(net 303 "Net-(U18-SCLK)")
			(pinfunction "SCLK")
			(pintype "input")
		)
		(pad "7" smd roundrect
			(at 2.712 -0.635)
			(size 0.65 1.525)
			(layers "F.Cu" "F.Mask" "F.Paste")
			(roundrect_rratio 0.25)
			(net 27 "/FPGA/SPI_DQ3")
			(pinfunction "~{HOLD}/IO3")
			(pintype "bidirectional")
		)
		(pad "8" smd roundrect
			(at 2.712 -1.905)
			(size 0.65 1.525)
			(layers "F.Cu" "F.Mask" "F.Paste")
			(roundrect_rratio 0.25)
			(net 2 "+3V3")
			(pinfunction "VCC")
			(pintype "power_in")
		)
	)
	(footprint "antmicro-footprints:R_0402_1005Metric"
		(layer "F.Cu")
		(at 161.49 69.85 90)
		(descr "Resistor SMD 0402")
		(tags "resistor SMD 0402")
		(property "Reference" "R18"
			(at -3.09 -0.36 90)
			(layer "F.SilkS")
			(effects
				(font
					(size 0.65 0.65)
					(thickness 0.15)
				)
				(justify left bottom)
			)
		)
		(property "Value" "R_470R_0402"
			(at 0 1.4 90)
			(layer "F.Fab")
			(hide yes)
			(effects
				(font
					(size 0.7 0.7)
					(thickness 0.15)
				)
				(justify left bottom)
			)
		)
		(property "Datasheet" "https://www.bourns.com/docs/product-datasheets/cr.pdf"
			(at 0 0 90)
			(layer "F.Fab")
			(hide yes)
			(effects
				(font
					(size 1.27 1.27)
					(thickness 0.15)
				)
			)
		)
		(property "Description" "SMD Chip Resistor, 470 ohm, ± 1%, 62.5 mW, 0402 [1005 Metric], Thick Film, General Purpose"
			(at 0 0 90)
			(layer "F.Fab")
			(hide yes)
			(effects
				(font
					(size 1.27 1.27)
					(thickness 0.15)
				)
			)
		)
		(property "Author" "Antmicro"
			(at 231.34 -91.64 0)
			(layer "F.Fab")
			(hide yes)
			(effects
				(font
					(size 1 1)
					(thickness 0.15)
				)
			)
		)
		(property "License" "Apache-2.0"
			(at 231.34 -91.64 0)
			(layer "F.Fab")
			(hide yes)
			(effects
				(font
					(size 1 1)
					(thickness 0.15)
				)
			)
		)
		(property "MPN" "CR0402-FX-4700GLF"
			(at 231.34 -91.64 0)
			(layer "F.Fab")
			(hide yes)
			(effects
				(font
					(size 1 1)
					(thickness 0.15)
				)
			)
		)
		(property "Manufacturer" "Bourns"
			(at 231.34 -91.64 0)
			(layer "F.Fab")
			(hide yes)
			(effects
				(font
					(size 1 1)
					(thickness 0.15)
				)
			)
		)
		(property "Tolerance" "1%"
			(at 231.34 -91.64 0)
			(layer "F.Fab")
			(hide yes)
			(effects
				(font
					(size 1 1)
					(thickness 0.15)
				)
			)
		)
		(property "Val" "470R"
			(at 231.34 -91.64 0)
			(layer "F.Fab")
			(hide yes)
			(effects
				(font
					(size 1 1)
					(thickness 0.15)
				)
			)
		)
		(sheetname "/Power Supply/")
		(sheetfile "supply.kicad_sch")
		(attr smd)
		(fp_rect
			(start -0.925 -0.47)
			(end 0.925 0.47)
			(stroke
				(width 0.05)
				(type default)
			)
			(fill no)
			(layer "F.CrtYd")
		)
		(fp_rect
			(start -0.5 -0.25)
			(end 0.5 0.25)
			(stroke
				(width 0.15)
				(type solid)
			)
			(fill no)
			(layer "F.Fab")
		)
		(fp_text user "License: Apache-2.0"
			(at -0.95 5.169 90)
			(layer "F.Fab")
			(effects
				(font
					(size 0.7 0.7)
					(thickness 0.15)
				)
				(justify left bottom)
			)
		)
		(fp_text user "Author: Antmicro"
			(at -0.95 4.169 90)
			(layer "F.Fab")
			(effects
				(font
					(size 0.7 0.7)
					(thickness 0.15)
				)
				(justify left bottom)
			)
		)
		(fp_text user "${REFERENCE}"
			(at -0.95 3.168 90)
			(layer "F.Fab")
			(effects
				(font
					(size 0.7 0.7)
					(thickness 0.15)
				)
				(justify left bottom)
			)
		)
		(pad "1" smd roundrect
			(at -0.48 0 90)
			(size 0.59 0.64)
			(layers "F.Cu" "F.Mask" "F.Paste")
			(roundrect_rratio 0.25)
			(net 62 "Net-(D2-A)")
			(pintype "passive")
		)
		(pad "2" smd roundrect
			(at 0.48 0 90)
			(size 0.59 0.64)
			(layers "F.Cu" "F.Mask" "F.Paste")
			(roundrect_rratio 0.25)
			(net 14 "+5V")
			(pintype "passive")
		)
	)
	(footprint "antmicro-footprints:C_0402_1005Metric"
		(layer "F.Cu")
		(at 83.3 104.675 180)
		(descr "Capacitor SMD 0402")
		(tags "capacitor SMD 0402")
		(property "Reference" "C78"
			(at -4.13 7.835 0)
			(layer "F.SilkS")
			(effects
				(font
					(size 0.65 0.65)
					(thickness 0.15)
				)
				(justify right bottom)
			)
		)
		(property "Value" "C_4u7_0402"
			(at 0 1.4 0)
			(layer "F.Fab")
			(hide yes)
			(effects
				(font
					(size 0.7 0.7)
					(thickness 0.15)
				)
				(justify right bottom)
			)
		)
		(property "Datasheet" "https://www.murata.com/products/productdetail?partno=GRM155R61A475MEAA%23"
			(at 0 0 180)
			(layer "F.Fab")
			(hide yes)
			(effects
				(font
					(size 1.27 1.27)
					(thickness 0.15)
				)
			)
		)
		(property "Description" "SMD Multilayer Ceramic Capacitor, 4.7 µF, 10 V, 0402 [1005 Metric], ± 20%, X5R, GRM Series"
			(at 0 0 180)
			(layer "F.Fab")
			(hide yes)
			(effects
				(font
					(size 1.27 1.27)
					(thickness 0.15)
				)
			)
		)
		(property "Author" "Antmicro"
			(at 166.6 209.35 0)
			(layer "F.Fab")
			(hide yes)
			(effects
				(font
					(size 1 1)
					(thickness 0.15)
				)
			)
		)
		(property "Dielectric" ""
			(at 166.6 209.35 0)
			(layer "F.Fab")
			(hide yes)
			(effects
				(font
					(size 1 1)
					(thickness 0.15)
				)
			)
		)
		(property "License" "Apache-2.0"
			(at 166.6 209.35 0)
			(layer "F.Fab")
			(hide yes)
			(effects
				(font
					(size 1 1)
					(thickness 0.15)
				)
			)
		)
		(property "MPN" "GRM155R61A475MEAAD"
			(at 166.6 209.35 0)
			(layer "F.Fab")
			(hide yes)
			(effects
				(font
					(size 1 1)
					(thickness 0.15)
				)
			)
		)
		(property "Manufacturer" "Murata"
			(at 166.6 209.35 0)
			(layer "F.Fab")
			(hide yes)
			(effects
				(font
					(size 1 1)
					(thickness 0.15)
				)
			)
		)
		(property "Val" "4u7"
			(at 166.6 209.35 0)
			(layer "F.Fab")
			(hide yes)
			(effects
				(font
					(size 1 1)
					(thickness 0.15)
				)
			)
		)
		(property "Voltage" ""
			(at 166.6 209.35 0)
			(layer "F.Fab")
			(hide yes)
			(effects
				(font
					(size 1 1)
					(thickness 0.15)
				)
			)
		)
		(sheetname "/SDI/")
		(sheetfile "sdi.kicad_sch")
		(attr smd)
		(fp_rect
			(start -0.925 -0.47)
			(end 0.925 0.47)
			(stroke
				(width 0.05)
				(type default)
			)
			(fill no)
			(layer "F.CrtYd")
		)
		(fp_line
			(start 0.504 0.248)
			(end -0.494 0.248)
			(stroke
				(width 0.15)
				(type solid)
			)
			(layer "F.Fab")
		)
		(fp_line
			(start 0.504 -0.25)
			(end 0.504 0.248)
			(stroke
				(width 0.15)
				(type solid)
			)
			(layer "F.Fab")
		)
		(fp_line
			(start -0.494 0.248)
			(end -0.494 -0.25)
			(stroke
				(width 0.15)
				(type solid)
			)
			(layer "F.Fab")
		)
		(fp_line
			(start -0.494 -0.25)
			(end 0.504 -0.25)
			(stroke
				(width 0.15)
				(type solid)
			)
			(layer "F.Fab")
		)
		(fp_text user "License: Apache-2.0"
			(at -0.939 5.799 180)
			(layer "F.Fab")
			(effects
				(font
					(size 0.7 0.7)
					(thickness 0.15)
				)
				(justify left bottom)
			)
		)
		(fp_text user "Author: Antmicro"
			(at -0.939 3.399 180)
			(layer "F.Fab")
			(effects
				(font
					(size 0.7 0.7)
					(thickness 0.15)
				)
				(justify left bottom)
			)
		)
		(fp_text user "${REFERENCE}"
			(at -0.939 4.599 180)
			(layer "F.Fab")
			(effects
				(font
					(size 0.7 0.7)
					(thickness 0.15)
				)
				(justify left bottom)
			)
		)
		(pad "1" smd roundrect
			(at -0.48 0 180)
			(size 0.59 0.64)
			(layers "F.Cu" "F.Mask" "F.Paste")
			(roundrect_rratio 0.25)
			(net 251 "/SDI/SDI_OUT_F2")
			(pintype "passive")
		)
		(pad "2" smd roundrect
			(at 0.48 0 180)
			(size 0.59 0.64)
			(layers "F.Cu" "F.Mask" "F.Paste")
			(roundrect_rratio 0.25)
			(net 252 "/SDI/SDI_OUT")
			(pintype "passive")
		)
	)
	(footprint "antmicro-footprints:C_0402_1005Metric"
		(layer "F.Cu")
		(at 110.29 103.9 90)
		(descr "Capacitor SMD 0402")
		(tags "capacitor SMD 0402")
		(property "Reference" "C81"
			(at -1.14 2.44 90)
			(layer "F.SilkS")
			(effects
				(font
					(size 0.65 0.65)
					(thickness 0.15)
				)
				(justify left bottom)
			)
		)
		(property "Value" "C_100n_0402"
			(at 0 1.4 90)
			(layer "F.Fab")
			(hide yes)
			(effects
				(font
					(size 0.7 0.7)
					(thickness 0.15)
				)
				(justify left bottom)
			)
		)
		(property "Datasheet" "https://www.murata.com/products/productdetail?partno=GRM155R61H104KE14%23"
			(at 0 0 90)
			(layer "F.Fab")
			(hide yes)
			(effects
				(font
					(size 1.27 1.27)
					(thickness 0.15)
				)
			)
		)
		(property "Description" "SMD Multilayer Ceramic Capacitor, 0.1 µF, 50 V, 0402 [1005 Metric], ± 10%, X5R, GRM Series"
			(at 0 0 90)
			(layer "F.Fab")
			(hide yes)
			(effects
				(font
					(size 1.27 1.27)
					(thickness 0.15)
				)
			)
		)
		(property "Author" "Antmicro"
			(at 214.19 -6.39 0)
			(layer "F.Fab")
			(hide yes)
			(effects
				(font
					(size 1 1)
					(thickness 0.15)
				)
			)
		)
		(property "Dielectric" "X5R"
			(at 214.19 -6.39 0)
			(layer "F.Fab")
			(hide yes)
			(effects
				(font
					(size 1 1)
					(thickness 0.15)
				)
			)
		)
		(property "License" "Apache-2.0"
			(at 214.19 -6.39 0)
			(layer "F.Fab")
			(hide yes)
			(effects
				(font
					(size 1 1)
					(thickness 0.15)
				)
			)
		)
		(property "MPN" "GRM155R61H104KE14D"
			(at 214.19 -6.39 0)
			(layer "F.Fab")
			(hide yes)
			(effects
				(font
					(size 1 1)
					(thickness 0.15)
				)
			)
		)
		(property "Manufacturer" "Murata"
			(at 214.19 -6.39 0)
			(layer "F.Fab")
			(hide yes)
			(effects
				(font
					(size 1 1)
					(thickness 0.15)
				)
			)
		)
		(property "Val" "100n"
			(at 214.19 -6.39 0)
			(layer "F.Fab")
			(hide yes)
			(effects
				(font
					(size 1 1)
					(thickness 0.15)
				)
			)
		)
		(property "Voltage" "50V"
			(at 214.19 -6.39 0)
			(layer "F.Fab")
			(hide yes)
			(effects
				(font
					(size 1 1)
					(thickness 0.15)
				)
			)
		)
		(sheetname "/FPGA/")
		(sheetfile "fpga.kicad_sch")
		(attr smd)
		(fp_rect
			(start -0.925 -0.47)
			(end 0.925 0.47)
			(stroke
				(width 0.05)
				(type default)
			)
			(fill no)
			(layer "F.CrtYd")
		)
		(fp_line
			(start 0.504 -0.25)
			(end 0.504 0.248)
			(stroke
				(width 0.15)
				(type solid)
			)
			(layer "F.Fab")
		)
		(fp_line
			(start -0.494 -0.25)
			(end 0.504 -0.25)
			(stroke
				(width 0.15)
				(type solid)
			)
			(layer "F.Fab")
		)
		(fp_line
			(start 0.504 0.248)
			(end -0.494 0.248)
			(stroke
				(width 0.15)
				(type solid)
			)
			(layer "F.Fab")
		)
		(fp_line
			(start -0.494 0.248)
			(end -0.494 -0.25)
			(stroke
				(width 0.15)
				(type solid)
			)
			(layer "F.Fab")
		)
		(fp_text user "License: Apache-2.0"
			(at -0.939 5.799 90)
			(layer "F.Fab")
			(effects
				(font
					(size 0.7 0.7)
					(thickness 0.15)
				)
				(justify left bottom)
			)
		)
		(fp_text user "${REFERENCE}"
			(at -0.939 4.599 90)
			(layer "F.Fab")
			(effects
				(font
					(size 0.7 0.7)
					(thickness 0.15)
				)
				(justify left bottom)
			)
		)
		(fp_text user "Author: Antmicro"
			(at -0.939 3.399 90)
			(layer "F.Fab")
			(effects
				(font
					(size 0.7 0.7)
					(thickness 0.15)
				)
				(justify left bottom)
			)
		)
		(pad "1" smd roundrect
			(at -0.48 0 90)
			(size 0.59 0.64)
			(layers "F.Cu" "F.Mask" "F.Paste")
			(roundrect_rratio 0.25)
			(net 1 "GND")
			(pintype "passive")
		)
		(pad "2" smd roundrect
			(at 0.48 0 90)
			(size 0.59 0.64)
			(layers "F.Cu" "F.Mask" "F.Paste")
			(roundrect_rratio 0.25)
			(net 2 "+3V3")
			(pintype "passive")
		)
	)
	(footprint "antmicro-footprints:R_0603_1608Metric"
		(layer "F.Cu")
		(at 162.51 94.26 90)
		(descr "Resistor SMD 0603")
		(tags "resistor SMD 0603")
		(property "Reference" "R107"
			(at -1.34 -0.97 90)
			(layer "F.SilkS")
			(effects
				(font
					(size 0.65 0.65)
					(thickness 0.15)
				)
				(justify left bottom)
			)
		)
		(property "Value" "R_15k_0603"
			(at 0 1.6 90)
			(layer "F.Fab")
			(hide yes)
			(effects
				(font
					(size 0.7 0.7)
					(thickness 0.15)
				)
				(justify left bottom)
			)
		)
		(property "Datasheet" "https://www.bourns.com/docs/product-datasheets/cr.pdf"
			(at 0 0 90)
			(layer "F.Fab")
			(hide yes)
			(effects
				(font
					(size 1.27 1.27)
					(thickness 0.15)
				)
			)
		)
		(property "Description" "SMD Chip Resistor, 15 kohm, ± 1%, 100 mW, 0603 [1608 Metric], Thick Film, General Purpose"
			(at 0 0 90)
			(layer "F.Fab")
			(hide yes)
			(effects
				(font
					(size 1.27 1.27)
					(thickness 0.15)
				)
			)
		)
		(property "Author" "Antmicro"
			(at 256.8 -68.2 0)
			(layer "F.Fab")
			(hide yes)
			(effects
				(font
					(size 1 1)
					(thickness 0.15)
				)
			)
		)
		(property "License" "Apache-2.0"
			(at 256.8 -68.2 0)
			(layer "F.Fab")
			(hide yes)
			(effects
				(font
					(size 1 1)
					(thickness 0.15)
				)
			)
		)
		(property "MPN" "CR0603-FX-1502ELF"
			(at 256.8 -68.2 0)
			(layer "F.Fab")
			(hide yes)
			(effects
				(font
					(size 1 1)
					(thickness 0.15)
				)
			)
		)
		(property "Manufacturer" "Bourns"
			(at 256.8 -68.2 0)
			(layer "F.Fab")
			(hide yes)
			(effects
				(font
					(size 1 1)
					(thickness 0.15)
				)
			)
		)
		(property "Tolerance" "1%"
			(at 256.8 -68.2 0)
			(layer "F.Fab")
			(hide yes)
			(effects
				(font
					(size 1 1)
					(thickness 0.15)
				)
			)
		)
		(property "Val" "15k"
			(at 256.8 -68.2 0)
			(layer "F.Fab")
			(hide yes)
			(effects
				(font
					(size 1 1)
					(thickness 0.15)
				)
			)
		)
		(sheetname "/Peripherals/")
		(sheetfile "peripherals.kicad_sch")
		(attr smd)
		(fp_line
			(start -0.15 -0.4)
			(end 0.15 -0.4)
			(stroke
				(width 0.15)
				(type solid)
			)
			(layer "F.SilkS")
		)
		(fp_line
			(start -0.15 0.4)
			(end 0.15 0.4)
			(stroke
				(width 0.15)
				(type solid)
			)
			(layer "F.SilkS")
		)
		(fp_rect
			(start -1.25 -0.65)
			(end 1.25 0.65)
			(stroke
				(width 0.05)
				(type solid)
			)
			(fill no)
			(layer "F.CrtYd")
		)
		(fp_rect
			(start -0.8 -0.4)
			(end 0.8 0.4)
			(stroke
				(width 0.15)
				(type solid)
			)
			(fill no)
			(layer "F.Fab")
		)
		(fp_text user "License: Apache-2.0"
			(at -1.25 5.9 90)
			(layer "F.Fab")
			(effects
				(font
					(size 0.7 0.7)
					(thickness 0.15)
				)
				(justify left bottom)
			)
		)
		(fp_text user "${REFERENCE}"
			(at -1.25 3.898 90)
			(layer "F.Fab")
			(effects
				(font
					(size 0.7 0.7)
					(thickness 0.15)
				)
				(justify left bottom)
			)
		)
		(fp_text user "Author: Antmicro"
			(at -1.25 4.9 90)
			(layer "F.Fab")
			(effects
				(font
					(size 0.7 0.7)
					(thickness 0.15)
				)
				(justify left bottom)
			)
		)
		(pad "1" smd roundrect
			(at -0.7 0 90)
			(size 0.8 1)
			(layers "F.Cu" "F.Mask" "F.Paste")
			(roundrect_rratio 0.2)
			(net 1 "GND")
			(pintype "passive")
		)
		(pad "2" smd roundrect
			(at 0.7 0 90)
			(size 0.8 1)
			(layers "F.Cu" "F.Mask" "F.Paste")
			(roundrect_rratio 0.2)
			(net 353 "Net-(U13-ILIM)")
			(pintype "passive")
		)
	)
	(footprint "antmicro-footprints:LED_0603_1608Metric_G"
		(layer "F.Cu")
		(at 162.79 70.3 90)
		(descr "LED SMD 0603 Green")
		(tags "LED SMD 0603 Green")
		(property "Reference" "D2"
			(at 1.18 -0.09 90)
			(layer "F.SilkS")
			(effects
				(font
					(size 0.65 0.65)
					(thickness 0.15)
				)
				(justify left top)
			)
		)
		(property "Value" "LED_G_0603_LTST-C190GKT"
			(at 0 1.6 90)
			(layer "F.Fab")
			(hide yes)
			(effects
				(font
					(size 0.7 0.7)
					(thickness 0.15)
				)
				(justify left top)
			)
		)
		(property "Datasheet" "https://media.digikey.com/pdf/Data%20Sheets/Lite-On%20PDFs/LTST-C190GKT.pdf"
			(at 0 0 90)
			(layer "F.Fab")
			(hide yes)
			(effects
				(font
					(size 1.27 1.27)
					(thickness 0.15)
				)
			)
		)
		(property "Description" "LED, Green, SMD, 0603, 20 mA, 2.1 V, 569 nm"
			(at 0 0 90)
			(layer "F.Fab")
			(hide yes)
			(effects
				(font
					(size 1.27 1.27)
					(thickness 0.15)
				)
			)
		)
		(property "Author" "Antmicro"
			(at 92.49 233.09 0)
			(layer "F.Fab")
			(hide yes)
			(effects
				(font
					(size 1 1)
					(thickness 0.15)
				)
			)
		)
		(property "License" "Apache-2.0"
			(at 92.49 233.09 0)
			(layer "F.Fab")
			(hide yes)
			(effects
				(font
					(size 1 1)
					(thickness 0.15)
				)
			)
		)
		(property "MPN" "LTST-C190GKT"
			(at 92.49 233.09 0)
			(layer "F.Fab")
			(hide yes)
			(effects
				(font
					(size 1 1)
					(thickness 0.15)
				)
			)
		)
		(property "Manufacturer" "Lite-On"
			(at 92.49 233.09 0)
			(layer "F.Fab")
			(hide yes)
			(effects
				(font
					(size 1 1)
					(thickness 0.15)
				)
			)
		)
		(property "Color" "Green"
			(at 0 0 90)
			(unlocked yes)
			(layer "F.Fab")
			(hide yes)
			(effects
				(font
					(size 1 1)
					(thickness 0.15)
				)
			)
		)
		(sheetname "/Power Supply/")
		(sheetfile "supply.kicad_sch")
		(attr smd)
		(fp_line
			(start 0.22 -0.35)
			(end -0.22 -0.35)
			(stroke
				(width 0.15)
				(type solid)
			)
			(layer "F.SilkS")
		)
		(fp_line
			(start -1.18 -0.319)
			(end -1.18 0.321)
			(stroke
				(width 0.15)
				(type solid)
			)
			(layer "F.SilkS")
		)
		(fp_line
			(start 0.105328 0.001008)
			(end 0.24 0.001)
			(stroke
				(width 0.1)
				(type solid)
			)
			(layer "F.SilkS")
		)
		(fp_line
			(start -0.094672 0.001008)
			(end 0.105328 -0.198992)
			(stroke
				(width 0.1)
				(type solid)
			)
			(layer "F.SilkS")
		)
		(fp_line
			(start -0.094672 0.001008)
			(end -0.24 0.001008)
			(stroke
				(width 0.1)
				(type solid)
			)
			(layer "F.SilkS")
		)
		(fp_line
			(start 0.105328 0.201008)
			(end 0.105328 -0.198992)
			(stroke
				(width 0.1)
				(type solid)
			)
			(layer "F.SilkS")
		)
		(fp_line
			(start 0.105328 0.201008)
			(end -0.094672 0.001008)
			(stroke
				(width 0.1)
				(type solid)
			)
			(layer "F.SilkS")
		)
		(fp_line
			(start -0.094672 0.201008)
			(end -0.094672 -0.198992)
			(stroke
				(width 0.1)
				(type solid)
			)
			(layer "F.SilkS")
		)
		(fp_line
			(start 0.22 0.35)
			(end -0.22 0.35)
			(stroke
				(width 0.15)
				(type solid)
			)
			(layer "F.SilkS")
		)
		(fp_rect
			(start 1.25 0.65)
			(end -1.25 -0.65)
			(stroke
				(width 0.05)
				(type solid)
			)
			(fill no)
			(layer "F.CrtYd")
		)
		(fp_line
			(start 0.201 -0.202)
			(end -0.101 0)
			(stroke
				(width 0.15)
				(type solid)
			)
			(layer "F.Fab")
		)
		(fp_line
			(start -0.199 -0.202)
			(end -0.199 0.1)
			(stroke
				(width 0.15)
				(type solid)
			)
			(layer "F.Fab")
		)
		(fp_line
			(start 0.599 0)
			(end 0.201 0)
			(stroke
				(width 0.15)
				(type solid)
			)
			(layer "F.Fab")
		)
		(fp_line
			(start 0.201 0)
			(end 0.201 -0.202)
			(stroke
				(width 0.15)
				(type solid)
			)
			(layer "F.Fab")
		)
		(fp_line
			(start -0.101 0)
			(end 0.201 0.2)
			(stroke
				(width 0.15)
				(type solid)
			)
			(layer "F.Fab")
		)
		(fp_line
			(start -0.199 0)
			(end -0.597 0)
			(stroke
				(width 0.15)
				(type solid)
			)
			(layer "F.Fab")
		)
		(fp_line
			(start 0.201 0.2)
			(end 0.201 0)
			(stroke
				(width 0.15)
				(type solid)
			)
			(layer "F.Fab")
		)
		(fp_line
			(start -0.199 0.2)
			(end -0.199 0.1)
			(stroke
				(width 0.15)
				(type solid)
			)
			(layer "F.Fab")
		)
		(fp_rect
			(start 0.848 0.4)
			(end -0.85 -0.402)
			(stroke
				(width 0.15)
				(type solid)
			)
			(fill no)
			(layer "F.Fab")
		)
		(fp_text user "${REFERENCE}"
			(at -1.4224 5.999 90)
			(layer "F.Fab")
			(effects
				(font
					(size 0.7 0.7)
					(thickness 0.15)
				)
				(justify left bottom)
			)
		)
		(fp_text user "Author: Antmicro"
			(at -1.4224 4.799 90)
			(layer "F.Fab")
			(effects
				(font
					(size 0.7 0.7)
					(thickness 0.15)
				)
				(justify left bottom)
			)
		)
		(fp_text user "License: Apache-2.0"
			(at -1.4224 3.599 90)
			(layer "F.Fab")
			(effects
				(font
					(size 0.7 0.7)
					(thickness 0.15)
				)
				(justify left bottom)
			)
		)
		(pad "1" smd roundrect
			(at -0.7 0 270)
			(size 0.8 1)
			(layers "F.Cu" "F.Mask" "F.Paste")
			(roundrect_rratio 0.2)
			(net 1 "GND")
			(pinfunction "C")
			(pintype "passive")
		)
		(pad "2" smd roundrect
			(at 0.7 0 270)
			(size 0.8 1)
			(layers "F.Cu" "F.Mask" "F.Paste")
			(roundrect_rratio 0.2)
			(net 62 "Net-(D2-A)")
			(pinfunction "A")
			(pintype "passive")
		)
	)
	(footprint "antmicro-footprints:R_0402_1005Metric"
		(layer "F.Cu")
		(at 142.215 117.85 180)
		(descr "Resistor SMD 0402")
		(tags "resistor SMD 0402")
		(property "Reference" "R33"
			(at 0.985 -1.49 180)
			(layer "F.SilkS")
			(effects
				(font
					(size 0.65 0.65)
					(thickness 0.15)
				)
				(justify left bottom)
			)
		)
		(property "Value" "R_12k_0402"
			(at 0 1.4 180)
			(layer "F.Fab")
			(hide yes)
			(effects
				(font
					(size 0.7 0.7)
					(thickness 0.15)
				)
				(justify left bottom)
			)
		)
		(property "Datasheet" "https://www.bourns.com/docs/product-datasheets/cr.pdf"
			(at 0 0 180)
			(layer "F.Fab")
			(hide yes)
			(effects
				(font
					(size 1.27 1.27)
					(thickness 0.15)
				)
			)
		)
		(property "Description" "SMD Chip Resistor, 12 kohm, ± 1%, 62.5 mW, 0402 [1005 Metric], Thick Film, General Purpose"
			(at 0 0 180)
			(layer "F.Fab")
			(hide yes)
			(effects
				(font
					(size 1.27 1.27)
					(thickness 0.15)
				)
			)
		)
		(property "Author" "Antmicro"
			(at 284.43 235.7 0)
			(layer "F.Fab")
			(hide yes)
			(effects
				(font
					(size 1 1)
					(thickness 0.15)
				)
			)
		)
		(property "License" "Apache-2.0"
			(at 284.43 235.7 0)
			(layer "F.Fab")
			(hide yes)
			(effects
				(font
					(size 1 1)
					(thickness 0.15)
				)
			)
		)
		(property "MPN" "CR0402-FX-1202GLF"
			(at 284.43 235.7 0)
			(layer "F.Fab")
			(hide yes)
			(effects
				(font
					(size 1 1)
					(thickness 0.15)
				)
			)
		)
		(property "Manufacturer" "Bourns"
			(at 284.43 235.7 0)
			(layer "F.Fab")
			(hide yes)
			(effects
				(font
					(size 1 1)
					(thickness 0.15)
				)
			)
		)
		(property "Tolerance" "1%"
			(at 284.43 235.7 0)
			(layer "F.Fab")
			(hide yes)
			(effects
				(font
					(size 1 1)
					(thickness 0.15)
				)
			)
		)
		(property "Val" "12k"
			(at 284.43 235.7 0)
			(layer "F.Fab")
			(hide yes)
			(effects
				(font
					(size 1 1)
					(thickness 0.15)
				)
			)
		)
		(sheetname "/Power Supply/")
		(sheetfile "supply.kicad_sch")
		(attr smd)
		(fp_rect
			(start -0.925 -0.47)
			(end 0.925 0.47)
			(stroke
				(width 0.05)
				(type default)
			)
			(fill no)
			(layer "F.CrtYd")
		)
		(fp_rect
			(start -0.5 -0.25)
			(end 0.5 0.25)
			(stroke
				(width 0.15)
				(type solid)
			)
			(fill no)
			(layer "F.Fab")
		)
		(fp_text user "${REFERENCE}"
			(at -0.95 3.168 180)
			(layer "F.Fab")
			(effects
				(font
					(size 0.7 0.7)
					(thickness 0.15)
				)
				(justify left bottom)
			)
		)
		(fp_text user "Author: Antmicro"
			(at -0.95 4.169 180)
			(layer "F.Fab")
			(effects
				(font
					(size 0.7 0.7)
					(thickness 0.15)
				)
				(justify left bottom)
			)
		)
		(fp_text user "License: Apache-2.0"
			(at -0.95 5.169 180)
			(layer "F.Fab")
			(effects
				(font
					(size 0.7 0.7)
					(thickness 0.15)
				)
				(justify left bottom)
			)
		)
		(pad "1" smd roundrect
			(at -0.48 0 180)
			(size 0.59 0.64)
			(layers "F.Cu" "F.Mask" "F.Paste")
			(roundrect_rratio 0.25)
			(net 282 "Net-(U9-ADJ)")
			(pintype "passive")
		)
		(pad "2" smd roundrect
			(at 0.48 0 180)
			(size 0.59 0.64)
			(layers "F.Cu" "F.Mask" "F.Paste")
			(roundrect_rratio 0.25)
			(net 279 "Net-(U9-V_{OUT})")
			(pintype "passive")
		)
	)
	(footprint "antmicro-footprints:Oscillator_SMD_YIC_OSC-S5_5x3.2mm"
		(layer "F.Cu")
		(at 113.14 89.25)
		(property "Reference" "Y2"
			(at -2.11 3.61 90)
			(unlocked yes)
			(layer "F.SilkS")
			(effects
				(font
					(size 0.65 0.65)
					(thickness 0.15)
				)
				(justify left bottom)
			)
		)
		(property "Value" "Oscillator_SMD_40MHz_OSC-S5"
			(at 0 3 0)
			(unlocked yes)
			(layer "F.Fab")
			(hide yes)
			(effects
				(font
					(size 0.7 0.7)
					(thickness 0.15)
				)
				(justify left bottom)
			)
		)
		(property "Datasheet" "https://www.tme.eu/Document/456c7b2975a812de7905406dd4f750d9/YIC-S5.pdf"
			(at 0 0 0)
			(layer "F.Fab")
			(hide yes)
			(effects
				(font
					(size 1.27 1.27)
					(thickness 0.15)
				)
			)
		)
		(property "Description" "Generator: quartz, 40MHz, SMD, 3.3V, ±50ppm, -20÷70°C, 5x3.2x1.3mm"
			(at 0 0 0)
			(layer "F.Fab")
			(hide yes)
			(effects
				(font
					(size 1.27 1.27)
					(thickness 0.15)
				)
			)
		)
		(property "Author" "Antmicro"
			(at 23.89 202.39 90)
			(layer "F.Fab")
			(hide yes)
			(effects
				(font
					(size 1 1)
					(thickness 0.15)
				)
			)
		)
		(property "License" "Apache-2.0"
			(at 23.89 202.39 90)
			(layer "F.Fab")
			(hide yes)
			(effects
				(font
					(size 1 1)
					(thickness 0.15)
				)
			)
		)
		(property "MPN" "OSC40M-3.3/S5"
			(at 23.89 202.39 90)
			(layer "F.Fab")
			(hide yes)
			(effects
				(font
					(size 1 1)
					(thickness 0.15)
				)
			)
		)
		(property "Manufacturer" "YIC"
			(at 23.89 202.39 90)
			(layer "F.Fab")
			(hide yes)
			(effects
				(font
					(size 1 1)
					(thickness 0.15)
				)
			)
		)
		(property "Val" "40 MHz"
			(at 0 0 0)
			(unlocked yes)
			(layer "F.Fab")
			(hide yes)
			(effects
				(font
					(size 1 1)
					(thickness 0.15)
				)
			)
		)
		(sheetname "/FPGA/")
		(sheetfile "fpga.kicad_sch")
		(attr smd)
		(fp_line
			(start -1.899 2.618)
			(end -1.899 1.618)
			(stroke
				(width 0.15)
				(type solid)
			)
			(layer "F.SilkS")
		)
		(fp_line
			(start -1.899 2.618)
			(end -0.901 2.618)
			(stroke
				(width 0.15)
				(type solid)
			)
			(layer "F.SilkS")
		)
		(fp_line
			(start -1.88 -2.65)
			(end -1.88 -1.651)
			(stroke
				(width 0.15)
				(type solid)
			)
			(layer "F.SilkS")
		)
		(fp_line
			(start -1.88 -2.65)
			(end -0.881 -2.65)
			(stroke
				(width 0.15)
				(type solid)
			)
			(layer "F.SilkS")
		)
		(fp_line
			(start 1.9 -2.68)
			(end 0.901 -2.68)
			(stroke
				(width 0.15)
				(type solid)
			)
			(layer "F.SilkS")
		)
		(fp_line
			(start 1.9 -2.68)
			(end 1.9 -1.681)
			(stroke
				(width 0.15)
				(type solid)
			)
			(layer "F.SilkS")
		)
		(fp_line
			(start 1.9 2.618)
			(end 0.901 2.618)
			(stroke
				(width 0.15)
				(type solid)
			)
			(layer "F.SilkS")
		)
		(fp_line
			(start 1.9 2.618)
			(end 1.9 1.618)
			(stroke
				(width 0.15)
				(type solid)
			)
			(layer "F.SilkS")
		)
		(fp_circle
			(center -1.96 -1.34)
			(end -1.96 -1.29)
			(stroke
				(width 0.15)
				(type solid)
			)
			(fill yes)
			(layer "F.SilkS")
		)
		(fp_rect
			(start 2.1 -3.03)
			(end -2.101 2.969)
			(stroke
				(width 0.05)
				(type solid)
			)
			(fill no)
			(layer "F.CrtYd")
		)
		(fp_rect
			(start 1.749 -2.53)
			(end -1.75 2.469)
			(stroke
				(width 0.15)
				(type solid)
			)
			(fill no)
			(layer "F.Fab")
		)
		(fp_text user "${REFERENCE}"
			(at -3 6.999 0)
			(unlocked yes)
			(layer "F.Fab")
			(effects
				(font
					(size 0.7 0.7)
					(thickness 0.15)
				)
				(justify left bottom)
			)
		)
		(fp_text user "Author: Antmicro"
			(at -3 8.198 0)
			(layer "F.Fab")
			(effects
				(font
					(size 0.7 0.7)
					(thickness 0.15)
				)
				(justify left bottom)
			)
		)
		(fp_text user "License: Apache-2.0"
			(at -3 9.399 0)
			(layer "F.Fab")
			(effects
				(font
					(size 0.7 0.7)
					(thickness 0.15)
				)
				(justify left bottom)
			)
		)
		(pad "1" smd roundrect
			(at -1.101 -1.3 270)
			(size 1.6 1.4)
			(layers "F.Cu" "F.Mask" "F.Paste")
			(roundrect_rratio 0.2)
			(net 286 "Net-(Y2-EN)")
			(pinfunction "EN")
			(pintype "input")
		)
		(pad "2" smd roundrect
			(at -1.101 1.3 270)
			(size 1.6 1.4)
			(layers "F.Cu" "F.Mask" "F.Paste")
			(roundrect_rratio 0.2)
			(net 1 "GND")
			(pinfunction "GND")
			(pintype "power_in")
		)
		(pad "3" smd roundrect
			(at 1.1 1.3 270)
			(size 1.6 1.4)
			(layers "F.Cu" "F.Mask" "F.Paste")
			(roundrect_rratio 0.2)
			(net 186 "40MHz_3V3")
			(pinfunction "OUT")
			(pintype "output")
		)
		(pad "4" smd roundrect
			(at 1.1 -1.3 270)
			(size 1.6 1.4)
			(layers "F.Cu" "F.Mask" "F.Paste")
			(roundrect_rratio 0.2)
			(net 2 "+3V3")
			(pinfunction "VDD")
			(pintype "power_in")
		)
	)
	(footprint "antmicro-footprints:TP_SMD_0.75mm"
		(layer "F.Cu")
		(at 150.33 71.7 90)
		(property "Reference" "TP4"
			(at -0.64 1.4 90)
			(layer "F.SilkS")
			(effects
				(font
					(size 0.65 0.65)
					(thickness 0.15)
				)
				(justify left bottom)
			)
		)
		(property "Value" "TP_0.75mm_SMD"
			(at 0 1.2 90)
			(layer "F.Fab")
			(hide yes)
			(effects
				(font
					(size 0.7 0.7)
					(thickness 0.15)
				)
				(justify left bottom)
			)
		)
		(property "Description" "SMT test point"
			(at 0 0 90)
			(layer "F.Fab")
			(hide yes)
			(effects
				(font
					(size 1.27 1.27)
					(thickness 0.15)
				)
			)
		)
		(property "Author" "Antmicro"
			(at 222.03 -78.63 0)
			(layer "F.Fab")
			(hide yes)
			(effects
				(font
					(size 1 1)
					(thickness 0.15)
				)
			)
		)
		(property "License" "Apache-2.0"
			(at 222.03 -78.63 0)
			(layer "F.Fab")
			(hide yes)
			(effects
				(font
					(size 1 1)
					(thickness 0.15)
				)
			)
		)
		(property "MPN" ""
			(at 222.03 -78.63 0)
			(layer "F.Fab")
			(hide yes)
			(effects
				(font
					(size 1 1)
					(thickness 0.15)
				)
			)
		)
		(property "Manufacturer" ""
			(at 222.03 -78.63 0)
			(layer "F.Fab")
			(hide yes)
			(effects
				(font
					(size 1 1)
					(thickness 0.15)
				)
			)
		)
		(sheetname "/Power Supply/")
		(sheetfile "supply.kicad_sch")
		(attr exclude_from_pos_files)
		(fp_circle
			(center 0 0)
			(end 0.475 0)
			(stroke
				(width 0.05)
				(type default)
			)
			(fill no)
			(layer "F.CrtYd")
		)
		(fp_text user "${REFERENCE}"
			(at -0.4 2.7 90)
			(layer "F.Fab")
			(effects
				(font
					(size 0.7 0.7)
					(thickness 0.15)
				)
				(justify left bottom)
			)
		)
		(fp_text user "Author: Antmicro"
			(at -0.4 3.901 90)
			(layer "F.Fab")
			(effects
				(font
					(size 0.7 0.7)
					(thickness 0.15)
				)
				(justify left bottom)
			)
		)
		(fp_text user "License: Apache-2.0"
			(at -0.4 5.101 90)
			(layer "F.Fab")
			(effects
				(font
					(size 0.7 0.7)
					(thickness 0.15)
				)
				(justify left bottom)
			)
		)
		(pad "1" smd circle
			(at 0 0 90)
			(size 0.75 0.75)
			(layers "F.Cu" "F.Mask")
			(net 4 "1V0_Power")
			(pinfunction "1")
			(pintype "passive")
		)
	)
	(footprint "antmicro-footprints:R_0402_1005Metric"
		(layer "F.Cu")
		(at 144.39 106.35 90)
		(descr "Resistor SMD 0402")
		(tags "resistor SMD 0402")
		(property "Reference" "R24"
			(at 0.81 0.44 90)
			(layer "F.SilkS")
			(effects
				(font
					(size 0.65 0.65)
					(thickness 0.15)
				)
				(justify left bottom)
			)
		)
		(property "Value" "R_0R_0402"
			(at 0 1.4 90)
			(layer "F.Fab")
			(hide yes)
			(effects
				(font
					(size 0.7 0.7)
					(thickness 0.15)
				)
				(justify left bottom)
			)
		)
		(property "Datasheet" "https://industrial.panasonic.com/cdbs/www-data/pdf/RDA0000/AOA0000C301.pdf"
			(at 0 0 90)
			(layer "F.Fab")
			(hide yes)
			(effects
				(font
					(size 1.27 1.27)
					(thickness 0.15)
				)
			)
		)
		(property "Description" "SMD Chip Resistor, Jumper, 0 ohm, 100 mW, 0402 [1005 Metric], Thick Film, General Purpose"
			(at 0 0 90)
			(layer "F.Fab")
			(hide yes)
			(effects
				(font
					(size 1.27 1.27)
					(thickness 0.15)
				)
			)
		)
		(property "Author" "Antmicro"
			(at 250.74 -38.04 0)
			(layer "F.Fab")
			(hide yes)
			(effects
				(font
					(size 1 1)
					(thickness 0.15)
				)
			)
		)
		(property "Current" "1A"
			(at 250.74 -38.04 0)
			(layer "F.Fab")
			(hide yes)
			(effects
				(font
					(size 1 1)
					(thickness 0.15)
				)
			)
		)
		(property "License" "Apache-2.0"
			(at 250.74 -38.04 0)
			(layer "F.Fab")
			(hide yes)
			(effects
				(font
					(size 1 1)
					(thickness 0.15)
				)
			)
		)
		(property "MPN" "ERJ2GE0R00X"
			(at 250.74 -38.04 0)
			(layer "F.Fab")
			(hide yes)
			(effects
				(font
					(size 1 1)
					(thickness 0.15)
				)
			)
		)
		(property "Manufacturer" "Panasonic"
			(at 250.74 -38.04 0)
			(layer "F.Fab")
			(hide yes)
			(effects
				(font
					(size 1 1)
					(thickness 0.15)
				)
			)
		)
		(property "Tolerance" "~"
			(at 250.74 -38.04 0)
			(layer "F.Fab")
			(hide yes)
			(effects
				(font
					(size 1 1)
					(thickness 0.15)
				)
			)
		)
		(property "Val" "0R"
			(at 250.74 -38.04 0)
			(layer "F.Fab")
			(hide yes)
			(effects
				(font
					(size 1 1)
					(thickness 0.15)
				)
			)
		)
		(sheetname "/Power Supply/")
		(sheetfile "supply.kicad_sch")
		(attr smd)
		(fp_rect
			(start -0.925 -0.47)
			(end 0.925 0.47)
			(stroke
				(width 0.05)
				(type default)
			)
			(fill no)
			(layer "F.CrtYd")
		)
		(fp_rect
			(start -0.5 -0.25)
			(end 0.5 0.25)
			(stroke
				(width 0.15)
				(type solid)
			)
			(fill no)
			(layer "F.Fab")
		)
		(fp_text user "Author: Antmicro"
			(at -0.95 4.169 90)
			(layer "F.Fab")
			(effects
				(font
					(size 0.7 0.7)
					(thickness 0.15)
				)
				(justify left bottom)
			)
		)
		(fp_text user "${REFERENCE}"
			(at -0.95 3.168 90)
			(layer "F.Fab")
			(effects
				(font
					(size 0.7 0.7)
					(thickness 0.15)
				)
				(justify left bottom)
			)
		)
		(fp_text user "License: Apache-2.0"
			(at -0.95 5.169 90)
			(layer "F.Fab")
			(effects
				(font
					(size 0.7 0.7)
					(thickness 0.15)
				)
				(justify left bottom)
			)
		)
		(pad "1" smd roundrect
			(at -0.48 0 90)
			(size 0.59 0.64)
			(layers "F.Cu" "F.Mask" "F.Paste")
			(roundrect_rratio 0.25)
			(net 264 "Net-(U8-V_{IN})")
			(pintype "passive")
		)
		(pad "2" smd roundrect
			(at 0.48 0 90)
			(size 0.59 0.64)
			(layers "F.Cu" "F.Mask" "F.Paste")
			(roundrect_rratio 0.25)
			(net 268 "Net-(U8-EN)")
			(pintype "passive")
		)
	)
	(footprint "antmicro-footprints:R_0603_1608Metric"
		(layer "F.Cu")
		(at 169.83 82.55 180)
		(descr "Resistor SMD 0603")
		(tags "resistor SMD 0603")
		(property "Reference" "R103"
			(at 4.1 -0.39 180)
			(layer "F.SilkS")
			(effects
				(font
					(size 0.65 0.65)
					(thickness 0.15)
				)
				(justify left bottom)
			)
		)
		(property "Value" "R_470R_0603"
			(at 0 1.6 180)
			(layer "F.Fab")
			(hide yes)
			(effects
				(font
					(size 0.7 0.7)
					(thickness 0.15)
				)
				(justify left bottom)
			)
		)
		(property "Datasheet" "https://www.bourns.com/docs/product-datasheets/cr.pdf"
			(at 0 0 180)
			(layer "F.Fab")
			(hide yes)
			(effects
				(font
					(size 1.27 1.27)
					(thickness 0.15)
				)
			)
		)
		(property "Description" "SMD Chip Resistor, 470 ohm, ± 1%, 100 mW, 0603 [1608 Metric], Thick Film, General Purpose"
			(at 0 0 180)
			(layer "F.Fab")
			(hide yes)
			(effects
				(font
					(size 1.27 1.27)
					(thickness 0.15)
				)
			)
		)
		(property "Author" "Antmicro"
			(at 339.66 165.1 0)
			(layer "F.Fab")
			(hide yes)
			(effects
				(font
					(size 1 1)
					(thickness 0.15)
				)
			)
		)
		(property "License" "Apache-2.0"
			(at 339.66 165.1 0)
			(layer "F.Fab")
			(hide yes)
			(effects
				(font
					(size 1 1)
					(thickness 0.15)
				)
			)
		)
		(property "MPN" "CR0603-FX-4700ELF"
			(at 339.66 165.1 0)
			(layer "F.Fab")
			(hide yes)
			(effects
				(font
					(size 1 1)
					(thickness 0.15)
				)
			)
		)
		(property "Manufacturer" "Bourns"
			(at 339.66 165.1 0)
			(layer "F.Fab")
			(hide yes)
			(effects
				(font
					(size 1 1)
					(thickness 0.15)
				)
			)
		)
		(property "Tolerance" "1%"
			(at 339.66 165.1 0)
			(layer "F.Fab")
			(hide yes)
			(effects
				(font
					(size 1 1)
					(thickness 0.15)
				)
			)
		)
		(property "Val" "470R"
			(at 339.66 165.1 0)
			(layer "F.Fab")
			(hide yes)
			(effects
				(font
					(size 1 1)
					(thickness 0.15)
				)
			)
		)
		(sheetname "/Peripherals/")
		(sheetfile "peripherals.kicad_sch")
		(attr smd)
		(fp_line
			(start -0.15 0.4)
			(end 0.15 0.4)
			(stroke
				(width 0.15)
				(type solid)
			)
			(layer "F.SilkS")
		)
		(fp_line
			(start -0.15 -0.4)
			(end 0.15 -0.4)
			(stroke
				(width 0.15)
				(type solid)
			)
			(layer "F.SilkS")
		)
		(fp_rect
			(start -1.25 -0.65)
			(end 1.25 0.65)
			(stroke
				(width 0.05)
				(type solid)
			)
			(fill no)
			(layer "F.CrtYd")
		)
		(fp_rect
			(start -0.8 -0.4)
			(end 0.8 0.4)
			(stroke
				(width 0.15)
				(type solid)
			)
			(fill no)
			(layer "F.Fab")
		)
		(fp_text user "${REFERENCE}"
			(at -1.25 3.898 180)
			(layer "F.Fab")
			(effects
				(font
					(size 0.7 0.7)
					(thickness 0.15)
				)
				(justify left bottom)
			)
		)
		(fp_text user "Author: Antmicro"
			(at -1.25 4.9 180)
			(layer "F.Fab")
			(effects
				(font
					(size 0.7 0.7)
					(thickness 0.15)
				)
				(justify left bottom)
			)
		)
		(fp_text user "License: Apache-2.0"
			(at -1.25 5.9 180)
			(layer "F.Fab")
			(effects
				(font
					(size 0.7 0.7)
					(thickness 0.15)
				)
				(justify left bottom)
			)
		)
		(pad "1" smd roundrect
			(at -0.7 0 180)
			(size 0.8 1)
			(layers "F.Cu" "F.Mask" "F.Paste")
			(roundrect_rratio 0.2)
			(net 256 "Net-(D10-A)")
			(pintype "passive")
		)
		(pad "2" smd roundrect
			(at 0.7 0 180)
			(size 0.8 1)
			(layers "F.Cu" "F.Mask" "F.Paste")
			(roundrect_rratio 0.2)
			(net 16 "/Peripherals/FFC1_5V")
			(pintype "passive")
		)
	)
	(footprint "antmicro-footprints:R_1206_3216Metric"
		(layer "F.Cu")
		(at 154.79 70.65 -90)
		(property "Reference" "R13"
			(at 1.89 -2.04 270)
			(layer "F.SilkS")
			(effects
				(font
					(size 0.65 0.65)
					(thickness 0.15)
				)
				(justify left bottom)
			)
		)
		(property "Value" "R_0R_1206"
			(at 0 2 270)
			(layer "F.Fab")
			(hide yes)
			(effects
				(font
					(size 0.7 0.7)
					(thickness 0.15)
				)
				(justify left bottom)
			)
		)
		(property "Datasheet" "https://www.farnell.com/datasheets/2860635.pdf"
			(at 0 0 270)
			(layer "F.Fab")
			(hide yes)
			(effects
				(font
					(size 1.27 1.27)
					(thickness 0.15)
				)
			)
		)
		(property "Description" "Zero Ohm Resistor, Jumper, 1206 [3216 Metric], Thick Film, 250 mW, 2 A, Surface Mount Device"
			(at 0 0 270)
			(layer "F.Fab")
			(hide yes)
			(effects
				(font
					(size 1.27 1.27)
					(thickness 0.15)
				)
			)
		)
		(property "Author" "Antmicro"
			(at 84.14 225.44 0)
			(layer "F.Fab")
			(hide yes)
			(effects
				(font
					(size 1 1)
					(thickness 0.15)
				)
			)
		)
		(property "Current" "2A"
			(at 84.14 225.44 0)
			(layer "F.Fab")
			(hide yes)
			(effects
				(font
					(size 1 1)
					(thickness 0.15)
				)
			)
		)
		(property "License" "Apache-2.0"
			(at 84.14 225.44 0)
			(layer "F.Fab")
			(hide yes)
			(effects
				(font
					(size 1 1)
					(thickness 0.15)
				)
			)
		)
		(property "MPN" "MCMR12X000_PTL"
			(at 84.14 225.44 0)
			(layer "F.Fab")
			(hide yes)
			(effects
				(font
					(size 1 1)
					(thickness 0.15)
				)
			)
		)
		(property "Manufacturer" "Multicomp Pro"
			(at 84.14 225.44 0)
			(layer "F.Fab")
			(hide yes)
			(effects
				(font
					(size 1 1)
					(thickness 0.15)
				)
			)
		)
		(property "Tolerance" "~"
			(at 84.14 225.44 0)
			(layer "F.Fab")
			(hide yes)
			(effects
				(font
					(size 1 1)
					(thickness 0.15)
				)
			)
		)
		(property "Val" "0R"
			(at 84.14 225.44 0)
			(layer "F.Fab")
			(hide yes)
			(effects
				(font
					(size 1 1)
					(thickness 0.15)
				)
			)
		)
		(sheetname "/Power Supply/")
		(sheetfile "supply.kicad_sch")
		(attr smd)
		(fp_line
			(start 0.8 0.901)
			(end -0.8 0.901)
			(stroke
				(width 0.15)
				(type solid)
			)
			(layer "F.SilkS")
		)
		(fp_line
			(start 0.8 -0.899)
			(end -0.8 -0.899)
			(stroke
				(width 0.15)
				(type solid)
			)
			(layer "F.SilkS")
		)
		(fp_rect
			(start -2.325 -1.15)
			(end 2.325 1.15)
			(stroke
				(width 0.05)
				(type default)
			)
			(fill no)
			(layer "F.CrtYd")
		)
		(fp_line
			(start -1.601 0.8)
			(end 1.6 0.8)
			(stroke
				(width 0.15)
				(type solid)
			)
			(layer "F.Fab")
		)
		(fp_line
			(start -1.601 -0.802)
			(end -1.601 0.8)
			(stroke
				(width 0.15)
				(type solid)
			)
			(layer "F.Fab")
		)
		(fp_line
			(start -1.601 -0.802)
			(end 1.6 -0.802)
			(stroke
				(width 0.15)
				(type solid)
			)
			(layer "F.Fab")
		)
		(fp_line
			(start 1.6 -0.802)
			(end 1.6 0.8)
			(stroke
				(width 0.15)
				(type solid)
			)
			(layer "F.Fab")
		)
		(fp_text user "${REFERENCE}"
			(at -2.401 3.5 270)
			(layer "F.Fab")
			(effects
				(font
					(size 0.7 0.7)
					(thickness 0.15)
				)
				(justify left bottom)
			)
		)
		(fp_text user "Author: Antmicro"
			(at -2.401 4.899 270)
			(layer "F.Fab")
			(effects
				(font
					(size 0.7 0.7)
					(thickness 0.15)
				)
				(justify left bottom)
			)
		)
		(fp_text user "License: Apache-2.0"
			(at -2.401 6.3 270)
			(layer "F.Fab")
			(effects
				(font
					(size 0.7 0.7)
					(thickness 0.15)
				)
				(justify left bottom)
			)
		)
		(pad "1" smd roundrect
			(at -1.5 0.001 270)
			(size 1.15 1.8)
			(layers "F.Cu" "F.Mask" "F.Paste")
			(roundrect_rratio 0.25)
			(net 304 "/Power Supply/5V_I")
			(pintype "passive")
		)
		(pad "2" smd roundrect
			(at 1.5 0.001 270)
			(size 1.15 1.8)
			(layers "F.Cu" "F.Mask" "F.Paste")
			(roundrect_rratio 0.25)
			(net 14 "+5V")
			(pintype "passive")
		)
	)
	(footprint "antmicro-footprints:SOT-23-6"
		(layer "F.Cu")
		(at 161.4 91.1 -90)
		(property "Reference" "U13"
			(at -1.75 0.77 0)
			(layer "F.SilkS")
			(effects
				(font
					(size 0.65 0.65)
					(thickness 0.15)
				)
				(justify left bottom)
			)
		)
		(property "Value" "DIO7553ST6"
			(at -1.75 2.75 90)
			(layer "F.Fab")
			(hide yes)
			(effects
				(font
					(size 0.7 0.7)
					(thickness 0.15)
				)
				(justify right top)
			)
		)
		(property "Datasheet" "https://www.mouser.com/datasheet/2/802/7e5c577022fb784effcb3cdb25b437c0-1815562.pdf"
			(at 0 0 90)
			(layer "F.Fab")
			(hide yes)
			(effects
				(font
					(size 1.27 1.27)
					(thickness 0.15)
				)
			)
		)
		(property "Description" "Power switch"
			(at 0 0 90)
			(layer "F.Fab")
			(hide yes)
			(effects
				(font
					(size 1.27 1.27)
					(thickness 0.15)
				)
			)
		)
		(property "Author" "Antmicro"
			(at 70.3 252.5 0)
			(layer "F.Fab")
			(hide yes)
			(effects
				(font
					(size 1 1)
					(thickness 0.15)
				)
			)
		)
		(property "License" "Apache-2.0"
			(at 70.3 252.5 0)
			(layer "F.Fab")
			(hide yes)
			(effects
				(font
					(size 1 1)
					(thickness 0.15)
				)
			)
		)
		(property "MPN" "DIO7553ST6"
			(at 70.3 252.5 0)
			(layer "F.Fab")
			(hide yes)
			(effects
				(font
					(size 1 1)
					(thickness 0.15)
				)
			)
		)
		(property "Manufacturer" "DIOO Microcircuits"
			(at 70.3 252.5 0)
			(layer "F.Fab")
			(hide yes)
			(effects
				(font
					(size 1 1)
					(thickness 0.15)
				)
			)
		)
		(sheetname "/Peripherals/")
		(sheetfile "peripherals.kicad_sch")
		(attr smd)
		(fp_line
			(start -1.45 0.643)
			(end -1.45 0.343)
			(stroke
				(width 0.12)
				(type solid)
			)
			(layer "F.SilkS")
		)
		(fp_line
			(start 1.3 0.643)
			(end 1.45 0.643)
			(stroke
				(width 0.12)
				(type solid)
			)
			(layer "F.SilkS")
		)
		(fp_line
			(start 1.45 0.643)
			(end 1.45 0.343)
			(stroke
				(width 0.12)
				(type solid)
			)
			(layer "F.SilkS")
		)
		(fp_line
			(start -1.45 -0.757)
			(end -1.45 -0.457)
			(stroke
				(width 0.12)
				(type solid)
			)
			(layer "F.SilkS")
		)
		(fp_line
			(start -1.3 -0.757)
			(end -1.45 -0.757)
			(stroke
				(width 0.12)
				(type solid)
			)
			(layer "F.SilkS")
		)
		(fp_line
			(start 1.3 -0.757)
			(end 1.45 -0.757)
			(stroke
				(width 0.12)
				(type solid)
			)
			(layer "F.SilkS")
		)
		(fp_line
			(start 1.45 -0.757)
			(end 1.45 -0.457)
			(stroke
				(width 0.12)
				(type solid)
			)
			(layer "F.SilkS")
		)
		(fp_rect
			(start -1.55 -1.85)
			(end 1.55 1.75)
			(stroke
				(width 0.05)
				(type solid)
			)
			(fill no)
			(layer "F.CrtYd")
		)
		(fp_line
			(start -1.5 0.643)
			(end -1.5 -0.757)
			(stroke
				(width 0.1)
				(type solid)
			)
			(layer "F.Fab")
		)
		(fp_line
			(start 1.5 0.643)
			(end -1.5 0.643)
			(stroke
				(width 0.1)
				(type solid)
			)
			(layer "F.Fab")
		)
		(fp_line
			(start -1.5 -0.757)
			(end 1.5 -0.757)
			(stroke
				(width 0.1)
				(type solid)
			)
			(layer "F.Fab")
		)
		(fp_line
			(start 1.5 -0.757)
			(end 1.5 0.643)
			(stroke
				(width 0.1)
				(type solid)
			)
			(layer "F.Fab")
		)
		(fp_text user "."
			(at -1.48 1.5 90)
			(layer "F.SilkS")
			(effects
				(font
					(size 1 1)
					(thickness 0.15)
				)
			)
		)
		(fp_text user "License: Apache-2.0"
			(at -1.75 6.5 270)
			(layer "F.Fab")
			(effects
				(font
					(size 0.7 0.7)
					(thickness 0.15)
				)
				(justify left bottom)
			)
		)
		(fp_text user "Author: Antmicro"
			(at -1.829 5.25 270)
			(layer "F.Fab")
			(effects
				(font
					(size 0.7 0.7)
					(thickness 0.15)
				)
				(justify left bottom)
			)
		)
		(fp_text user "${REFERENCE}"
			(at -1.75 4 270)
			(layer "F.Fab")
			(effects
				(font
					(size 0.7 0.7)
					(thickness 0.15)
				)
				(justify left bottom)
			)
		)
		(pad "1" smd roundrect
			(at -0.954 1.1 270)
			(size 0.55 1)
			(layers "F.Cu" "F.Mask" "F.Paste")
			(roundrect_rratio 0.15)
			(net 2 "+3V3")
			(pinfunction "IN")
			(pintype "power_in")
		)
		(pad "2" smd roundrect
			(at -0.003 1.1 270)
			(size 0.55 1)
			(layers "F.Cu" "F.Mask" "F.Paste")
			(roundrect_rratio 0.15)
			(net 1 "GND")
			(pinfunction "GND")
			(pintype "power_in")
		)
		(pad "3" smd roundrect
			(at 0.947 1.1 270)
			(size 0.55 1)
			(layers "F.Cu" "F.Mask" "F.Paste")
			(roundrect_rratio 0.15)
			(net 307 "/Peripherals/FFC1_PEN")
			(pinfunction "EN")
			(pintype "input")
		)
		(pad "4" smd roundrect
			(at 0.947 -1.214 270)
			(size 0.55 1)
			(layers "F.Cu" "F.Mask" "F.Paste")
			(roundrect_rratio 0.15)
			(net 351 "Net-(U13-~{FAULT})")
			(pinfunction "~{FAULT}")
			(pintype "output")
		)
		(pad "5" smd roundrect
			(at -0.003 -1.214 270)
			(size 0.55 1)
			(layers "F.Cu" "F.Mask" "F.Paste")
			(roundrect_rratio 0.15)
			(net 353 "Net-(U13-ILIM)")
			(pinfunction "ILIM")
			(pintype "passive")
		)
		(pad "6" smd roundrect
			(at -0.954 -1.214 270)
			(size 0.55 1)
			(layers "F.Cu" "F.Mask" "F.Paste")
			(roundrect_rratio 0.15)
			(net 17 "/Peripherals/FFC1_3V3")
			(pinfunction "OUT")
			(pintype "power_out")
		)
	)
	(footprint "antmicro-footprints:R_0603_1608Metric"
		(layer "F.Cu")
		(at 108.75 70.55 90)
		(descr "Resistor SMD 0603")
		(tags "resistor SMD 0603")
		(property "Reference" "R101"
			(at 1.41 0.28 90)
			(layer "F.SilkS")
			(effects
				(font
					(size 0.65 0.65)
					(thickness 0.15)
				)
				(justify left bottom)
			)
		)
		(property "Value" "R_200R_0603"
			(at 0 1.6 90)
			(layer "F.Fab")
			(hide yes)
			(effects
				(font
					(size 0.7 0.7)
					(thickness 0.15)
				)
				(justify left bottom)
			)
		)
		(property "Datasheet" "https://www.bourns.com/docs/product-datasheets/cr.pdf"
			(at 0 0 90)
			(layer "F.Fab")
			(hide yes)
			(effects
				(font
					(size 1.27 1.27)
					(thickness 0.15)
				)
			)
		)
		(property "Description" "SMD Chip Resistor, 200 ohm, ± 1%, 100 mW, 0603 [1608 Metric], Thick Film, General Purpose"
			(at 0 0 90)
			(layer "F.Fab")
			(hide yes)
			(effects
				(font
					(size 1.27 1.27)
					(thickness 0.15)
				)
			)
		)
		(property "Author" "Antmicro"
			(at 179.3 -38.2 0)
			(layer "F.Fab")
			(hide yes)
			(effects
				(font
					(size 1 1)
					(thickness 0.15)
				)
			)
		)
		(property "License" "Apache-2.0"
			(at 179.3 -38.2 0)
			(layer "F.Fab")
			(hide yes)
			(effects
				(font
					(size 1 1)
					(thickness 0.15)
				)
			)
		)
		(property "MPN" "CR0603-FX-2000ELF"
			(at 179.3 -38.2 0)
			(layer "F.Fab")
			(hide yes)
			(effects
				(font
					(size 1 1)
					(thickness 0.15)
				)
			)
		)
		(property "Manufacturer" "Bourns"
			(at 179.3 -38.2 0)
			(layer "F.Fab")
			(hide yes)
			(effects
				(font
					(size 1 1)
					(thickness 0.15)
				)
			)
		)
		(property "Tolerance" "1%"
			(at 179.3 -38.2 0)
			(layer "F.Fab")
			(hide yes)
			(effects
				(font
					(size 1 1)
					(thickness 0.15)
				)
			)
		)
		(property "Val" "200R"
			(at 179.3 -38.2 0)
			(layer "F.Fab")
			(hide yes)
			(effects
				(font
					(size 1 1)
					(thickness 0.15)
				)
			)
		)
		(sheetname "/SDI/")
		(sheetfile "sdi.kicad_sch")
		(attr smd)
		(fp_line
			(start -0.15 -0.4)
			(end 0.15 -0.4)
			(stroke
				(width 0.15)
				(type solid)
			)
			(layer "F.SilkS")
		)
		(fp_line
			(start -0.15 0.4)
			(end 0.15 0.4)
			(stroke
				(width 0.15)
				(type solid)
			)
			(layer "F.SilkS")
		)
		(fp_rect
			(start -1.25 -0.65)
			(end 1.25 0.65)
			(stroke
				(width 0.05)
				(type solid)
			)
			(fill no)
			(layer "F.CrtYd")
		)
		(fp_rect
			(start -0.8 -0.4)
			(end 0.8 0.4)
			(stroke
				(width 0.15)
				(type solid)
			)
			(fill no)
			(layer "F.Fab")
		)
		(fp_text user "License: Apache-2.0"
			(at -1.25 5.9 90)
			(layer "F.Fab")
			(effects
				(font
					(size 0.7 0.7)
					(thickness 0.15)
				)
				(justify left bottom)
			)
		)
		(fp_text user "${REFERENCE}"
			(at -1.25 3.898 90)
			(layer "F.Fab")
			(effects
				(font
					(size 0.7 0.7)
					(thickness 0.15)
				)
				(justify left bottom)
			)
		)
		(fp_text user "Author: Antmicro"
			(at -1.25 4.9 90)
			(layer "F.Fab")
			(effects
				(font
					(size 0.7 0.7)
					(thickness 0.15)
				)
				(justify left bottom)
			)
		)
		(pad "1" smd roundrect
			(at -0.7 0 90)
			(size 0.8 1)
			(layers "F.Cu" "F.Mask" "F.Paste")
			(roundrect_rratio 0.2)
			(net 247 "Net-(D8-A)")
			(pintype "passive")
		)
		(pad "2" smd roundrect
			(at 0.7 0 90)
			(size 0.8 1)
			(layers "F.Cu" "F.Mask" "F.Paste")
			(roundrect_rratio 0.2)
			(net 219 "/SDI/SDI_STAT3")
			(pintype "passive")
		)
	)
	(footprint "antmicro-footprints:R_0402_1005Metric"
		(layer "F.Cu")
		(at 84.2 107.15 180)
		(descr "Resistor SMD 0402")
		(tags "resistor SMD 0402")
		(property "Reference" "R60"
			(at -4.33 7.91 0)
			(layer "F.SilkS")
			(effects
				(font
					(size 0.65 0.65)
					(thickness 0.15)
				)
				(justify right bottom)
			)
		)
		(property "Value" "R_75R_0402"
			(at 0 1.4 0)
			(layer "F.Fab")
			(hide yes)
			(effects
				(font
					(size 0.7 0.7)
					(thickness 0.15)
				)
				(justify right bottom)
			)
		)
		(property "Datasheet" "https://www.bourns.com/docs/product-datasheets/cr.pdf"
			(at 0 0 180)
			(layer "F.Fab")
			(hide yes)
			(effects
				(font
					(size 1.27 1.27)
					(thickness 0.15)
				)
			)
		)
		(property "Description" "SMD Chip Resistor, 75 ohm, ± 1%, 62.5 mW, 0402 [1005 Metric], Thick Film, General Purpose"
			(at 0 0 180)
			(layer "F.Fab")
			(hide yes)
			(effects
				(font
					(size 1.27 1.27)
					(thickness 0.15)
				)
			)
		)
		(property "Author" "Antmicro"
			(at 168.4 214.3 0)
			(layer "F.Fab")
			(hide yes)
			(effects
				(font
					(size 1 1)
					(thickness 0.15)
				)
			)
		)
		(property "License" "Apache-2.0"
			(at 168.4 214.3 0)
			(layer "F.Fab")
			(hide yes)
			(effects
				(font
					(size 1 1)
					(thickness 0.15)
				)
			)
		)
		(property "MPN" "CR0402-FX-75R0GLF"
			(at 168.4 214.3 0)
			(layer "F.Fab")
			(hide yes)
			(effects
				(font
					(size 1 1)
					(thickness 0.15)
				)
			)
		)
		(property "Manufacturer" "Bourns"
			(at 168.4 214.3 0)
			(layer "F.Fab")
			(hide yes)
			(effects
				(font
					(size 1 1)
					(thickness 0.15)
				)
			)
		)
		(property "Tolerance" "1%"
			(at 168.4 214.3 0)
			(layer "F.Fab")
			(hide yes)
			(effects
				(font
					(size 1 1)
					(thickness 0.15)
				)
			)
		)
		(property "Val" "75R"
			(at 168.4 214.3 0)
			(layer "F.Fab")
			(hide yes)
			(effects
				(font
					(size 1 1)
					(thickness 0.15)
				)
			)
		)
		(sheetname "/SDI/")
		(sheetfile "sdi.kicad_sch")
		(attr smd)
		(fp_rect
			(start -0.925 -0.47)
			(end 0.925 0.47)
			(stroke
				(width 0.05)
				(type default)
			)
			(fill no)
			(layer "F.CrtYd")
		)
		(fp_rect
			(start -0.5 -0.25)
			(end 0.5 0.25)
			(stroke
				(width 0.15)
				(type solid)
			)
			(fill no)
			(layer "F.Fab")
		)
		(fp_text user "Author: Antmicro"
			(at -0.95 4.169 180)
			(layer "F.Fab")
			(effects
				(font
					(size 0.7 0.7)
					(thickness 0.15)
				)
				(justify left bottom)
			)
		)
		(fp_text user "License: Apache-2.0"
			(at -0.95 5.169 180)
			(layer "F.Fab")
			(effects
				(font
					(size 0.7 0.7)
					(thickness 0.15)
				)
				(justify left bottom)
			)
		)
		(fp_text user "${REFERENCE}"
			(at -0.95 3.168 180)
			(layer "F.Fab")
			(effects
				(font
					(size 0.7 0.7)
					(thickness 0.15)
				)
				(justify left bottom)
			)
		)
		(pad "1" smd roundrect
			(at -0.48 0 180)
			(size 0.59 0.64)
			(layers "F.Cu" "F.Mask" "F.Paste")
			(roundrect_rratio 0.25)
			(net 249 "/SDI/SDI_OUT_P")
			(pintype "passive")
		)
		(pad "2" smd roundrect
			(at 0.48 0 180)
			(size 0.59 0.64)
			(layers "F.Cu" "F.Mask" "F.Paste")
			(roundrect_rratio 0.25)
			(net 2 "+3V3")
			(pintype "passive")
		)
	)
	(footprint "antmicro-footprints:C_0603_1608Metric"
		(layer "F.Cu")
		(at 144.39 65.34)
		(descr "Capacitor SMD 0603")
		(tags "capacitor 0603")
		(property "Reference" "C24"
			(at -7.56 0.1 0)
			(layer "F.SilkS")
			(effects
				(font
					(size 0.65 0.65)
					(thickness 0.15)
				)
				(justify left bottom)
			)
		)
		(property "Value" "C_22u_0603"
			(at 0 1.6 0)
			(layer "F.Fab")
			(hide yes)
			(effects
				(font
					(size 0.7 0.7)
					(thickness 0.15)
				)
				(justify left bottom)
			)
		)
		(property "Datasheet" "https://www.murata.com/products/productdetail?partno=GRM188R60J226MEA0%23"
			(at 0 0 0)
			(layer "F.Fab")
			(hide yes)
			(effects
				(font
					(size 1.27 1.27)
					(thickness 0.15)
				)
			)
		)
		(property "Description" "SMD Multilayer Ceramic Capacitor, 22 µF, 6.3 V, 0603 [1608 Metric], ± 20%, X5R, GRM Series"
			(at 0 0 0)
			(layer "F.Fab")
			(hide yes)
			(effects
				(font
					(size 1.27 1.27)
					(thickness 0.15)
				)
			)
		)
		(property "Author" "Antmicro"
			(at 0 0 0)
			(layer "F.Fab")
			(hide yes)
			(effects
				(font
					(size 1 1)
					(thickness 0.15)
				)
			)
		)
		(property "Dielectric" ""
			(at 0 0 0)
			(layer "F.Fab")
			(hide yes)
			(effects
				(font
					(size 1 1)
					(thickness 0.15)
				)
			)
		)
		(property "License" "Apache-2.0"
			(at 0 0 0)
			(layer "F.Fab")
			(hide yes)
			(effects
				(font
					(size 1 1)
					(thickness 0.15)
				)
			)
		)
		(property "MPN" "GRM188R60J226MEA0D"
			(at 0 0 0)
			(layer "F.Fab")
			(hide yes)
			(effects
				(font
					(size 1 1)
					(thickness 0.15)
				)
			)
		)
		(property "Manufacturer" "Murata"
			(at 0 0 0)
			(layer "F.Fab")
			(hide yes)
			(effects
				(font
					(size 1 1)
					(thickness 0.15)
				)
			)
		)
		(property "Val" "22u"
			(at 0 0 0)
			(layer "F.Fab")
			(hide yes)
			(effects
				(font
					(size 1 1)
					(thickness 0.15)
				)
			)
		)
		(property "Voltage" ""
			(at 0 0 0)
			(layer "F.Fab")
			(hide yes)
			(effects
				(font
					(size 1 1)
					(thickness 0.15)
				)
			)
		)
		(sheetname "/Power Supply/")
		(sheetfile "supply.kicad_sch")
		(attr smd)
		(fp_line
			(start -0.15 -0.4)
			(end 0.15 -0.4)
			(stroke
				(width 0.15)
				(type solid)
			)
			(layer "F.SilkS")
		)
		(fp_line
			(start -0.15 0.4)
			(end 0.15 0.4)
			(stroke
				(width 0.15)
				(type solid)
			)
			(layer "F.SilkS")
		)
		(fp_rect
			(start -1.25 -0.65)
			(end 1.25 0.65)
			(stroke
				(width 0.05)
				(type solid)
			)
			(fill no)
			(layer "F.CrtYd")
		)
		(fp_rect
			(start -0.8 -0.4)
			(end 0.8 0.4)
			(stroke
				(width 0.15)
				(type solid)
			)
			(fill no)
			(layer "F.Fab")
		)
		(fp_text user "Author: Antmicro"
			(at -1.682 4.894 0)
			(layer "F.Fab")
			(effects
				(font
					(size 0.7 0.7)
					(thickness 0.15)
				)
				(justify left bottom)
			)
		)
		(fp_text user "${REFERENCE}"
			(at -1.682 3.895 0)
			(layer "F.Fab")
			(effects
				(font
					(size 0.7 0.7)
					(thickness 0.15)
				)
				(justify left bottom)
			)
		)
		(fp_text user "License: Apache-2.0"
			(at -1.682 5.895 0)
			(layer "F.Fab")
			(effects
				(font
					(size 0.7 0.7)
					(thickness 0.15)
				)
				(justify left bottom)
			)
		)
		(pad "1" smd roundrect
			(at -0.7 0)
			(size 0.8 1)
			(layers "F.Cu" "F.Mask" "F.Paste")
			(roundrect_rratio 0.2)
			(net 274 "/Power Supply/1V5_OUT")
			(pintype "passive")
		)
		(pad "2" smd roundrect
			(at 0.7 0)
			(size 0.8 1)
			(layers "F.Cu" "F.Mask" "F.Paste")
			(roundrect_rratio 0.2)
			(net 1 "GND")
			(pintype "passive")
		)
	)
	(footprint "antmicro-footprints:R_0402_1005Metric"
		(layer "F.Cu")
		(at 144.94 112.75 180)
		(descr "Resistor SMD 0402")
		(tags "resistor SMD 0402")
		(property "Reference" "R21"
			(at -0.89 -0.39 180)
			(layer "F.SilkS")
			(effects
				(font
					(size 0.65 0.65)
					(thickness 0.15)
				)
				(justify left bottom)
			)
		)
		(property "Value" "R_0R_0402"
			(at 0 1.4 180)
			(layer "F.Fab")
			(hide yes)
			(effects
				(font
					(size 0.7 0.7)
					(thickness 0.15)
				)
				(justify left bottom)
			)
		)
		(property "Datasheet" "https://industrial.panasonic.com/cdbs/www-data/pdf/RDA0000/AOA0000C301.pdf"
			(at 0 0 180)
			(layer "F.Fab")
			(hide yes)
			(effects
				(font
					(size 1.27 1.27)
					(thickness 0.15)
				)
			)
		)
		(property "Description" "SMD Chip Resistor, Jumper, 0 ohm, 100 mW, 0402 [1005 Metric], Thick Film, General Purpose"
			(at 0 0 180)
			(layer "F.Fab")
			(hide yes)
			(effects
				(font
					(size 1.27 1.27)
					(thickness 0.15)
				)
			)
		)
		(property "Author" "Antmicro"
			(at 289.88 225.5 0)
			(layer "F.Fab")
			(hide yes)
			(effects
				(font
					(size 1 1)
					(thickness 0.15)
				)
			)
		)
		(property "Current" "1A"
			(at 289.88 225.5 0)
			(layer "F.Fab")
			(hide yes)
			(effects
				(font
					(size 1 1)
					(thickness 0.15)
				)
			)
		)
		(property "License" "Apache-2.0"
			(at 289.88 225.5 0)
			(layer "F.Fab")
			(hide yes)
			(effects
				(font
					(size 1 1)
					(thickness 0.15)
				)
			)
		)
		(property "MPN" "ERJ2GE0R00X"
			(at 289.88 225.5 0)
			(layer "F.Fab")
			(hide yes)
			(effects
				(font
					(size 1 1)
					(thickness 0.15)
				)
			)
		)
		(property "Manufacturer" "Panasonic"
			(at 289.88 225.5 0)
			(layer "F.Fab")
			(hide yes)
			(effects
				(font
					(size 1 1)
					(thickness 0.15)
				)
			)
		)
		(property "Tolerance" "~"
			(at 289.88 225.5 0)
			(layer "F.Fab")
			(hide yes)
			(effects
				(font
					(size 1 1)
					(thickness 0.15)
				)
			)
		)
		(property "Val" "0R"
			(at 289.88 225.5 0)
			(layer "F.Fab")
			(hide yes)
			(effects
				(font
					(size 1 1)
					(thickness 0.15)
				)
			)
		)
		(sheetname "/Power Supply/")
		(sheetfile "supply.kicad_sch")
		(attr smd)
		(fp_rect
			(start -0.925 -0.47)
			(end 0.925 0.47)
			(stroke
				(width 0.05)
				(type default)
			)
			(fill no)
			(layer "F.CrtYd")
		)
		(fp_rect
			(start -0.5 -0.25)
			(end 0.5 0.25)
			(stroke
				(width 0.15)
				(type solid)
			)
			(fill no)
			(layer "F.Fab")
		)
		(fp_text user "License: Apache-2.0"
			(at -0.95 5.169 180)
			(layer "F.Fab")
			(effects
				(font
					(size 0.7 0.7)
					(thickness 0.15)
				)
				(justify left bottom)
			)
		)
		(fp_text user "${REFERENCE}"
			(at -0.95 3.168 180)
			(layer "F.Fab")
			(effects
				(font
					(size 0.7 0.7)
					(thickness 0.15)
				)
				(justify left bottom)
			)
		)
		(fp_text user "Author: Antmicro"
			(at -0.95 4.169 180)
			(layer "F.Fab")
			(effects
				(font
					(size 0.7 0.7)
					(thickness 0.15)
				)
				(justify left bottom)
			)
		)
		(pad "1" smd roundrect
			(at -0.48 0 180)
			(size 0.59 0.64)
			(layers "F.Cu" "F.Mask" "F.Paste")
			(roundrect_rratio 0.25)
			(net 2 "+3V3")
			(pintype "passive")
		)
		(pad "2" smd roundrect
			(at 0.48 0 180)
			(size 0.59 0.64)
			(layers "F.Cu" "F.Mask" "F.Paste")
			(roundrect_rratio 0.25)
			(net 266 "Net-(U10-V_{IN})")
			(pintype "passive")
		)
	)
	(footprint "antmicro-footprints:R_0402_1005Metric"
		(layer "F.Cu")
		(at 140.64 104.55)
		(descr "Resistor SMD 0402")
		(tags "resistor SMD 0402")
		(property "Reference" "R32"
			(at -1.01 -0.7 0)
			(layer "F.SilkS")
			(effects
				(font
					(size 0.65 0.65)
					(thickness 0.15)
				)
				(justify left bottom)
			)
		)
		(property "Value" "R_10k_0402"
			(at 0 1.4 0)
			(layer "F.Fab")
			(hide yes)
			(effects
				(font
					(size 0.7 0.7)
					(thickness 0.15)
				)
				(justify left bottom)
			)
		)
		(property "Datasheet" "https://www.bourns.com/docs/product-datasheets/cr.pdf"
			(at 0 0 0)
			(layer "F.Fab")
			(hide yes)
			(effects
				(font
					(size 1.27 1.27)
					(thickness 0.15)
				)
			)
		)
		(property "Description" "SMD Chip Resistor, 10 kohm, ± 1%, 62.5 mW, 0402 [1005 Metric], Thick Film, General Purpose"
			(at 0 0 0)
			(layer "F.Fab")
			(hide yes)
			(effects
				(font
					(size 1.27 1.27)
					(thickness 0.15)
				)
			)
		)
		(property "Author" "Antmicro"
			(at 0 0 0)
			(layer "F.Fab")
			(hide yes)
			(effects
				(font
					(size 1 1)
					(thickness 0.15)
				)
			)
		)
		(property "License" "Apache-2.0"
			(at 0 0 0)
			(layer "F.Fab")
			(hide yes)
			(effects
				(font
					(size 1 1)
					(thickness 0.15)
				)
			)
		)
		(property "MPN" "CR0402-FX-1002GLF"
			(at 0 0 0)
			(layer "F.Fab")
			(hide yes)
			(effects
				(font
					(size 1 1)
					(thickness 0.15)
				)
			)
		)
		(property "Manufacturer" "Bourns"
			(at 0 0 0)
			(layer "F.Fab")
			(hide yes)
			(effects
				(font
					(size 1 1)
					(thickness 0.15)
				)
			)
		)
		(property "Tolerance" "1%"
			(at 0 0 0)
			(layer "F.Fab")
			(hide yes)
			(effects
				(font
					(size 1 1)
					(thickness 0.15)
				)
			)
		)
		(property "Val" "10k"
			(at 0 0 0)
			(layer "F.Fab")
			(hide yes)
			(effects
				(font
					(size 1 1)
					(thickness 0.15)
				)
			)
		)
		(sheetname "/Power Supply/")
		(sheetfile "supply.kicad_sch")
		(attr smd)
		(fp_rect
			(start -0.925 -0.47)
			(end 0.925 0.47)
			(stroke
				(width 0.05)
				(type default)
			)
			(fill no)
			(layer "F.CrtYd")
		)
		(fp_rect
			(start -0.5 -0.25)
			(end 0.5 0.25)
			(stroke
				(width 0.15)
				(type solid)
			)
			(fill no)
			(layer "F.Fab")
		)
		(fp_text user "${REFERENCE}"
			(at -0.95 3.168 0)
			(layer "F.Fab")
			(effects
				(font
					(size 0.7 0.7)
					(thickness 0.15)
				)
				(justify left bottom)
			)
		)
		(fp_text user "Author: Antmicro"
			(at -0.95 4.169 0)
			(layer "F.Fab")
			(effects
				(font
					(size 0.7 0.7)
					(thickness 0.15)
				)
				(justify left bottom)
			)
		)
		(fp_text user "License: Apache-2.0"
			(at -0.95 5.169 0)
			(layer "F.Fab")
			(effects
				(font
					(size 0.7 0.7)
					(thickness 0.15)
				)
				(justify left bottom)
			)
		)
		(pad "1" smd roundrect
			(at -0.48 0)
			(size 0.59 0.64)
			(layers "F.Cu" "F.Mask" "F.Paste")
			(roundrect_rratio 0.25)
			(net 1 "GND")
			(pintype "passive")
		)
		(pad "2" smd roundrect
			(at 0.48 0)
			(size 0.59 0.64)
			(layers "F.Cu" "F.Mask" "F.Paste")
			(roundrect_rratio 0.25)
			(net 280 "Net-(U8-ADJ)")
			(pintype "passive")
		)
	)
	(footprint "antmicro-footprints:C_0603_1608Metric"
		(layer "F.Cu")
		(at 148.23 74.84 180)
		(descr "Capacitor SMD 0603")
		(tags "capacitor 0603")
		(property "Reference" "C32"
			(at -3.4 -0.4 0)
			(layer "F.SilkS")
			(effects
				(font
					(size 0.65 0.65)
					(thickness 0.15)
				)
				(justify right bottom)
			)
		)
		(property "Value" "C_22u_0603"
			(at 0 1.6 0)
			(layer "F.Fab")
			(hide yes)
			(effects
				(font
					(size 0.7 0.7)
					(thickness 0.15)
				)
				(justify right bottom)
			)
		)
		(property "Datasheet" "https://www.murata.com/products/productdetail?partno=GRM188R60J226MEA0%23"
			(at 0 0 180)
			(layer "F.Fab")
			(hide yes)
			(effects
				(font
					(size 1.27 1.27)
					(thickness 0.15)
				)
			)
		)
		(property "Description" "SMD Multilayer Ceramic Capacitor, 22 µF, 6.3 V, 0603 [1608 Metric], ± 20%, X5R, GRM Series"
			(at 0 0 180)
			(layer "F.Fab")
			(hide yes)
			(effects
				(font
					(size 1.27 1.27)
					(thickness 0.15)
				)
			)
		)
		(property "Author" "Antmicro"
			(at 296.46 149.68 0)
			(layer "F.Fab")
			(hide yes)
			(effects
				(font
					(size 1 1)
					(thickness 0.15)
				)
			)
		)
		(property "Dielectric" ""
			(at 296.46 149.68 0)
			(layer "F.Fab")
			(hide yes)
			(effects
				(font
					(size 1 1)
					(thickness 0.15)
				)
			)
		)
		(property "License" "Apache-2.0"
			(at 296.46 149.68 0)
			(layer "F.Fab")
			(hide yes)
			(effects
				(font
					(size 1 1)
					(thickness 0.15)
				)
			)
		)
		(property "MPN" "GRM188R60J226MEA0D"
			(at 296.46 149.68 0)
			(layer "F.Fab")
			(hide yes)
			(effects
				(font
					(size 1 1)
					(thickness 0.15)
				)
			)
		)
		(property "Manufacturer" "Murata"
			(at 296.46 149.68 0)
			(layer "F.Fab")
			(hide yes)
			(effects
				(font
					(size 1 1)
					(thickness 0.15)
				)
			)
		)
		(property "Val" "22u"
			(at 296.46 149.68 0)
			(layer "F.Fab")
			(hide yes)
			(effects
				(font
					(size 1 1)
					(thickness 0.15)
				)
			)
		)
		(property "Voltage" ""
			(at 296.46 149.68 0)
			(layer "F.Fab")
			(hide yes)
			(effects
				(font
					(size 1 1)
					(thickness 0.15)
				)
			)
		)
		(sheetname "/Power Supply/")
		(sheetfile "supply.kicad_sch")
		(attr smd)
		(fp_line
			(start -0.15 0.4)
			(end 0.15 0.4)
			(stroke
				(width 0.15)
				(type solid)
			)
			(layer "F.SilkS")
		)
		(fp_line
			(start -0.15 -0.4)
			(end 0.15 -0.4)
			(stroke
				(width 0.15)
				(type solid)
			)
			(layer "F.SilkS")
		)
		(fp_rect
			(start -1.25 -0.65)
			(end 1.25 0.65)
			(stroke
				(width 0.05)
				(type solid)
			)
			(fill no)
			(layer "F.CrtYd")
		)
		(fp_rect
			(start -0.8 -0.4)
			(end 0.8 0.4)
			(stroke
				(width 0.15)
				(type solid)
			)
			(fill no)
			(layer "F.Fab")
		)
		(fp_text user "${REFERENCE}"
			(at -1.682 3.895 180)
			(layer "F.Fab")
			(effects
				(font
					(size 0.7 0.7)
					(thickness 0.15)
				)
				(justify left bottom)
			)
		)
		(fp_text user "Author: Antmicro"
			(at -1.682 4.894 180)
			(layer "F.Fab")
			(effects
				(font
					(size 0.7 0.7)
					(thickness 0.15)
				)
				(justify left bottom)
			)
		)
		(fp_text user "License: Apache-2.0"
			(at -1.682 5.895 180)
			(layer "F.Fab")
			(effects
				(font
					(size 0.7 0.7)
					(thickness 0.15)
				)
				(justify left bottom)
			)
		)
		(pad "1" smd roundrect
			(at -0.7 0 180)
			(size 0.8 1)
			(layers "F.Cu" "F.Mask" "F.Paste")
			(roundrect_rratio 0.2)
			(net 1 "GND")
			(pintype "passive")
		)
		(pad "2" smd roundrect
			(at 0.7 0 180)
			(size 0.8 1)
			(layers "F.Cu" "F.Mask" "F.Paste")
			(roundrect_rratio 0.2)
			(net 273 "/Power Supply/1V0_OUT")
			(pintype "passive")
		)
	)
	(footprint "antmicro-footprints:C_Pol_0603_1608Metric"
		(layer "F.Cu")
		(at 94.3 70.515 90)
		(property "Reference" "C71"
			(at 1.375 0.23 90)
			(layer "F.SilkS")
			(effects
				(font
					(size 0.65 0.65)
					(thickness 0.15)
				)
				(justify left bottom)
			)
		)
		(property "Value" "C_33u_0603"
			(at 0 1.6 90)
			(layer "F.Fab")
			(hide yes)
			(effects
				(font
					(size 0.7 0.7)
					(thickness 0.15)
				)
				(justify left bottom)
			)
		)
		(property "Datasheet" "https://spicat.kyocera-avx.com/product/tan/chartview/F980G336MMA/"
			(at 0 0 90)
			(layer "F.Fab")
			(hide yes)
			(effects
				(font
					(size 1.27 1.27)
					(thickness 0.15)
				)
			)
		)
		(property "Description" "Surface Mount Tantalum Capacitor, 33 µF, 4 V, 0603 [1608 Metric], ± 20%, 4 ohm, M"
			(at 0 0 90)
			(layer "F.Fab")
			(hide yes)
			(effects
				(font
					(size 1.27 1.27)
					(thickness 0.15)
				)
			)
		)
		(property "Author" "Antmicro"
			(at 164.815 -23.785 0)
			(layer "F.Fab")
			(hide yes)
			(effects
				(font
					(size 1 1)
					(thickness 0.15)
				)
			)
		)
		(property "Dielectric" "template_dielectric"
			(at 164.815 -23.785 0)
			(layer "F.Fab")
			(hide yes)
			(effects
				(font
					(size 1 1)
					(thickness 0.15)
				)
			)
		)
		(property "License" "Apache-2.0"
			(at 164.815 -23.785 0)
			(layer "F.Fab")
			(hide yes)
			(effects
				(font
					(size 1 1)
					(thickness 0.15)
				)
			)
		)
		(property "MPN" "F980G336MMA"
			(at 164.815 -23.785 0)
			(layer "F.Fab")
			(hide yes)
			(effects
				(font
					(size 1 1)
					(thickness 0.15)
				)
			)
		)
		(property "Manufacturer" "KYOCERA AVX"
			(at 164.815 -23.785 0)
			(layer "F.Fab")
			(hide yes)
			(effects
				(font
					(size 1 1)
					(thickness 0.15)
				)
			)
		)
		(property "Val" "33u"
			(at 164.815 -23.785 0)
			(layer "F.Fab")
			(hide yes)
			(effects
				(font
					(size 1 1)
					(thickness 0.15)
				)
			)
		)
		(property "Voltage" "4V"
			(at 164.815 -23.785 0)
			(layer "F.Fab")
			(hide yes)
			(effects
				(font
					(size 1 1)
					(thickness 0.15)
				)
			)
		)
		(sheetname "/SDI/")
		(sheetfile "sdi.kicad_sch")
		(attr smd)
		(fp_line
			(start -1.2 -0.775)
			(end -1.2 -0.475)
			(stroke
				(width 0.12)
				(type solid)
			)
			(layer "F.SilkS")
		)
		(fp_line
			(start -1.35 -0.625)
			(end -1.05 -0.625)
			(stroke
				(width 0.12)
				(type solid)
			)
			(layer "F.SilkS")
		)
		(fp_line
			(start -0.15 -0.4)
			(end 0.15 -0.4)
			(stroke
				(width 0.15)
				(type solid)
			)
			(layer "F.SilkS")
		)
		(fp_line
			(start -0.15 0.4)
			(end 0.15 0.4)
			(stroke
				(width 0.15)
				(type solid)
			)
			(layer "F.SilkS")
		)
		(fp_rect
			(start -1.25 -0.65)
			(end 1.25 0.65)
			(stroke
				(width 0.05)
				(type solid)
			)
			(fill no)
			(layer "F.CrtYd")
		)
		(fp_text user "Author: Antmicro"
			(at -1.25 3.77 90)
			(layer "F.Fab")
			(effects
				(font
					(size 0.7 0.7)
					(thickness 0.15)
				)
				(justify left bottom)
			)
		)
		(fp_text user "${REFERENCE}"
			(at -1.25 6.17 90)
			(layer "F.Fab")
			(effects
				(font
					(size 0.7 0.7)
					(thickness 0.15)
				)
				(justify left bottom)
			)
		)
		(fp_text user "License: Apache-2.0"
			(at -1.25 4.97 90)
			(layer "F.Fab")
			(effects
				(font
					(size 0.7 0.7)
					(thickness 0.15)
				)
				(justify left bottom)
			)
		)
		(pad "1" smd roundrect
			(at -0.7 0 90)
			(size 0.8 1)
			(layers "F.Cu" "F.Mask" "F.Paste")
			(roundrect_rratio 0.2)
			(net 244 "Net-(U15C-VCO_{VDD})")
			(pintype "passive")
		)
		(pad "2" smd roundrect
			(at 0.7 0 90)
			(size 0.8 1)
			(layers "F.Cu" "F.Mask" "F.Paste")
			(roundrect_rratio 0.2)
			(net 1 "GND")
			(pintype "passive")
		)
	)
	(footprint "antmicro-footprints:C_0402_1005Metric"
		(layer "F.Cu")
		(at 115.8 88.8 90)
		(descr "Capacitor SMD 0402")
		(tags "capacitor SMD 0402")
		(property "Reference" "C79"
			(at -1.14 1.43 90)
			(layer "F.SilkS")
			(effects
				(font
					(size 0.65 0.65)
					(thickness 0.15)
				)
				(justify left bottom)
			)
		)
		(property "Value" "C_100n_0402"
			(at 0 1.4 90)
			(layer "F.Fab")
			(hide yes)
			(effects
				(font
					(size 0.7 0.7)
					(thickness 0.15)
				)
				(justify left bottom)
			)
		)
		(property "Datasheet" "https://www.murata.com/products/productdetail?partno=GRM155R61H104KE14%23"
			(at 0 0 90)
			(layer "F.Fab")
			(hide yes)
			(effects
				(font
					(size 1.27 1.27)
					(thickness 0.15)
				)
			)
		)
		(property "Description" "SMD Multilayer Ceramic Capacitor, 0.1 µF, 50 V, 0402 [1005 Metric], ± 10%, X5R, GRM Series"
			(at 0 0 90)
			(layer "F.Fab")
			(hide yes)
			(effects
				(font
					(size 1.27 1.27)
					(thickness 0.15)
				)
			)
		)
		(property "Author" "Antmicro"
			(at 204.6 -27 0)
			(layer "F.Fab")
			(hide yes)
			(effects
				(font
					(size 1 1)
					(thickness 0.15)
				)
			)
		)
		(property "Dielectric" "X5R"
			(at 204.6 -27 0)
			(layer "F.Fab")
			(hide yes)
			(effects
				(font
					(size 1 1)
					(thickness 0.15)
				)
			)
		)
		(property "License" "Apache-2.0"
			(at 204.6 -27 0)
			(layer "F.Fab")
			(hide yes)
			(effects
				(font
					(size 1 1)
					(thickness 0.15)
				)
			)
		)
		(property "MPN" "GRM155R61H104KE14D"
			(at 204.6 -27 0)
			(layer "F.Fab")
			(hide yes)
			(effects
				(font
					(size 1 1)
					(thickness 0.15)
				)
			)
		)
		(property "Manufacturer" "Murata"
			(at 204.6 -27 0)
			(layer "F.Fab")
			(hide yes)
			(effects
				(font
					(size 1 1)
					(thickness 0.15)
				)
			)
		)
		(property "Val" "100n"
			(at 204.6 -27 0)
			(layer "F.Fab")
			(hide yes)
			(effects
				(font
					(size 1 1)
					(thickness 0.15)
				)
			)
		)
		(property "Voltage" "50V"
			(at 204.6 -27 0)
			(layer "F.Fab")
			(hide yes)
			(effects
				(font
					(size 1 1)
					(thickness 0.15)
				)
			)
		)
		(sheetname "/FPGA/")
		(sheetfile "fpga.kicad_sch")
		(attr smd)
		(fp_rect
			(start -0.925 -0.47)
			(end 0.925 0.47)
			(stroke
				(width 0.05)
				(type default)
			)
			(fill no)
			(layer "F.CrtYd")
		)
		(fp_line
			(start 0.504 -0.25)
			(end 0.504 0.248)
			(stroke
				(width 0.15)
				(type solid)
			)
			(layer "F.Fab")
		)
		(fp_line
			(start -0.494 -0.25)
			(end 0.504 -0.25)
			(stroke
				(width 0.15)
				(type solid)
			)
			(layer "F.Fab")
		)
		(fp_line
			(start 0.504 0.248)
			(end -0.494 0.248)
			(stroke
				(width 0.15)
				(type solid)
			)
			(layer "F.Fab")
		)
		(fp_line
			(start -0.494 0.248)
			(end -0.494 -0.25)
			(stroke
				(width 0.15)
				(type solid)
			)
			(layer "F.Fab")
		)
		(fp_text user "${REFERENCE}"
			(at -0.939 4.599 90)
			(layer "F.Fab")
			(effects
				(font
					(size 0.7 0.7)
					(thickness 0.15)
				)
				(justify left bottom)
			)
		)
		(fp_text user "License: Apache-2.0"
			(at -0.939 5.799 90)
			(layer "F.Fab")
			(effects
				(font
					(size 0.7 0.7)
					(thickness 0.15)
				)
				(justify left bottom)
			)
		)
		(fp_text user "Author: Antmicro"
			(at -0.939 3.399 90)
			(layer "F.Fab")
			(effects
				(font
					(size 0.7 0.7)
					(thickness 0.15)
				)
				(justify left bottom)
			)
		)
		(pad "1" smd roundrect
			(at -0.48 0 90)
			(size 0.59 0.64)
			(layers "F.Cu" "F.Mask" "F.Paste")
			(roundrect_rratio 0.25)
			(net 1 "GND")
			(pintype "passive")
		)
		(pad "2" smd roundrect
			(at 0.48 0 90)
			(size 0.59 0.64)
			(layers "F.Cu" "F.Mask" "F.Paste")
			(roundrect_rratio 0.25)
			(net 2 "+3V3")
			(pintype "passive")
		)
	)
	(footprint "antmicro-footprints:R_0402_1005Metric"
		(layer "F.Cu")
		(at 110.79 101.4)
		(descr "Resistor SMD 0402")
		(tags "resistor SMD 0402")
		(property "Reference" "R80"
			(at 0.94 0.44 0)
			(layer "F.SilkS")
			(effects
				(font
					(size 0.65 0.65)
					(thickness 0.15)
				)
				(justify left bottom)
			)
		)
		(property "Value" "R_0R_0402"
			(at 0 1.4 0)
			(layer "F.Fab")
			(hide yes)
			(effects
				(font
					(size 0.7 0.7)
					(thickness 0.15)
				)
				(justify left bottom)
			)
		)
		(property "Datasheet" "https://industrial.panasonic.com/cdbs/www-data/pdf/RDA0000/AOA0000C301.pdf"
			(at 0 0 0)
			(layer "F.Fab")
			(hide yes)
			(effects
				(font
					(size 1.27 1.27)
					(thickness 0.15)
				)
			)
		)
		(property "Description" "SMD Chip Resistor, Jumper, 0 ohm, 100 mW, 0402 [1005 Metric], Thick Film, General Purpose"
			(at 0 0 0)
			(layer "F.Fab")
			(hide yes)
			(effects
				(font
					(size 1.27 1.27)
					(thickness 0.15)
				)
			)
		)
		(property "Author" "Antmicro"
			(at 0 0 0)
			(layer "F.Fab")
			(hide yes)
			(effects
				(font
					(size 1 1)
					(thickness 0.15)
				)
			)
		)
		(property "Current" "1A"
			(at 0 0 0)
			(layer "F.Fab")
			(hide yes)
			(effects
				(font
					(size 1 1)
					(thickness 0.15)
				)
			)
		)
		(property "License" "Apache-2.0"
			(at 0 0 0)
			(layer "F.Fab")
			(hide yes)
			(effects
				(font
					(size 1 1)
					(thickness 0.15)
				)
			)
		)
		(property "MPN" "ERJ2GE0R00X"
			(at 0 0 0)
			(layer "F.Fab")
			(hide yes)
			(effects
				(font
					(size 1 1)
					(thickness 0.15)
				)
			)
		)
		(property "Manufacturer" "Panasonic"
			(at 0 0 0)
			(layer "F.Fab")
			(hide yes)
			(effects
				(font
					(size 1 1)
					(thickness 0.15)
				)
			)
		)
		(property "Tolerance" "~"
			(at 0 0 0)
			(layer "F.Fab")
			(hide yes)
			(effects
				(font
					(size 1 1)
					(thickness 0.15)
				)
			)
		)
		(property "Val" "0R"
			(at 0 0 0)
			(layer "F.Fab")
			(hide yes)
			(effects
				(font
					(size 1 1)
					(thickness 0.15)
				)
			)
		)
		(sheetname "/FPGA/")
		(sheetfile "fpga.kicad_sch")
		(attr smd)
		(fp_rect
			(start -0.925 -0.47)
			(end 0.925 0.47)
			(stroke
				(width 0.05)
				(type default)
			)
			(fill no)
			(layer "F.CrtYd")
		)
		(fp_rect
			(start -0.5 -0.25)
			(end 0.5 0.25)
			(stroke
				(width 0.15)
				(type solid)
			)
			(fill no)
			(layer "F.Fab")
		)
		(fp_text user "Author: Antmicro"
			(at -0.95 4.169 0)
			(layer "F.Fab")
			(effects
				(font
					(size 0.7 0.7)
					(thickness 0.15)
				)
				(justify left bottom)
			)
		)
		(fp_text user "License: Apache-2.0"
			(at -0.95 5.169 0)
			(layer "F.Fab")
			(effects
				(font
					(size 0.7 0.7)
					(thickness 0.15)
				)
				(justify left bottom)
			)
		)
		(fp_text user "${REFERENCE}"
			(at -0.95 3.168 0)
			(layer "F.Fab")
			(effects
				(font
					(size 0.7 0.7)
					(thickness 0.15)
				)
				(justify left bottom)
			)
		)
		(pad "1" smd roundrect
			(at -0.48 0)
			(size 0.59 0.64)
			(layers "F.Cu" "F.Mask" "F.Paste")
			(roundrect_rratio 0.25)
			(net 316 "Net-(U17-A1)")
			(pintype "passive")
		)
		(pad "2" smd roundrect
			(at 0.48 0)
			(size 0.59 0.64)
			(layers "F.Cu" "F.Mask" "F.Paste")
			(roundrect_rratio 0.25)
			(net 1 "GND")
			(pintype "passive")
		)
	)
	(footprint "antmicro-footprints:TP_SMD_0.75mm"
		(layer "F.Cu")
		(at 139.4 55.93)
		(property "Reference" "TP1"
			(at -3.595 0.44 0)
			(layer "F.SilkS")
			(effects
				(font
					(size 0.65 0.65)
					(thickness 0.15)
				)
				(justify left bottom)
			)
		)
		(property "Value" "TP_0.75mm_SMD"
			(at 0 1.2 0)
			(layer "F.Fab")
			(hide yes)
			(effects
				(font
					(size 0.7 0.7)
					(thickness 0.15)
				)
				(justify left bottom)
			)
		)
		(property "Description" "SMT test point"
			(at 0 0 0)
			(layer "F.Fab")
			(hide yes)
			(effects
				(font
					(size 1.27 1.27)
					(thickness 0.15)
				)
			)
		)
		(property "Author" "Antmicro"
			(at 0 0 0)
			(layer "F.Fab")
			(hide yes)
			(effects
				(font
					(size 1 1)
					(thickness 0.15)
				)
			)
		)
		(property "License" "Apache-2.0"
			(at 0 0 0)
			(layer "F.Fab")
			(hide yes)
			(effects
				(font
					(size 1 1)
					(thickness 0.15)
				)
			)
		)
		(property "MPN" ""
			(at 0 0 0)
			(layer "F.Fab")
			(hide yes)
			(effects
				(font
					(size 1 1)
					(thickness 0.15)
				)
			)
		)
		(property "Manufacturer" ""
			(at 0 0 0)
			(layer "F.Fab")
			(hide yes)
			(effects
				(font
					(size 1 1)
					(thickness 0.15)
				)
			)
		)
		(sheetname "/Power Supply/")
		(sheetfile "supply.kicad_sch")
		(attr exclude_from_pos_files)
		(fp_circle
			(center 0 0)
			(end 0.475 0)
			(stroke
				(width 0.05)
				(type default)
			)
			(fill no)
			(layer "F.CrtYd")
		)
		(fp_text user "License: Apache-2.0"
			(at -0.4 5.101 0)
			(layer "F.Fab")
			(effects
				(font
					(size 0.7 0.7)
					(thickness 0.15)
				)
				(justify left bottom)
			)
		)
		(fp_text user "${REFERENCE}"
			(at -0.4 2.7 0)
			(layer "F.Fab")
			(effects
				(font
					(size 0.7 0.7)
					(thickness 0.15)
				)
				(justify left bottom)
			)
		)
		(fp_text user "Author: Antmicro"
			(at -0.4 3.901 0)
			(layer "F.Fab")
			(effects
				(font
					(size 0.7 0.7)
					(thickness 0.15)
				)
				(justify left bottom)
			)
		)
		(pad "1" smd circle
			(at 0 0)
			(size 0.75 0.75)
			(layers "F.Cu" "F.Mask")
			(net 1 "GND")
			(pinfunction "1")
			(pintype "passive")
		)
	)
	(footprint "antmicro-footprints:C_0603_1608Metric"
		(layer "F.Cu")
		(at 167.03 88.75 -90)
		(descr "Capacitor SMD 0603")
		(tags "capacitor 0603")
		(property "Reference" "C111"
			(at -1.21 -1.5 90)
			(layer "F.SilkS")
			(effects
				(font
					(size 0.65 0.65)
					(thickness 0.15)
				)
				(justify right bottom)
			)
		)
		(property "Value" "C_1u_0603"
			(at 0 1.6 90)
			(layer "F.Fab")
			(hide yes)
			(effects
				(font
					(size 0.7 0.7)
					(thickness 0.15)
				)
				(justify right bottom)
			)
		)
		(property "Datasheet" "https://spicat.kyocera-avx.com/product/mlcc/chartview/0603YD105KAT2A/"
			(at 0 0 270)
			(layer "F.Fab")
			(hide yes)
			(effects
				(font
					(size 1.27 1.27)
					(thickness 0.15)
				)
			)
		)
		(property "Description" "SMD Multilayer Ceramic Capacitor, 1 µF, 16 V, 0603 [1608 Metric], ± 10%, X5R, AVX 0603 MLCC"
			(at 0 0 270)
			(layer "F.Fab")
			(hide yes)
			(effects
				(font
					(size 1.27 1.27)
					(thickness 0.15)
				)
			)
		)
		(property "Author" "Antmicro"
			(at 78.28 255.78 0)
			(layer "F.Fab")
			(hide yes)
			(effects
				(font
					(size 1 1)
					(thickness 0.15)
				)
			)
		)
		(property "Dielectric" ""
			(at 78.28 255.78 0)
			(layer "F.Fab")
			(hide yes)
			(effects
				(font
					(size 1 1)
					(thickness 0.15)
				)
			)
		)
		(property "License" "Apache-2.0"
			(at 78.28 255.78 0)
			(layer "F.Fab")
			(hide yes)
			(effects
				(font
					(size 1 1)
					(thickness 0.15)
				)
			)
		)
		(property "MPN" "0603YD105KAT2A"
			(at 78.28 255.78 0)
			(layer "F.Fab")
			(hide yes)
			(effects
				(font
					(size 1 1)
					(thickness 0.15)
				)
			)
		)
		(property "Manufacturer" "KYOCERA AVX"
			(at 78.28 255.78 0)
			(layer "F.Fab")
			(hide yes)
			(effects
				(font
					(size 1 1)
					(thickness 0.15)
				)
			)
		)
		(property "Val" "1u"
			(at 78.28 255.78 0)
			(layer "F.Fab")
			(hide yes)
			(effects
				(font
					(size 1 1)
					(thickness 0.15)
				)
			)
		)
		(property "Voltage" ""
			(at 78.28 255.78 0)
			(layer "F.Fab")
			(hide yes)
			(effects
				(font
					(size 1 1)
					(thickness 0.15)
				)
			)
		)
		(sheetname "/Peripherals/")
		(sheetfile "peripherals.kicad_sch")
		(attr smd)
		(fp_line
			(start -0.15 0.4)
			(end 0.15 0.4)
			(stroke
				(width 0.15)
				(type solid)
			)
			(layer "F.SilkS")
		)
		(fp_line
			(start -0.15 -0.4)
			(end 0.15 -0.4)
			(stroke
				(width 0.15)
				(type solid)
			)
			(layer "F.SilkS")
		)
		(fp_rect
			(start -1.25 -0.65)
			(end 1.25 0.65)
			(stroke
				(width 0.05)
				(type solid)
			)
			(fill no)
			(layer "F.CrtYd")
		)
		(fp_rect
			(start -0.8 -0.4)
			(end 0.8 0.4)
			(stroke
				(width 0.15)
				(type solid)
			)
			(fill no)
			(layer "F.Fab")
		)
		(fp_text user "Author: Antmicro"
			(at -1.682 4.894 270)
			(layer "F.Fab")
			(effects
				(font
					(size 0.7 0.7)
					(thickness 0.15)
				)
				(justify left bottom)
			)
		)
		(fp_text user "${REFERENCE}"
			(at -1.682 3.895 270)
			(layer "F.Fab")
			(effects
				(font
					(size 0.7 0.7)
					(thickness 0.15)
				)
				(justify left bottom)
			)
		)
		(fp_text user "License: Apache-2.0"
			(at -1.682 5.895 270)
			(layer "F.Fab")
			(effects
				(font
					(size 0.7 0.7)
					(thickness 0.15)
				)
				(justify left bottom)
			)
		)
		(pad "1" smd roundrect
			(at -0.7 0 270)
			(size 0.8 1)
			(layers "F.Cu" "F.Mask" "F.Paste")
			(roundrect_rratio 0.2)
			(net 1 "GND")
			(pintype "passive")
		)
		(pad "2" smd roundrect
			(at 0.7 0 270)
			(size 0.8 1)
			(layers "F.Cu" "F.Mask" "F.Paste")
			(roundrect_rratio 0.2)
			(net 17 "/Peripherals/FFC1_3V3")
			(pintype "passive")
		)
	)
	(footprint "antmicro-footprints:Conn_FFC_WE_68715014x22"
		(layer "F.Cu")
		(at 171.83 100.14 90)
		(property "Reference" "J4"
			(at -2.3 -3.4 90)
			(layer "F.SilkS")
			(effects
				(font
					(size 0.65 0.65)
					(thickness 0.15)
				)
				(justify left bottom)
			)
		)
		(property "Value" "Conn_FFC_WE_68715014522_ONE-SIDE"
			(at 0 4.5 90)
			(layer "F.Fab")
			(hide yes)
			(effects
				(font
					(size 0.7 0.7)
					(thickness 0.15)
				)
				(justify left bottom)
			)
		)
		(property "Datasheet" "https://www.we-online.com/components/products/datasheet/68715014522.pdf"
			(at 0 0 90)
			(layer "F.Fab")
			(hide yes)
			(effects
				(font
					(size 1.27 1.27)
					(thickness 0.15)
				)
			)
		)
		(property "Description" "FFC connector"
			(at 0 0 90)
			(layer "F.Fab")
			(hide yes)
			(effects
				(font
					(size 1.27 1.27)
					(thickness 0.15)
				)
			)
		)
		(property "Author" "Antmicro"
			(at 271.97 -71.69 0)
			(layer "F.Fab")
			(hide yes)
			(effects
				(font
					(size 1 1)
					(thickness 0.15)
				)
			)
		)
		(property "License" "Apache-2.0"
			(at 271.97 -71.69 0)
			(layer "F.Fab")
			(hide yes)
			(effects
				(font
					(size 1 1)
					(thickness 0.15)
				)
			)
		)
		(property "MPN" "68715014522"
			(at 271.97 -71.69 0)
			(layer "F.Fab")
			(hide yes)
			(effects
				(font
					(size 1 1)
					(thickness 0.15)
				)
			)
		)
		(property "Manufacturer" "Würth Elektronik"
			(at 271.97 -71.69 0)
			(layer "F.Fab")
			(hide yes)
			(effects
				(font
					(size 1 1)
					(thickness 0.15)
				)
			)
		)
		(sheetname "/Peripherals/")
		(sheetfile "peripherals.kicad_sch")
		(attr smd)
		(fp_line
			(start -12.5 -2.976)
			(end 12.499 -2.976)
			(stroke
				(width 0.15)
				(type solid)
			)
			(layer "F.SilkS")
		)
		(fp_line
			(start 15.85 -2.15)
			(end 12.499 -2.15)
			(stroke
				(width 0.15)
				(type solid)
			)
			(layer "F.SilkS")
		)
		(fp_line
			(start 12.499 -2.15)
			(end 12.499 -2.976)
			(stroke
				(width 0.15)
				(type solid)
			)
			(layer "F.SilkS")
		)
		(fp_line
			(start -12.5 -2.15)
			(end -12.5 -2.976)
			(stroke
				(width 0.15)
				(type solid)
			)
			(layer "F.SilkS")
		)
		(fp_line
			(start -15.85 -2.15)
			(end -12.5 -2.15)
			(stroke
				(width 0.15)
				(type solid)
			)
			(layer "F.SilkS")
		)
		(fp_line
			(start 15.85 2.7)
			(end 15.85 -2.15)
			(stroke
				(width 0.15)
				(type solid)
			)
			(layer "F.SilkS")
		)
		(fp_line
			(start 15.85 2.7)
			(end -15.85 2.7)
			(stroke
				(width 0.15)
				(type solid)
			)
			(layer "F.SilkS")
		)
		(fp_line
			(start -15.85 2.7)
			(end -15.85 -2.15)
			(stroke
				(width 0.15)
				(type solid)
			)
			(layer "F.SilkS")
		)
		(fp_circle
			(center -12.9 -2.9)
			(end -12.85 -2.85)
			(stroke
				(width 0.15)
				(type solid)
			)
			(fill yes)
			(layer "F.SilkS")
		)
		(fp_rect
			(start -16.2 -3.25)
			(end 16.2 3.55)
			(stroke
				(width 0.05)
				(type solid)
			)
			(fill no)
			(layer "F.CrtYd")
		)
		(fp_text user "${REFERENCE}"
			(at -16.2 5.9 90)
			(layer "F.Fab")
			(effects
				(font
					(size 0.7 0.7)
					(thickness 0.15)
				)
				(justify left bottom)
			)
		)
		(fp_text user "Author: Antmicro"
			(at -16.2 6.9 90)
			(layer "F.Fab")
			(effects
				(font
					(size 0.7 0.7)
					(thickness 0.15)
				)
				(justify left bottom)
			)
		)
		(fp_text user "License: Apache-2.0"
			(at -16.2 7.9 90)
			(layer "F.Fab")
			(effects
				(font
					(size 0.7 0.7)
					(thickness 0.15)
				)
				(justify left bottom)
			)
		)
		(pad "1" smd roundrect
			(at -12.25 -2.15 90)
			(size 0.3 1.2)
			(layers "F.Cu" "F.Mask" "F.Paste")
			(roundrect_rratio 0.25)
			(net 68 "/Peripherals/MIPI0_D3_N")
			(pintype "passive")
		)
		(pad "2" smd roundrect
			(at -11.75 -2.15 90)
			(size 0.3 1.2)
			(layers "F.Cu" "F.Mask" "F.Paste")
			(roundrect_rratio 0.25)
			(net 69 "/Peripherals/MIPI0_D3_P")
			(pintype "passive")
		)
		(pad "3" smd roundrect
			(at -11.25 -2.15 90)
			(size 0.3 1.2)
			(layers "F.Cu" "F.Mask" "F.Paste")
			(roundrect_rratio 0.25)
			(net 70 "/Peripherals/MIPI0_D2_N")
			(pintype "passive")
		)
		(pad "4" smd roundrect
			(at -10.75 -2.15 90)
			(size 0.3 1.2)
			(layers "F.Cu" "F.Mask" "F.Paste")
			(roundrect_rratio 0.25)
			(net 71 "/Peripherals/MIPI0_D2_P")
			(pintype "passive")
		)
		(pad "5" smd roundrect
			(at -10.25 -2.15 90)
			(size 0.3 1.2)
			(layers "F.Cu" "F.Mask" "F.Paste")
			(roundrect_rratio 0.25)
			(net 72 "/Peripherals/MIPI0_D1_N")
			(pintype "passive")
		)
		(pad "6" smd roundrect
			(at -9.75 -2.15 90)
			(size 0.3 1.2)
			(layers "F.Cu" "F.Mask" "F.Paste")
			(roundrect_rratio 0.25)
			(net 73 "/Peripherals/MIPI0_D1_P")
			(pintype "passive")
		)
		(pad "7" smd roundrect
			(at -9.25 -2.15 90)
			(size 0.3 1.2)
			(layers "F.Cu" "F.Mask" "F.Paste")
			(roundrect_rratio 0.25)
			(net 74 "/Peripherals/MIPI0_D0_N")
			(pintype "passive")
		)
		(pad "8" smd roundrect
			(at -8.75 -2.15 90)
			(size 0.3 1.2)
			(layers "F.Cu" "F.Mask" "F.Paste")
			(roundrect_rratio 0.25)
			(net 75 "/Peripherals/MIPI0_D0_P")
			(pintype "passive")
		)
		(pad "9" smd roundrect
			(at -8.25 -2.15 90)
			(size 0.3 1.2)
			(layers "F.Cu" "F.Mask" "F.Paste")
			(roundrect_rratio 0.25)
			(net 1 "GND")
			(pintype "passive")
		)
		(pad "10" smd roundrect
			(at -7.75 -2.15 90)
			(size 0.3 1.2)
			(layers "F.Cu" "F.Mask" "F.Paste")
			(roundrect_rratio 0.25)
			(net 76 "/Peripherals/MIPI0_CLK_N")
			(pintype "passive")
		)
		(pad "11" smd roundrect
			(at -7.25 -2.15 90)
			(size 0.3 1.2)
			(layers "F.Cu" "F.Mask" "F.Paste")
			(roundrect_rratio 0.25)
			(net 77 "/Peripherals/MIPI0_CLK_P")
			(pintype "passive")
		)
		(pad "12" smd roundrect
			(at -6.75 -2.15 90)
			(size 0.3 1.2)
			(layers "F.Cu" "F.Mask" "F.Paste")
			(roundrect_rratio 0.25)
			(net 1 "GND")
			(pintype "passive")
		)
		(pad "13" smd roundrect
			(at -6.25 -2.15 90)
			(size 0.3 1.2)
			(layers "F.Cu" "F.Mask" "F.Paste")
			(roundrect_rratio 0.25)
			(net 51 "unconnected-(J4-Pad13)")
			(pintype "passive+no_connect")
		)
		(pad "14" smd roundrect
			(at -5.75 -2.15 90)
			(size 0.3 1.2)
			(layers "F.Cu" "F.Mask" "F.Paste")
			(roundrect_rratio 0.25)
			(net 52 "unconnected-(J4-Pad14)")
			(pintype "passive+no_connect")
		)
		(pad "15" smd roundrect
			(at -5.25 -2.15 90)
			(size 0.3 1.2)
			(layers "F.Cu" "F.Mask" "F.Paste")
			(roundrect_rratio 0.25)
			(net 1 "GND")
			(pintype "passive")
		)
		(pad "16" smd roundrect
			(at -4.75 -2.15 90)
			(size 0.3 1.2)
			(layers "F.Cu" "F.Mask" "F.Paste")
			(roundrect_rratio 0.25)
			(net 53 "unconnected-(J4-Pad16)")
			(pintype "passive+no_connect")
		)
		(pad "17" smd roundrect
			(at -4.25 -2.15 90)
			(size 0.3 1.2)
			(layers "F.Cu" "F.Mask" "F.Paste")
			(roundrect_rratio 0.25)
			(net 54 "unconnected-(J4-Pad17)")
			(pintype "passive+no_connect")
		)
		(pad "18" smd roundrect
			(at -3.75 -2.15 90)
			(size 0.3 1.2)
			(layers "F.Cu" "F.Mask" "F.Paste")
			(roundrect_rratio 0.25)
			(net 1 "GND")
			(pintype "passive")
		)
		(pad "19" smd roundrect
			(at -3.25 -2.15 90)
			(size 0.3 1.2)
			(layers "F.Cu" "F.Mask" "F.Paste")
			(roundrect_rratio 0.25)
			(net 78 "/Peripherals/MIPI2_D3_N")
			(pintype "passive")
		)
		(pad "20" smd roundrect
			(at -2.75 -2.15 90)
			(size 0.3 1.2)
			(layers "F.Cu" "F.Mask" "F.Paste")
			(roundrect_rratio 0.25)
			(net 79 "/Peripherals/MIPI2_D3_P")
			(pintype "passive")
		)
		(pad "21" smd roundrect
			(at -2.25 -2.15 90)
			(size 0.3 1.2)
			(layers "F.Cu" "F.Mask" "F.Paste")
			(roundrect_rratio 0.25)
			(net 80 "/Peripherals/MIPI2_D2_N")
			(pintype "passive")
		)
		(pad "22" smd roundrect
			(at -1.75 -2.15 90)
			(size 0.3 1.2)
			(layers "F.Cu" "F.Mask" "F.Paste")
			(roundrect_rratio 0.25)
			(net 81 "/Peripherals/MIPI2_D2_P")
			(pintype "passive")
		)
		(pad "23" smd roundrect
			(at -1.25 -2.15 90)
			(size 0.3 1.2)
			(layers "F.Cu" "F.Mask" "F.Paste")
			(roundrect_rratio 0.25)
			(net 82 "/Peripherals/MIPI2_D1_N")
			(pintype "passive")
		)
		(pad "24" smd roundrect
			(at -0.75 -2.15 90)
			(size 0.3 1.2)
			(layers "F.Cu" "F.Mask" "F.Paste")
			(roundrect_rratio 0.25)
			(net 83 "/Peripherals/MIPI2_D1_P")
			(pintype "passive")
		)
		(pad "25" smd roundrect
			(at -0.25 -2.15 90)
			(size 0.3 1.2)
			(layers "F.Cu" "F.Mask" "F.Paste")
			(roundrect_rratio 0.25)
			(net 84 "/Peripherals/MIPI2_D0_N")
			(pintype "passive")
		)
		(pad "26" smd roundrect
			(at 0.248 -2.15 90)
			(size 0.3 1.2)
			(layers "F.Cu" "F.Mask" "F.Paste")
			(roundrect_rratio 0.25)
			(net 85 "/Peripherals/MIPI2_D0_P")
			(pintype "passive")
		)
		(pad "27" smd roundrect
			(at 0.748 -2.15 90)
			(size 0.3 1.2)
			(layers "F.Cu" "F.Mask" "F.Paste")
			(roundrect_rratio 0.25)
			(net 1 "GND")
			(pintype "passive")
		)
		(pad "28" smd roundrect
			(at 1.249 -2.15 90)
			(size 0.3 1.2)
			(layers "F.Cu" "F.Mask" "F.Paste")
			(roundrect_rratio 0.25)
			(net 86 "/Peripherals/MIPI2_CLK_N")
			(pintype "passive")
		)
		(pad "29" smd roundrect
			(at 1.749 -2.15 90)
			(size 0.3 1.2)
			(layers "F.Cu" "F.Mask" "F.Paste")
			(roundrect_rratio 0.25)
			(net 87 "/Peripherals/MIPI2_CLK_P")
			(pintype "passive")
		)
		(pad "30" smd roundrect
			(at 2.249 -2.15 90)
			(size 0.3 1.2)
			(layers "F.Cu" "F.Mask" "F.Paste")
			(roundrect_rratio 0.25)
			(net 1 "GND")
			(pintype "passive")
		)
		(pad "31" smd roundrect
			(at 2.749 -2.15 90)
			(size 0.3 1.2)
			(layers "F.Cu" "F.Mask" "F.Paste")
			(roundrect_rratio 0.25)
			(net 55 "unconnected-(J4-Pad31)")
			(pintype "passive+no_connect")
		)
		(pad "32" smd roundrect
			(at 3.249 -2.15 90)
			(size 0.3 1.2)
			(layers "F.Cu" "F.Mask" "F.Paste")
			(roundrect_rratio 0.25)
			(net 56 "Net-(J4-Pad32)")
			(pintype "passive")
		)
		(pad "33" smd roundrect
			(at 3.749 -2.15 90)
			(size 0.3 1.2)
			(layers "F.Cu" "F.Mask" "F.Paste")
			(roundrect_rratio 0.25)
			(net 336 "Net-(J4-Pad33)")
			(pintype "passive")
		)
		(pad "34" smd roundrect
			(at 4.248 -2.15 90)
			(size 0.3 1.2)
			(layers "F.Cu" "F.Mask" "F.Paste")
			(roundrect_rratio 0.25)
			(net 337 "Net-(J4-Pad34)")
			(pintype "passive")
		)
		(pad "35" smd roundrect
			(at 4.748 -2.15 90)
			(size 0.3 1.2)
			(layers "F.Cu" "F.Mask" "F.Paste")
			(roundrect_rratio 0.25)
			(net 338 "unconnected-(J4-Pad35)")
			(pintype "passive+no_connect")
		)
		(pad "36" smd roundrect
			(at 5.248 -2.15 90)
			(size 0.3 1.2)
			(layers "F.Cu" "F.Mask" "F.Paste")
			(roundrect_rratio 0.25)
			(net 339 "unconnected-(J4-Pad36)")
			(pintype "passive+no_connect")
		)
		(pad "37" smd roundrect
			(at 5.749 -2.15 90)
			(size 0.3 1.2)
			(layers "F.Cu" "F.Mask" "F.Paste")
			(roundrect_rratio 0.25)
			(net 340 "unconnected-(J4-Pad37)")
			(pintype "passive+no_connect")
		)
		(pad "38" smd roundrect
			(at 6.249 -2.15 90)
			(size 0.3 1.2)
			(layers "F.Cu" "F.Mask" "F.Paste")
			(roundrect_rratio 0.25)
			(net 341 "unconnected-(J4-Pad38)")
			(pintype "passive+no_connect")
		)
		(pad "39" smd roundrect
			(at 6.749 -2.15 90)
			(size 0.3 1.2)
			(layers "F.Cu" "F.Mask" "F.Paste")
			(roundrect_rratio 0.25)
			(net 342 "Net-(J4-Pad39)")
			(pintype "passive")
		)
		(pad "40" smd roundrect
			(at 7.249 -2.15 90)
			(size 0.3 1.2)
			(layers "F.Cu" "F.Mask" "F.Paste")
			(roundrect_rratio 0.25)
			(net 364 "Net-(J4-Pad40)")
			(pintype "passive")
		)
		(pad "41" smd roundrect
			(at 7.749 -2.15 90)
			(size 0.3 1.2)
			(layers "F.Cu" "F.Mask" "F.Paste")
			(roundrect_rratio 0.25)
			(net 365 "Net-(J4-Pad41)")
			(pintype "passive")
		)
		(pad "42" smd roundrect
			(at 8.249 -2.15 90)
			(size 0.3 1.2)
			(layers "F.Cu" "F.Mask" "F.Paste")
			(roundrect_rratio 0.25)
			(net 366 "Net-(J4-Pad42)")
			(pintype "passive")
		)
		(pad "43" smd roundrect
			(at 8.749 -2.15 90)
			(size 0.3 1.2)
			(layers "F.Cu" "F.Mask" "F.Paste")
			(roundrect_rratio 0.25)
			(net 367 "unconnected-(J4-Pad43)")
			(pintype "passive+no_connect")
		)
		(pad "44" smd roundrect
			(at 9.249 -2.15 90)
			(size 0.3 1.2)
			(layers "F.Cu" "F.Mask" "F.Paste")
			(roundrect_rratio 0.25)
			(net 368 "unconnected-(J4-Pad44)")
			(pintype "passive+no_connect")
		)
		(pad "45" smd roundrect
			(at 9.749 -2.15 90)
			(size 0.3 1.2)
			(layers "F.Cu" "F.Mask" "F.Paste")
			(roundrect_rratio 0.25)
			(net 369 "unconnected-(J4-Pad45)")
			(pintype "passive+no_connect")
		)
		(pad "46" smd roundrect
			(at 10.249 -2.15 90)
			(size 0.3 1.2)
			(layers "F.Cu" "F.Mask" "F.Paste")
			(roundrect_rratio 0.25)
			(net 370 "unconnected-(J4-Pad46)")
			(pintype "passive+no_connect")
		)
		(pad "47" smd roundrect
			(at 10.749 -2.15 90)
			(size 0.3 1.2)
			(layers "F.Cu" "F.Mask" "F.Paste")
			(roundrect_rratio 0.25)
			(net 17 "/Peripherals/FFC1_3V3")
			(pintype "passive")
		)
		(pad "48" smd roundrect
			(at 11.249 -2.15 90)
			(size 0.3 1.2)
			(layers "F.Cu" "F.Mask" "F.Paste")
			(roundrect_rratio 0.25)
			(net 17 "/Peripherals/FFC1_3V3")
			(pintype "passive")
		)
		(pad "49" smd roundrect
			(at 11.749 -2.15 90)
			(size 0.3 1.2)
			(layers "F.Cu" "F.Mask" "F.Paste")
			(roundrect_rratio 0.25)
			(net 16 "/Peripherals/FFC1_5V")
			(pintype "passive")
		)
		(pad "50" smd roundrect
			(at 12.249 -2.15 90)
			(size 0.3 1.2)
			(layers "F.Cu" "F.Mask" "F.Paste")
			(roundrect_rratio 0.25)
			(net 16 "/Peripherals/FFC1_5V")
			(pintype "passive")
		)
		(pad "MP1" smd roundrect
			(at -14.198 -0.3 90)
			(size 2.7 3)
			(layers "F.Cu" "F.Mask" "F.Paste")
			(roundrect_rratio 0.05)
			(net 1 "GND")
			(pinfunction "MP")
			(pintype "passive")
		)
		(pad "MP2" smd roundrect
			(at 14.198 -0.3 90)
			(size 2.7 3)
			(layers "F.Cu" "F.Mask" "F.Paste")
			(roundrect_rratio 0.05)
			(net 1 "GND")
			(pinfunction "MP")
			(pintype "passive")
		)
	)
	(footprint "antmicro-footprints:C_0402_1005Metric"
		(layer "F.Cu")
		(at 82.7 107.15 -90)
		(descr "Capacitor SMD 0402")
		(tags "capacitor SMD 0402")
		(property "Reference" "C76"
			(at -9.31 -3.53 90)
			(layer "F.SilkS")
			(effects
				(font
					(size 0.65 0.65)
					(thickness 0.15)
				)
				(justify right bottom)
			)
		)
		(property "Value" "C_10n_0402"
			(at 0 1.4 90)
			(layer "F.Fab")
			(hide yes)
			(effects
				(font
					(size 0.7 0.7)
					(thickness 0.15)
				)
				(justify right bottom)
			)
		)
		(property "Datasheet" "https://www.murata.com/products/productdetail?partno=GRM155R71H103KA88%23"
			(at 0 0 270)
			(layer "F.Fab")
			(hide yes)
			(effects
				(font
					(size 1.27 1.27)
					(thickness 0.15)
				)
			)
		)
		(property "Description" "SMD Multilayer Ceramic Capacitor, 10000 pF, 50 V, 0402 [1005 Metric], ± 10%, X7R, GRM Series"
			(at 0 0 270)
			(layer "F.Fab")
			(hide yes)
			(effects
				(font
					(size 1.27 1.27)
					(thickness 0.15)
				)
			)
		)
		(property "Author" "Antmicro"
			(at -24.45 189.85 0)
			(layer "F.Fab")
			(hide yes)
			(effects
				(font
					(size 1 1)
					(thickness 0.15)
				)
			)
		)
		(property "Dielectric" "X7R"
			(at -24.45 189.85 0)
			(layer "F.Fab")
			(hide yes)
			(effects
				(font
					(size 1 1)
					(thickness 0.15)
				)
			)
		)
		(property "License" "Apache-2.0"
			(at -24.45 189.85 0)
			(layer "F.Fab")
			(hide yes)
			(effects
				(font
					(size 1 1)
					(thickness 0.15)
				)
			)
		)
		(property "MPN" "GRM155R71H103KA88D"
			(at -24.45 189.85 0)
			(layer "F.Fab")
			(hide yes)
			(effects
				(font
					(size 1 1)
					(thickness 0.15)
				)
			)
		)
		(property "Manufacturer" "Murata"
			(at -24.45 189.85 0)
			(layer "F.Fab")
			(hide yes)
			(effects
				(font
					(size 1 1)
					(thickness 0.15)
				)
			)
		)
		(property "Val" "10n"
			(at -24.45 189.85 0)
			(layer "F.Fab")
			(hide yes)
			(effects
				(font
					(size 1 1)
					(thickness 0.15)
				)
			)
		)
		(property "Voltage" "50V"
			(at -24.45 189.85 0)
			(layer "F.Fab")
			(hide yes)
			(effects
				(font
					(size 1 1)
					(thickness 0.15)
				)
			)
		)
		(sheetname "/SDI/")
		(sheetfile "sdi.kicad_sch")
		(attr smd)
		(fp_rect
			(start -0.925 -0.47)
			(end 0.925 0.47)
			(stroke
				(width 0.05)
				(type default)
			)
			(fill no)
			(layer "F.CrtYd")
		)
		(fp_line
			(start -0.494 0.248)
			(end -0.494 -0.25)
			(stroke
				(width 0.15)
				(type solid)
			)
			(layer "F.Fab")
		)
		(fp_line
			(start 0.504 0.248)
			(end -0.494 0.248)
			(stroke
				(width 0.15)
				(type solid)
			)
			(layer "F.Fab")
		)
		(fp_line
			(start -0.494 -0.25)
			(end 0.504 -0.25)
			(stroke
				(width 0.15)
				(type solid)
			)
			(layer "F.Fab")
		)
		(fp_line
			(start 0.504 -0.25)
			(end 0.504 0.248)
			(stroke
				(width 0.15)
				(type solid)
			)
			(layer "F.Fab")
		)
		(fp_text user "License: Apache-2.0"
			(at -0.939 5.799 270)
			(layer "F.Fab")
			(effects
				(font
					(size 0.7 0.7)
					(thickness 0.15)
				)
				(justify left bottom)
			)
		)
		(fp_text user "${REFERENCE}"
			(at -0.939 4.599 270)
			(layer "F.Fab")
			(effects
				(font
					(size 0.7 0.7)
					(thickness 0.15)
				)
				(justify left bottom)
			)
		)
		(fp_text user "Author: Antmicro"
			(at -0.939 3.399 270)
			(layer "F.Fab")
			(effects
				(font
					(size 0.7 0.7)
					(thickness 0.15)
				)
				(justify left bottom)
			)
		)
		(pad "1" smd roundrect
			(at -0.48 0 270)
			(size 0.59 0.64)
			(layers "F.Cu" "F.Mask" "F.Paste")
			(roundrect_rratio 0.25)
			(net 2 "+3V3")
			(pintype "passive")
		)
		(pad "2" smd roundrect
			(at 0.48 0 270)
			(size 0.59 0.64)
			(layers "F.Cu" "F.Mask" "F.Paste")
			(roundrect_rratio 0.25)
			(net 1 "GND")
			(pintype "passive")
		)
	)
	(footprint "antmicro-footprints:R_0402_1005Metric"
		(layer "F.Cu")
		(at 133.75 116.75 90)
		(descr "Resistor SMD 0402")
		(tags "resistor SMD 0402")
		(property "Reference" "R127"
			(at 0.71 0.73 90)
			(layer "F.SilkS")
			(effects
				(font
					(size 0.65 0.65)
					(thickness 0.15)
				)
				(justify left bottom)
			)
		)
		(property "Value" "R_0R_0402"
			(at 0 1.4 90)
			(layer "F.Fab")
			(hide yes)
			(effects
				(font
					(size 0.7 0.7)
					(thickness 0.15)
				)
				(justify left bottom)
			)
		)
		(property "Datasheet" "https://industrial.panasonic.com/cdbs/www-data/pdf/RDA0000/AOA0000C301.pdf"
			(at 0 0 90)
			(layer "F.Fab")
			(hide yes)
			(effects
				(font
					(size 1.27 1.27)
					(thickness 0.15)
				)
			)
		)
		(property "Description" "SMD Chip Resistor, Jumper, 0 ohm, 100 mW, 0402 [1005 Metric], Thick Film, General Purpose"
			(at 0 0 90)
			(layer "F.Fab")
			(hide yes)
			(effects
				(font
					(size 1.27 1.27)
					(thickness 0.15)
				)
			)
		)
		(property "Author" "Antmicro"
			(at 250.5 -17 0)
			(layer "F.Fab")
			(hide yes)
			(effects
				(font
					(size 1 1)
					(thickness 0.15)
				)
			)
		)
		(property "Current" "1A"
			(at 250.5 -17 0)
			(layer "F.Fab")
			(hide yes)
			(effects
				(font
					(size 1 1)
					(thickness 0.15)
				)
			)
		)
		(property "License" "Apache-2.0"
			(at 250.5 -17 0)
			(layer "F.Fab")
			(hide yes)
			(effects
				(font
					(size 1 1)
					(thickness 0.15)
				)
			)
		)
		(property "MPN" "ERJ2GE0R00X"
			(at 250.5 -17 0)
			(layer "F.Fab")
			(hide yes)
			(effects
				(font
					(size 1 1)
					(thickness 0.15)
				)
			)
		)
		(property "Manufacturer" "Panasonic"
			(at 250.5 -17 0)
			(layer "F.Fab")
			(hide yes)
			(effects
				(font
					(size 1 1)
					(thickness 0.15)
				)
			)
		)
		(property "Tolerance" "~"
			(at 250.5 -17 0)
			(layer "F.Fab")
			(hide yes)
			(effects
				(font
					(size 1 1)
					(thickness 0.15)
				)
			)
		)
		(property "Val" "0R"
			(at 250.5 -17 0)
			(layer "F.Fab")
			(hide yes)
			(effects
				(font
					(size 1 1)
					(thickness 0.15)
				)
			)
		)
		(sheetname "/Peripherals/")
		(sheetfile "peripherals.kicad_sch")
		(attr smd)
		(fp_rect
			(start -0.925 -0.47)
			(end 0.925 0.47)
			(stroke
				(width 0.05)
				(type default)
			)
			(fill no)
			(layer "F.CrtYd")
		)
		(fp_rect
			(start -0.5 -0.25)
			(end 0.5 0.25)
			(stroke
				(width 0.15)
				(type solid)
			)
			(fill no)
			(layer "F.Fab")
		)
		(fp_text user "${REFERENCE}"
			(at -0.95 3.168 90)
			(layer "F.Fab")
			(effects
				(font
					(size 0.7 0.7)
					(thickness 0.15)
				)
				(justify left bottom)
			)
		)
		(fp_text user "License: Apache-2.0"
			(at -0.95 5.169 90)
			(layer "F.Fab")
			(effects
				(font
					(size 0.7 0.7)
					(thickness 0.15)
				)
				(justify left bottom)
			)
		)
		(fp_text user "Author: Antmicro"
			(at -0.95 4.169 90)
			(layer "F.Fab")
			(effects
				(font
					(size 0.7 0.7)
					(thickness 0.15)
				)
				(justify left bottom)
			)
		)
		(pad "1" smd roundrect
			(at -0.48 0 90)
			(size 0.59 0.64)
			(layers "F.Cu" "F.Mask" "F.Paste")
			(roundrect_rratio 0.25)
			(net 347 "Net-(J6-Pad42)")
			(pintype "passive")
		)
		(pad "2" smd roundrect
			(at 0.48 0 90)
			(size 0.59 0.64)
			(layers "F.Cu" "F.Mask" "F.Paste")
			(roundrect_rratio 0.25)
			(net 371 "FCC2_SCL2")
			(pintype "passive")
		)
	)
	(footprint "antmicro-footprints:Conn_JST_SH_1x4_SM04B-SRSS-TB-LF-SN"
		(layer "F.Cu")
		(at 172.3 72.15 90)
		(property "Reference" "J8"
			(at 3.36 -2.07 180)
			(layer "F.SilkS")
			(effects
				(font
					(size 0.7 0.7)
					(thickness 0.15)
				)
				(justify left bottom)
			)
		)
		(property "Value" "SM04B-SRSS-TB-LF-SN"
			(at 0 3.9 90)
			(layer "F.Fab")
			(effects
				(font
					(size 0.7 0.7)
					(thickness 0.15)
				)
				(justify left bottom)
			)
		)
		(property "Datasheet" "https://www.jst-mfg.com/product/pdf/eng/eSH.pdf"
			(at 0 0 90)
			(layer "F.Fab")
			(hide yes)
			(effects
				(font
					(size 1.27 1.27)
					(thickness 0.15)
				)
			)
		)
		(property "Description" "Pin Header, Right Angle, Wire-to-Board, 1 mm, 1 Rows, 4 Contacts, Surface Mount Right Angle, SH"
			(at 0 0 90)
			(layer "F.Fab")
			(hide yes)
			(effects
				(font
					(size 1.27 1.27)
					(thickness 0.15)
				)
			)
		)
		(property "Author" "Antmicro"
			(at 244.45 -100.15 0)
			(layer "F.Fab")
			(hide yes)
			(effects
				(font
					(size 1 1)
					(thickness 0.15)
				)
			)
		)
		(property "License" "Apache-2.0"
			(at 244.45 -100.15 0)
			(layer "F.Fab")
			(hide yes)
			(effects
				(font
					(size 1 1)
					(thickness 0.15)
				)
			)
		)
		(property "MPN" "SM04B-SRSS-TB(LF)(SN)"
			(at 244.45 -100.15 0)
			(layer "F.Fab")
			(hide yes)
			(effects
				(font
					(size 1 1)
					(thickness 0.15)
				)
			)
		)
		(property "Manufacturer" "JST Automotive Connectors"
			(at 244.45 -100.15 0)
			(layer "F.Fab")
			(hide yes)
			(effects
				(font
					(size 1 1)
					(thickness 0.15)
				)
			)
		)
		(sheetname "/Peripherals/")
		(sheetfile "peripherals.kicad_sch")
		(attr smd)
		(fp_line
			(start 3.2 -2)
			(end 3.2 0.6)
			(stroke
				(width 0.15)
				(type solid)
			)
			(layer "F.SilkS")
		)
		(fp_line
			(start 2 -2)
			(end 3.2 -2)
			(stroke
				(width 0.15)
				(type solid)
			)
			(layer "F.SilkS")
		)
		(fp_line
			(start -2 -2)
			(end -3.2 -2)
			(stroke
				(width 0.15)
				(type solid)
			)
			(layer "F.SilkS")
		)
		(fp_line
			(start -3.2 -2)
			(end -3.2 0.6)
			(stroke
				(width 0.15)
				(type solid)
			)
			(layer "F.SilkS")
		)
		(fp_line
			(start -2 2.6)
			(end 2 2.6)
			(stroke
				(width 0.15)
				(type solid)
			)
			(layer "F.SilkS")
		)
		(fp_circle
			(center -2.1 -2.5)
			(end -2.05 -2.5)
			(stroke
				(width 0.15)
				(type solid)
			)
			(fill yes)
			(layer "F.SilkS")
		)
		(fp_rect
			(start -3.65 -3.14)
			(end 3.65 2.9)
			(stroke
				(width 0.05)
				(type solid)
			)
			(fill no)
			(layer "F.CrtYd")
		)
		(fp_rect
			(start -3 -2.475)
			(end 3 2.475)
			(stroke
				(width 0.15)
				(type solid)
			)
			(fill no)
			(layer "F.Fab")
		)
		(fp_text user "${REFERENCE}"
			(at -4 8.28 90)
			(layer "F.Fab")
			(effects
				(font
					(size 0.7 0.7)
					(thickness 0.15)
				)
				(justify left bottom)
			)
		)
		(fp_text user "License: Apache-2.0"
			(at -4 5.88 90)
			(layer "F.Fab")
			(effects
				(font
					(size 0.7 0.7)
					(thickness 0.15)
				)
				(justify left bottom)
			)
		)
		(fp_text user "Author: Antmicro"
			(at -4 7.08 90)
			(layer "F.Fab")
			(effects
				(font
					(size 0.7 0.7)
					(thickness 0.15)
				)
				(justify left bottom)
			)
		)
		(pad "1" smd roundrect
			(at -1.5 -2.12 270)
			(size 0.6 1.55)
			(layers "F.Cu" "F.Mask" "F.Paste")
			(roundrect_rratio 0.25)
			(net 1 "GND")
			(pintype "passive")
		)
		(pad "2" smd roundrect
			(at -0.5 -2.12 270)
			(size 0.6 1.55)
			(layers "F.Cu" "F.Mask" "F.Paste")
			(roundrect_rratio 0.25)
			(net 310 "/Peripherals/QWIIC_3V3")
			(pintype "passive")
		)
		(pad "3" smd roundrect
			(at 0.5 -2.12 270)
			(size 0.6 1.55)
			(layers "F.Cu" "F.Mask" "F.Paste")
			(roundrect_rratio 0.25)
			(net 312 "Net-(J8-Pad3)")
			(pintype "passive")
		)
		(pad "4" smd roundrect
			(at 1.5 -2.12 270)
			(size 0.6 1.55)
			(layers "F.Cu" "F.Mask" "F.Paste")
			(roundrect_rratio 0.25)
			(net 313 "Net-(J8-Pad4)")
			(pintype "passive")
		)
		(pad "MP" smd roundrect
			(at -2.8 1.755 90)
			(size 1.2 1.8)
			(layers "F.Cu" "F.Mask" "F.Paste")
			(roundrect_rratio 0.25)
			(net 1 "GND")
			(pintype "passive")
		)
		(pad "MP" smd roundrect
			(at 2.8 1.755 90)
			(size 1.2 1.8)
			(layers "F.Cu" "F.Mask" "F.Paste")
			(roundrect_rratio 0.25)
			(net 1 "GND")
			(pintype "passive")
		)
	)
	(footprint "antmicro-footprints:BGA-100_11x11mm_Layout10x10_P1mm"
		(layer "F.Cu")
		(at 95.609 77.893)
		(property "Reference" "U15"
			(at 0 -6.15 0)
			(layer "F.SilkS")
			(effects
				(font
					(size 0.7 0.7)
					(thickness 0.15)
				)
				(justify left bottom)
			)
		)
		(property "Value" "GS2971A"
			(at 0 7 0)
			(layer "F.Fab")
			(effects
				(font
					(size 0.7 0.7)
					(thickness 0.15)
				)
				(justify left bottom)
			)
		)
		(property "Datasheet" "https://semtech.my.salesforce.com/sfc/p/#E0000000JelG/a/44000000MD3i/kpmMkrmUWgHlbCOwdLzVohMm1SDPoVH85guEGK.KXTc"
			(at 0 0 0)
			(layer "F.Fab")
			(hide yes)
			(effects
				(font
					(size 1.27 1.27)
					(thickness 0.15)
				)
			)
		)
		(property "Description" "SDI receiver"
			(at 0 0 0)
			(layer "F.Fab")
			(hide yes)
			(effects
				(font
					(size 1.27 1.27)
					(thickness 0.15)
				)
			)
		)
		(property "Author" "Antmicro"
			(at 0 0 0)
			(layer "F.Fab")
			(hide yes)
			(effects
				(font
					(size 1 1)
					(thickness 0.15)
				)
			)
		)
		(property "License" "Apache-2.0"
			(at 0 0 0)
			(layer "F.Fab")
			(hide yes)
			(effects
				(font
					(size 1 1)
					(thickness 0.15)
				)
			)
		)
		(property "MPN" "GS2971A"
			(at 0 0 0)
			(layer "F.Fab")
			(hide yes)
			(effects
				(font
					(size 1 1)
					(thickness 0.15)
				)
			)
		)
		(property "Manufacturer" "Semtech"
			(at 0 0 0)
			(layer "F.Fab")
			(hide yes)
			(effects
				(font
					(size 1 1)
					(thickness 0.15)
				)
			)
		)
		(sheetname "/SDI/")
		(sheetfile "sdi.kicad_sch")
		(attr smd)
		(fp_line
			(start -5.65 -5.65)
			(end -5.65 -2.894)
			(stroke
				(width 0.15)
				(type solid)
			)
			(layer "F.SilkS")
		)
		(fp_line
			(start -5.65 5.65)
			(end -5.65 2.9)
			(stroke
				(width 0.15)
				(type solid)
			)
			(layer "F.SilkS")
		)
		(fp_line
			(start -2.919 -5.65)
			(end -5.65 -5.65)
			(stroke
				(width 0.15)
				(type solid)
			)
			(layer "F.SilkS")
		)
		(fp_line
			(start -2.9 5.65)
			(end -5.65 5.65)
			(stroke
				(width 0.15)
				(type solid)
			)
			(layer "F.SilkS")
		)
		(fp_line
			(start 2.901 -5.65)
			(end 5.65 -5.65)
			(stroke
				(width 0.15)
				(type solid)
			)
			(layer "F.SilkS")
		)
		(fp_line
			(start 2.901 5.65)
			(end 5.65 5.65)
			(stroke
				(width 0.15)
				(type solid)
			)
			(layer "F.SilkS")
		)
		(fp_line
			(start 5.65 -5.65)
			(end 5.65 -2.901)
			(stroke
				(width 0.15)
				(type solid)
			)
			(layer "F.SilkS")
		)
		(fp_line
			(start 5.65 5.65)
			(end 5.65 2.9)
			(stroke
				(width 0.15)
				(type solid)
			)
			(layer "F.SilkS")
		)
		(fp_circle
			(center -5.8 -5.8)
			(end -5.75 -5.8)
			(stroke
				(width 0.15)
				(type solid)
			)
			(fill yes)
			(layer "F.SilkS")
		)
		(fp_rect
			(start -6 -6)
			(end 5.999 5.999)
			(stroke
				(width 0.05)
				(type solid)
			)
			(fill no)
			(layer "F.CrtYd")
		)
		(fp_line
			(start -4.5 -5.5)
			(end -5.5 -4.5)
			(stroke
				(width 0.15)
				(type solid)
			)
			(layer "F.Fab")
		)
		(fp_rect
			(start 5.5 5.5)
			(end -5.5 -5.5)
			(stroke
				(width 0.15)
				(type solid)
			)
			(fill no)
			(layer "F.Fab")
		)
		(pad "A1" smd circle
			(at -4.518 -4.494)
			(size 0.5 0.5)
			(layers "F.Cu" "F.Mask" "F.Paste")
			(net 242 "Net-(U15B-VBG)")
			(pinfunction "VBG")
			(pintype "input")
		)
		(pad "A2" smd circle
			(at -3.519 -4.494)
			(size 0.5 0.5)
			(layers "F.Cu" "F.Mask" "F.Paste")
			(net 156 "Net-(U15B-LF)")
			(pinfunction "LF")
			(pintype "input")
		)
		(pad "A3" smd circle
			(at -2.519 -4.494)
			(size 0.5 0.5)
			(layers "F.Cu" "F.Mask" "F.Paste")
			(net 288 "Net-(U15B-LB_CONT)")
			(pinfunction "LB_CONT")
			(pintype "input")
		)
		(pad "A4" smd circle
			(at -1.518 -4.494)
			(size 0.5 0.5)
			(layers "F.Cu" "F.Mask" "F.Paste")
			(net 244 "Net-(U15C-VCO_{VDD})")
			(pinfunction "VCO_{VDD}")
			(pintype "power_in")
		)
		(pad "A5" smd circle
			(at -0.519 -4.494)
			(size 0.5 0.5)
			(layers "F.Cu" "F.Mask" "F.Paste")
			(net 214 "/SDI/SDI_STAT0")
			(pinfunction "STAT0")
			(pintype "output")
		)
		(pad "A6" smd circle
			(at 0.481 -4.494)
			(size 0.5 0.5)
			(layers "F.Cu" "F.Mask" "F.Paste")
			(net 217 "/SDI/SDI_STAT1")
			(pinfunction "STAT1")
			(pintype "output")
		)
		(pad "A7" smd circle
			(at 1.481 -4.494)
			(size 0.5 0.5)
			(layers "F.Cu" "F.Mask" "F.Paste")
			(net 2 "+3V3")
			(pinfunction "IO_{VDD}")
			(pintype "power_in")
		)
		(pad "A8" smd circle
			(at 2.482 -4.494)
			(size 0.5 0.5)
			(layers "F.Cu" "F.Mask" "F.Paste")
			(net 197 "/SDI/SDI_PCLK")
			(pinfunction "PCLK")
			(pintype "output")
		)
		(pad "A9" smd circle
			(at 3.482 -4.494)
			(size 0.5 0.5)
			(layers "F.Cu" "F.Mask" "F.Paste")
			(net 216 "/SDI/SDI_D18")
			(pinfunction "DOUT18")
			(pintype "output")
		)
		(pad "A10" smd circle
			(at 4.482 -4.494)
			(size 0.5 0.5)
			(layers "F.Cu" "F.Mask" "F.Paste")
			(net 215 "/SDI/SDI_D17")
			(pinfunction "DOUT17")
			(pintype "output")
		)
		(pad "B1" smd circle
			(at -4.518 -3.493)
			(size 0.5 0.5)
			(layers "F.Cu" "F.Mask" "F.Paste")
			(net 2 "+3V3")
			(pinfunction "A_{VDD}")
			(pintype "power_in")
		)
		(pad "B2" smd circle
			(at -3.519 -3.493)
			(size 0.5 0.5)
			(layers "F.Cu" "F.Mask" "F.Paste")
			(net 3 "+1V2")
			(pinfunction "PLL_{VDD}")
			(pintype "power_in")
		)
		(pad "B3" smd circle
			(at -2.519 -3.493)
			(size 0.5 0.5)
			(layers "F.Cu" "F.Mask" "F.Paste")
			(net 57 "unconnected-(U15B-RSV-PadB3)")
			(pinfunction "RSV")
			(pintype "no_connect")
		)
		(pad "B4" smd circle
			(at -1.518 -3.493)
			(size 0.5 0.5)
			(layers "F.Cu" "F.Mask" "F.Paste")
			(net 1 "GND")
			(pinfunction "VCO_{GND}")
			(pintype "power_in")
		)
		(pad "B5" smd circle
			(at -0.519 -3.493)
			(size 0.5 0.5)
			(layers "F.Cu" "F.Mask" "F.Paste")
			(net 212 "/SDI/SDI_STAT2")
			(pinfunction "STAT2")
			(pintype "output")
		)
		(pad "B6" smd circle
			(at 0.481 -3.493)
			(size 0.5 0.5)
			(layers "F.Cu" "F.Mask" "F.Paste")
			(net 219 "/SDI/SDI_STAT3")
			(pinfunction "STAT3")
			(pintype "output")
		)
		(pad "B7" smd circle
			(at 1.481 -3.493)
			(size 0.5 0.5)
			(layers "F.Cu" "F.Mask" "F.Paste")
			(net 1 "GND")
			(pinfunction "IO_{GND}")
			(pintype "power_in")
		)
		(pad "B8" smd circle
			(at 2.482 -3.493)
			(size 0.5 0.5)
			(layers "F.Cu" "F.Mask" "F.Paste")
			(net 213 "/SDI/SDI_D19")
			(pinfunction "DOUT19")
			(pintype "output")
		)
		(pad "B9" smd circle
			(at 3.482 -3.493)
			(size 0.5 0.5)
			(layers "F.Cu" "F.Mask" "F.Paste")
			(net 211 "/SDI/SDI_D16")
			(pinfunction "DOUT16")
			(pintype "output")
		)
		(pad "B10" smd circle
			(at 4.482 -3.493)
			(size 0.5 0.5)
			(layers "F.Cu" "F.Mask" "F.Paste")
			(net 210 "/SDI/SDI_D15")
			(pinfunction "DOUT15")
			(pintype "output")
		)
		(pad "C1" smd circle
			(at -4.518 -2.493)
			(size 0.5 0.5)
			(layers "F.Cu" "F.Mask" "F.Paste")
			(net 7 "/SDI/SDI_P")
			(pinfunction "SDI+")
			(pintype "input")
		)
		(pad "C2" smd circle
			(at -3.519 -2.493)
			(size 0.5 0.5)
			(layers "F.Cu" "F.Mask" "F.Paste")
			(net 1 "GND")
			(pinfunction "A_{GND}")
			(pintype "power_in")
		)
		(pad "C3" smd circle
			(at -2.519 -2.493)
			(size 0.5 0.5)
			(layers "F.Cu" "F.Mask" "F.Paste")
			(net 3 "+1V2")
			(pinfunction "PLL_{VDD}")
			(pintype "passive")
		)
		(pad "C4" smd circle
			(at -1.518 -2.493)
			(size 0.5 0.5)
			(layers "F.Cu" "F.Mask" "F.Paste")
			(net 3 "+1V2")
			(pinfunction "PLL_{VDD}")
			(pintype "passive")
		)
		(pad "C5" smd circle
			(at -0.519 -2.493)
			(size 0.5 0.5)
			(layers "F.Cu" "F.Mask" "F.Paste")
			(net 218 "/SDI/SDI_STAT4")
			(pinfunction "STAT4")
			(pintype "output")
		)
		(pad "C6" smd circle
			(at 0.481 -2.493)
			(size 0.5 0.5)
			(layers "F.Cu" "F.Mask" "F.Paste")
			(net 183 "/SDI/SDI_STAT5")
			(pinfunction "STAT5")
			(pintype "output")
		)
		(pad "C7" smd circle
			(at 1.481 -2.493)
			(size 0.5 0.5)
			(layers "F.Cu" "F.Mask" "F.Paste")
			(net 175 "/SDI/RESET_TRST")
			(pinfunction "RESET_TRST")
			(pintype "input")
		)
		(pad "C8" smd circle
			(at 2.482 -2.493)
			(size 0.5 0.5)
			(layers "F.Cu" "F.Mask" "F.Paste")
			(net 204 "/SDI/SDI_D12")
			(pinfunction "DOUT12")
			(pintype "output")
		)
		(pad "C9" smd circle
			(at 3.482 -2.493)
			(size 0.5 0.5)
			(layers "F.Cu" "F.Mask" "F.Paste")
			(net 206 "/SDI/SDI_D14")
			(pinfunction "DOUT14")
			(pintype "output")
		)
		(pad "C10" smd circle
			(at 4.482 -2.493)
			(size 0.5 0.5)
			(layers "F.Cu" "F.Mask" "F.Paste")
			(net 207 "/SDI/SDI_D13")
			(pinfunction "DOUT13")
			(pintype "output")
		)
		(pad "D1" smd circle
			(at -4.518 -1.494)
			(size 0.5 0.5)
			(layers "F.Cu" "F.Mask" "F.Paste")
			(net 8 "/SDI/SDI_N")
			(pinfunction "SDI-")
			(pintype "input")
		)
		(pad "D2" smd circle
			(at -3.519 -1.494)
			(size 0.5 0.5)
			(layers "F.Cu" "F.Mask" "F.Paste")
			(net 1 "GND")
			(pinfunction "A_{GND}")
			(pintype "passive")
		)
		(pad "D3" smd circle
			(at -2.519 -1.494)
			(size 0.5 0.5)
			(layers "F.Cu" "F.Mask" "F.Paste")
			(net 1 "GND")
			(pinfunction "A_{GND}")
			(pintype "passive")
		)
		(pad "D4" smd circle
			(at -1.518 -1.494)
			(size 0.5 0.5)
			(layers "F.Cu" "F.Mask" "F.Paste")
			(net 1 "GND")
			(pinfunction "PLL_{GND}")
			(pintype "power_in")
		)
		(pad "D5" smd circle
			(at -0.519 -1.494)
			(size 0.5 0.5)
			(layers "F.Cu" "F.Mask" "F.Paste")
			(net 1 "GND")
			(pinfunction "CORE_{GND}")
			(pintype "power_in")
		)
		(pad "D6" smd circle
			(at 0.481 -1.494)
			(size 0.5 0.5)
			(layers "F.Cu" "F.Mask" "F.Paste")
			(net 3 "+1V2")
			(pinfunction "CORE_{VDD}")
			(pintype "power_in")
		)
		(pad "D7" smd circle
			(at 1.481 -1.494)
			(size 0.5 0.5)
			(layers "F.Cu" "F.Mask" "F.Paste")
			(net 177 "/SDI/SW_EN")
			(pinfunction "SW_EN")
			(pintype "input")
		)
		(pad "D8" smd circle
			(at 2.482 -1.494)
			(size 0.5 0.5)
			(layers "F.Cu" "F.Mask" "F.Paste")
			(net 208 "/SDI/JTAG{slash}~{HOST}")
			(pinfunction "JTAG/~{HOST}")
			(pintype "input")
		)
		(pad "D9" smd circle
			(at 3.482 -1.494)
			(size 0.5 0.5)
			(layers "F.Cu" "F.Mask" "F.Paste")
			(net 1 "GND")
			(pinfunction "IO_{GND}")
			(pintype "passive")
		)
		(pad "D10" smd circle
			(at 4.482 -1.494)
			(size 0.5 0.5)
			(layers "F.Cu" "F.Mask" "F.Paste")
			(net 2 "+3V3")
			(pinfunction "IO_{VDD}")
			(pintype "passive")
		)
		(pad "E1" smd circle
			(at -4.518 -0.493)
			(size 0.5 0.5)
			(layers "F.Cu" "F.Mask" "F.Paste")
			(net 2 "+3V3")
			(pinfunction "EQ_{VDD}")
			(pintype "power_in")
		)
		(pad "E2" smd circle
			(at -3.519 -0.493)
			(size 0.5 0.5)
			(layers "F.Cu" "F.Mask" "F.Paste")
			(net 1 "GND")
			(pinfunction "EQ_{GND}")
			(pintype "power_in")
		)
		(pad "E3" smd circle
			(at -2.519 -0.493)
			(size 0.5 0.5)
			(layers "F.Cu" "F.Mask" "F.Paste")
			(net 1 "GND")
			(pinfunction "A_{GND}")
			(pintype "passive")
		)
		(pad "E4" smd circle
			(at -1.518 -0.493)
			(size 0.5 0.5)
			(layers "F.Cu" "F.Mask" "F.Paste")
			(net 1 "GND")
			(pinfunction "PLL_{GND}")
			(pintype "passive")
		)
		(pad "E5" smd circle
			(at -0.519 -0.493)
			(size 0.5 0.5)
			(layers "F.Cu" "F.Mask" "F.Paste")
			(net 1 "GND")
			(pinfunction "CORE_{GND}")
			(pintype "passive")
		)
		(pad "E6" smd circle
			(at 0.481 -0.493)
			(size 0.5 0.5)
			(layers "F.Cu" "F.Mask" "F.Paste")
			(net 3 "+1V2")
			(pinfunction "CORE_{VDD}")
			(pintype "passive")
		)
		(pad "E7" smd circle
			(at 1.481 -0.493)
			(size 0.5 0.5)
			(layers "F.Cu" "F.Mask" "F.Paste")
			(net 181 "/SDI/SDOUT_TDO")
			(pinfunction "SDOUT_TDO")
			(pintype "output")
		)
		(pad "E8" smd circle
			(at 2.482 -0.493)
			(size 0.5 0.5)
			(layers "F.Cu" "F.Mask" "F.Paste")
			(net 182 "/SDI/SDIN_TDI")
			(pinfunction "SDIN_TDI")
			(pintype "input")
		)
		(pad "E9" smd circle
			(at 3.482 -0.493)
			(size 0.5 0.5)
			(layers "F.Cu" "F.Mask" "F.Paste")
			(net 203 "/SDI/SDI_D10")
			(pinfunction "DOUT10")
			(pintype "output")
		)
		(pad "E10" smd circle
			(at 4.482 -0.493)
			(size 0.5 0.5)
			(layers "F.Cu" "F.Mask" "F.Paste")
			(net 205 "/SDI/SDI_D11")
			(pinfunction "DOUT11")
			(pintype "output")
		)
		(pad "F1" smd circle
			(at -4.518 0.506)
			(size 0.5 0.5)
			(layers "F.Cu" "F.Mask" "F.Paste")
			(net 292 "/SDI/AGC_P")
			(pinfunction "AGC+")
			(pintype "passive")
		)
		(pad "F2" smd circle
			(at -3.519 0.506)
			(size 0.5 0.5)
			(layers "F.Cu" "F.Mask" "F.Paste")
			(net 59 "unconnected-(U15B-RSV-PadF2)")
			(pinfunction "RSV")
			(pintype "no_connect")
		)
		(pad "F3" smd circle
			(at -2.519 0.506)
			(size 0.5 0.5)
			(layers "F.Cu" "F.Mask" "F.Paste")
			(net 1 "GND")
			(pinfunction "A_{GND}")
			(pintype "passive")
		)
		(pad "F4" smd circle
			(at -1.518 0.506)
			(size 0.5 0.5)
			(layers "F.Cu" "F.Mask" "F.Paste")
			(net 1 "GND")
			(pinfunction "PLL_{GND}")
			(pintype "passive")
		)
		(pad "F5" smd circle
			(at -0.519 0.506)
			(size 0.5 0.5)
			(layers "F.Cu" "F.Mask" "F.Paste")
			(net 1 "GND")
			(pinfunction "CORE_{GND}")
			(pintype "passive")
		)
		(pad "F6" smd circle
			(at 0.481 0.506)
			(size 0.5 0.5)
			(layers "F.Cu" "F.Mask" "F.Paste")
			(net 3 "+1V2")
			(pinfunction "CORE_{VDD}")
			(pintype "passive")
		)
		(pad "F7" smd circle
			(at 1.481 0.506)
			(size 0.5 0.5)
			(layers "F.Cu" "F.Mask" "F.Paste")
			(net 178 "/SDI/~{CS_TMS}")
			(pinfunction "~{CS}_TMS")
			(pintype "input")
		)
		(pad "F8" smd circle
			(at 2.482 0.506)
			(size 0.5 0.5)
			(layers "F.Cu" "F.Mask" "F.Paste")
			(net 179 "/SDI/SCLK_TCK")
			(pinfunction "SCLK_TCK")
			(pintype "input")
		)
		(pad "F9" smd circle
			(at 3.482 0.506)
			(size 0.5 0.5)
			(layers "F.Cu" "F.Mask" "F.Paste")
			(net 195 "/SDI/SDI_D8")
			(pinfunction "DOUT08")
			(pintype "output")
		)
		(pad "F10" smd circle
			(at 4.482 0.506)
			(size 0.5 0.5)
			(layers "F.Cu" "F.Mask" "F.Paste")
			(net 202 "/SDI/SDI_D9")
			(pinfunction "DOUT09")
			(pintype "output")
		)
		(pad "G1" smd circle
			(at -4.518 1.507)
			(size 0.5 0.5)
			(layers "F.Cu" "F.Mask" "F.Paste")
			(net 291 "/SDI/AGC_N")
			(pinfunction "AGC-")
			(pintype "passive")
		)
		(pad "G2" smd circle
			(at -3.519 1.507)
			(size 0.5 0.5)
			(layers "F.Cu" "F.Mask" "F.Paste")
			(net 1 "GND")
			(pinfunction "A_{GND}")
			(pintype "passive")
		)
		(pad "G3" smd circle
			(at -2.519 1.507)
			(size 0.5 0.5)
			(layers "F.Cu" "F.Mask" "F.Paste")
			(net 209 "/SDI/~{RC_BYP}")
			(pinfunction "~{RC_BYP}")
			(pintype "input")
		)
		(pad "G4" smd circle
			(at -1.518 1.507)
			(size 0.5 0.5)
			(layers "F.Cu" "F.Mask" "F.Paste")
			(net 1 "GND")
			(pinfunction "CORE_{GND}")
			(pintype "passive")
		)
		(pad "G5" smd circle
			(at -0.519 1.507)
			(size 0.5 0.5)
			(layers "F.Cu" "F.Mask" "F.Paste")
			(net 1 "GND")
			(pinfunction "CORE_{GND}")
			(pintype "passive")
		)
		(pad "G6" smd circle
			(at 0.481 1.507)
			(size 0.5 0.5)
			(layers "F.Cu" "F.Mask" "F.Paste")
			(net 3 "+1V2")
			(pinfunction "CORE_{VDD}")
			(pintype "passive")
		)
		(pad "G7" smd circle
			(at 1.481 1.507)
			(size 0.5 0.5)
			(layers "F.Cu" "F.Mask" "F.Paste")
			(net 201 "/SDI/~{SMPTE_BYPASS}")
			(pinfunction "~{SMPTE_BYPASS}")
			(pintype "bidirectional")
		)
		(pad "G8" smd circle
			(at 2.482 1.507)
			(size 0.5 0.5)
			(layers "F.Cu" "F.Mask" "F.Paste")
			(net 193 "/SDI/DVB_ASI")
			(pinfunction "DVB_ASI")
			(pintype "bidirectional")
		)
		(pad "G9" smd circle
			(at 3.482 1.507)
			(size 0.5 0.5)
			(layers "F.Cu" "F.Mask" "F.Paste")
			(net 1 "GND")
			(pinfunction "IO_{GND}")
			(pintype "passive")
		)
		(pad "G10" smd circle
			(at 4.482 1.507)
			(size 0.5 0.5)
			(layers "F.Cu" "F.Mask" "F.Paste")
			(net 2 "+3V3")
			(pinfunction "IO_{VDD}")
			(pintype "passive")
		)
		(pad "H1" smd circle
			(at -4.518 2.507)
			(size 0.5 0.5)
			(layers "F.Cu" "F.Mask" "F.Paste")
			(net 2 "+3V3")
			(pinfunction "BUFF_{VDD}")
			(pintype "power_in")
		)
		(pad "H2" smd circle
			(at -3.519 2.507)
			(size 0.5 0.5)
			(layers "F.Cu" "F.Mask" "F.Paste")
			(net 1 "GND")
			(pinfunction "BUFF_{GND}")
			(pintype "power_in")
		)
		(pad "H3" smd circle
			(at -2.519 2.507)
			(size 0.5 0.5)
			(layers "F.Cu" "F.Mask" "F.Paste")
			(net 198 "/SDI/AUDIO_EN{slash}~{DIS}")
			(pinfunction "AUDIO_EN/~{DIS}")
			(pintype "input")
		)
		(pad "H4" smd circle
			(at -1.518 2.507)
			(size 0.5 0.5)
			(layers "F.Cu" "F.Mask" "F.Paste")
			(net 21 "AUDIO_WCLK")
			(pinfunction "WCLK")
			(pintype "output")
		)
		(pad "H5" smd circle
			(at -0.519 2.507)
			(size 0.5 0.5)
			(layers "F.Cu" "F.Mask" "F.Paste")
			(net 180 "/SDI/TIM_861")
			(pinfunction "TIM_861")
			(pintype "input")
		)
		(pad "H6" smd circle
			(at 0.481 2.507)
			(size 0.5 0.5)
			(layers "F.Cu" "F.Mask" "F.Paste")
			(net 377 "Net-(U15B-XTAL_OUT)")
			(pinfunction "XTAL_OUT")
			(pintype "output")
		)
		(pad "H7" smd circle
			(at 1.481 2.507)
			(size 0.5 0.5)
			(layers "F.Cu" "F.Mask" "F.Paste")
			(net 200 "/SDI/20bit{slash}~{10bit}")
			(pinfunction "20BIT/~{10BIT}")
			(pintype "input")
		)
		(pad "H8" smd circle
			(at 2.482 2.507)
			(size 0.5 0.5)
			(layers "F.Cu" "F.Mask" "F.Paste")
			(net 199 "/SDI/IOPROC_EN{slash}~{DIS}")
			(pinfunction "IOPROC_EN/~{DIS}")
			(pintype "input")
		)
		(pad "H9" smd circle
			(at 3.482 2.507)
			(size 0.5 0.5)
			(layers "F.Cu" "F.Mask" "F.Paste")
			(net 196 "/SDI/SDI_D6")
			(pinfunction "DOUT06")
			(pintype "output")
		)
		(pad "H10" smd circle
			(at 4.482 2.507)
			(size 0.5 0.5)
			(layers "F.Cu" "F.Mask" "F.Paste")
			(net 194 "/SDI/SDI_D7")
			(pinfunction "DOUT07")
			(pintype "output")
		)
		(pad "J1" smd circle
			(at -4.518 3.507)
			(size 0.5 0.5)
			(layers "F.Cu" "F.Mask" "F.Paste")
			(net 47 "/SDI/SDO_P")
			(pinfunction "SDO+")
			(pintype "output")
		)
		(pad "J2" smd circle
			(at -3.519 3.507)
			(size 0.5 0.5)
			(layers "F.Cu" "F.Mask" "F.Paste")
			(net 185 "/SDI/SDO_EN{slash}DIS")
			(pinfunction "SDO_EN/DIS")
			(pintype "input")
		)
		(pad "J3" smd circle
			(at -2.519 3.507)
			(size 0.5 0.5)
			(layers "F.Cu" "F.Mask" "F.Paste")
			(net 22 "AUDIO_OUT_CH1_2")
			(pinfunction "AOUT_{1/2}")
			(pintype "output")
		)
		(pad "J4" smd circle
			(at -1.518 3.507)
			(size 0.5 0.5)
			(layers "F.Cu" "F.Mask" "F.Paste")
			(net 20 "AUDIO_ACLK")
			(pinfunction "ACLK")
			(pintype "output")
		)
		(pad "J5" smd circle
			(at -0.519 3.507)
			(size 0.5 0.5)
			(layers "F.Cu" "F.Mask" "F.Paste")
			(net 23 "AUDIO_OUT_CH5_6")
			(pinfunction "AOUT_{5/6}")
			(pintype "output")
		)
		(pad "J6" smd circle
			(at 0.481 3.507)
			(size 0.5 0.5)
			(layers "F.Cu" "F.Mask" "F.Paste")
			(net 46 "/SDI/XTAL2")
			(pinfunction "XTAL2")
			(pintype "input")
		)
		(pad "J7" smd circle
			(at 1.481 3.507)
			(size 0.5 0.5)
			(layers "F.Cu" "F.Mask" "F.Paste")
			(net 1 "GND")
			(pinfunction "IO_{GND}")
			(pintype "passive")
		)
		(pad "J8" smd circle
			(at 2.482 3.507)
			(size 0.5 0.5)
			(layers "F.Cu" "F.Mask" "F.Paste")
			(net 191 "/SDI/SDI_D1")
			(pinfunction "DOUT01")
			(pintype "output")
		)
		(pad "J9" smd circle
			(at 3.482 3.507)
			(size 0.5 0.5)
			(layers "F.Cu" "F.Mask" "F.Paste")
			(net 187 "/SDI/SDI_D4")
			(pinfunction "DOUT04")
			(pintype "output")
		)
		(pad "J10" smd circle
			(at 4.482 3.507)
			(size 0.5 0.5)
			(layers "F.Cu" "F.Mask" "F.Paste")
			(net 188 "/SDI/SDI_D5")
			(pinfunction "DOUT05")
			(pintype "output")
		)
		(pad "K1" smd circle
			(at -4.518 4.506)
			(size 0.5 0.5)
			(layers "F.Cu" "F.Mask" "F.Paste")
			(net 48 "/SDI/SDO_N")
			(pinfunction "SDO-")
			(pintype "output")
		)
		(pad "K2" smd circle
			(at -3.519 4.506)
			(size 0.5 0.5)
			(layers "F.Cu" "F.Mask" "F.Paste")
			(net 176 "/SDI/STANDBY")
			(pinfunction "STANDBY")
			(pintype "input")
		)
		(pad "K3" smd circle
			(at -2.519 4.506)
			(size 0.5 0.5)
			(layers "F.Cu" "F.Mask" "F.Paste")
			(net 24 "AUDIO_OUT_CH3_4")
			(pinfunction "AOUT_{3/4}")
			(pintype "output")
		)
		(pad "K4" smd circle
			(at -1.518 4.506)
			(size 0.5 0.5)
			(layers "F.Cu" "F.Mask" "F.Paste")
			(net 26 "AUDIO_MCLK")
			(pinfunction "AMCLK")
			(pintype "output")
		)
		(pad "K5" smd circle
			(at -0.519 4.506)
			(size 0.5 0.5)
			(layers "F.Cu" "F.Mask" "F.Paste")
			(net 25 "AUDIO_OUT_CH7_8")
			(pinfunction "AOUT_{7/8}")
			(pintype "output")
		)
		(pad "K6" smd circle
			(at 0.481 4.506)
			(size 0.5 0.5)
			(layers "F.Cu" "F.Mask" "F.Paste")
			(net 45 "/SDI/XTAL1")
			(pinfunction "XTAL1")
			(pintype "input")
		)
		(pad "K7" smd circle
			(at 1.481 4.506)
			(size 0.5 0.5)
			(layers "F.Cu" "F.Mask" "F.Paste")
			(net 2 "+3V3")
			(pinfunction "IO_{VDD}")
			(pintype "passive")
		)
		(pad "K8" smd circle
			(at 2.482 4.506)
			(size 0.5 0.5)
			(layers "F.Cu" "F.Mask" "F.Paste")
			(net 192 "/SDI/SDI_D0")
			(pinfunction "DOUT0")
			(pintype "output")
		)
		(pad "K9" smd circle
			(at 3.482 4.506)
			(size 0.5 0.5)
			(layers "F.Cu" "F.Mask" "F.Paste")
			(net 190 "/SDI/SDI_D2")
			(pinfunction "DOUT02")
			(pintype "output")
		)
		(pad "K10" smd circle
			(at 4.482 4.506)
			(size 0.5 0.5)
			(layers "F.Cu" "F.Mask" "F.Paste")
			(net 189 "/SDI/SDI_D3")
			(pinfunction "DOUT03")
			(pintype "output")
		)
	)
	(footprint "antmicro-footprints:TP_SMD_0.75mm"
		(layer "F.Cu")
		(at 99 69.48)
		(property "Reference" "TP24"
			(at -3.22 0.39 0)
			(layer "F.SilkS")
			(effects
				(font
					(size 0.65 0.65)
					(thickness 0.15)
				)
				(justify left bottom)
			)
		)
		(property "Value" "TP_0.75mm_SMD"
			(at 0 1.2 0)
			(layer "F.Fab")
			(hide yes)
			(effects
				(font
					(size 0.7 0.7)
					(thickness 0.15)
				)
				(justify left bottom)
			)
		)
		(property "Description" "SMT test point"
			(at 0 0 0)
			(layer "F.Fab")
			(hide yes)
			(effects
				(font
					(size 1.27 1.27)
					(thickness 0.15)
				)
			)
		)
		(property "Author" "Antmicro"
			(at 0 0 0)
			(layer "F.Fab")
			(hide yes)
			(effects
				(font
					(size 1 1)
					(thickness 0.15)
				)
			)
		)
		(property "License" "Apache-2.0"
			(at 0 0 0)
			(layer "F.Fab")
			(hide yes)
			(effects
				(font
					(size 1 1)
					(thickness 0.15)
				)
			)
		)
		(property "MPN" ""
			(at 0 0 0)
			(layer "F.Fab")
			(hide yes)
			(effects
				(font
					(size 1 1)
					(thickness 0.15)
				)
			)
		)
		(property "Manufacturer" ""
			(at 0 0 0)
			(layer "F.Fab")
			(hide yes)
			(effects
				(font
					(size 1 1)
					(thickness 0.15)
				)
			)
		)
		(sheetname "/SDI/")
		(sheetfile "sdi.kicad_sch")
		(attr exclude_from_pos_files)
		(fp_circle
			(center 0 0)
			(end 0.475 0)
			(stroke
				(width 0.05)
				(type default)
			)
			(fill no)
			(layer "F.CrtYd")
		)
		(fp_text user "License: Apache-2.0"
			(at -0.4 5.101 0)
			(layer "F.Fab")
			(effects
				(font
					(size 0.7 0.7)
					(thickness 0.15)
				)
				(justify left bottom)
			)
		)
		(fp_text user "${REFERENCE}"
			(at -0.4 2.7 0)
			(layer "F.Fab")
			(effects
				(font
					(size 0.7 0.7)
					(thickness 0.15)
				)
				(justify left bottom)
			)
		)
		(fp_text user "Author: Antmicro"
			(at -0.4 3.901 0)
			(layer "F.Fab")
			(effects
				(font
					(size 0.7 0.7)
					(thickness 0.15)
				)
				(justify left bottom)
			)
		)
		(pad "1" smd circle
			(at 0 0)
			(size 0.75 0.75)
			(layers "F.Cu" "F.Mask")
			(net 214 "/SDI/SDI_STAT0")
			(pinfunction "1")
			(pintype "passive")
		)
	)
	(footprint "antmicro-footprints:R_0402_1005Metric"
		(layer "F.Cu")
		(at 130.75 116.75 -90)
		(descr "Resistor SMD 0402")
		(tags "resistor SMD 0402")
		(property "Reference" "R109"
			(at -0.81 -0.28 270)
			(layer "F.SilkS")
			(effects
				(font
					(size 0.65 0.65)
					(thickness 0.15)
				)
				(justify left bottom)
			)
		)
		(property "Value" "R_0R_0402"
			(at 0 1.4 270)
			(layer "F.Fab")
			(hide yes)
			(effects
				(font
					(size 0.7 0.7)
					(thickness 0.15)
				)
				(justify left bottom)
			)
		)
		(property "Datasheet" "https://industrial.panasonic.com/cdbs/www-data/pdf/RDA0000/AOA0000C301.pdf"
			(at 0 0 270)
			(layer "F.Fab")
			(hide yes)
			(effects
				(font
					(size 1.27 1.27)
					(thickness 0.15)
				)
			)
		)
		(property "Description" "SMD Chip Resistor, Jumper, 0 ohm, 100 mW, 0402 [1005 Metric], Thick Film, General Purpose"
			(at 0 0 270)
			(layer "F.Fab")
			(hide yes)
			(effects
				(font
					(size 1.27 1.27)
					(thickness 0.15)
				)
			)
		)
		(property "Author" "Antmicro"
			(at 14 247.5 0)
			(layer "F.Fab")
			(hide yes)
			(effects
				(font
					(size 1 1)
					(thickness 0.15)
				)
			)
		)
		(property "Current" "1A"
			(at 14 247.5 0)
			(layer "F.Fab")
			(hide yes)
			(effects
				(font
					(size 1 1)
					(thickness 0.15)
				)
			)
		)
		(property "License" "Apache-2.0"
			(at 14 247.5 0)
			(layer "F.Fab")
			(hide yes)
			(effects
				(font
					(size 1 1)
					(thickness 0.15)
				)
			)
		)
		(property "MPN" "ERJ2GE0R00X"
			(at 14 247.5 0)
			(layer "F.Fab")
			(hide yes)
			(effects
				(font
					(size 1 1)
					(thickness 0.15)
				)
			)
		)
		(property "Manufacturer" "Panasonic"
			(at 14 247.5 0)
			(layer "F.Fab")
			(hide yes)
			(effects
				(font
					(size 1 1)
					(thickness 0.15)
				)
			)
		)
		(property "Tolerance" "~"
			(at 14 247.5 0)
			(layer "F.Fab")
			(hide yes)
			(effects
				(font
					(size 1 1)
					(thickness 0.15)
				)
			)
		)
		(property "Val" "0R"
			(at 14 247.5 0)
			(layer "F.Fab")
			(hide yes)
			(effects
				(font
					(size 1 1)
					(thickness 0.15)
				)
			)
		)
		(sheetname "/Peripherals/")
		(sheetfile "peripherals.kicad_sch")
		(attr smd)
		(fp_rect
			(start -0.925 -0.47)
			(end 0.925 0.47)
			(stroke
				(width 0.05)
				(type default)
			)
			(fill no)
			(layer "F.CrtYd")
		)
		(fp_rect
			(start -0.5 -0.25)
			(end 0.5 0.25)
			(stroke
				(width 0.15)
				(type solid)
			)
			(fill no)
			(layer "F.Fab")
		)
		(fp_text user "Author: Antmicro"
			(at -0.95 4.169 270)
			(layer "F.Fab")
			(effects
				(font
					(size 0.7 0.7)
					(thickness 0.15)
				)
				(justify left bottom)
			)
		)
		(fp_text user "License: Apache-2.0"
			(at -0.95 5.169 270)
			(layer "F.Fab")
			(effects
				(font
					(size 0.7 0.7)
					(thickness 0.15)
				)
				(justify left bottom)
			)
		)
		(fp_text user "${REFERENCE}"
			(at -0.95 3.168 270)
			(layer "F.Fab")
			(effects
				(font
					(size 0.7 0.7)
					(thickness 0.15)
				)
				(justify left bottom)
			)
		)
		(pad "1" smd roundrect
			(at -0.48 0 270)
			(size 0.59 0.64)
			(layers "F.Cu" "F.Mask" "F.Paste")
			(roundrect_rratio 0.25)
			(net 101 "SDA")
			(pintype "passive")
		)
		(pad "2" smd roundrect
			(at 0.48 0 270)
			(size 0.59 0.64)
			(layers "F.Cu" "F.Mask" "F.Paste")
			(roundrect_rratio 0.25)
			(net 323 "Net-(J6-Pad39)")
			(pintype "passive")
		)
	)
	(footprint "antmicro-footprints:R_0402_1005Metric"
		(layer "F.Cu")
		(at 129.75 116.75 -90)
		(descr "Resistor SMD 0402")
		(tags "resistor SMD 0402")
		(property "Reference" "R130"
			(at -0.81 -0.28 270)
			(layer "F.SilkS")
			(effects
				(font
					(size 0.65 0.65)
					(thickness 0.15)
				)
				(justify left bottom)
			)
		)
		(property "Value" "R_0R_0402"
			(at 0 1.4 270)
			(layer "F.Fab")
			(hide yes)
			(effects
				(font
					(size 0.7 0.7)
					(thickness 0.15)
				)
				(justify left bottom)
			)
		)
		(property "Datasheet" "https://industrial.panasonic.com/cdbs/www-data/pdf/RDA0000/AOA0000C301.pdf"
			(at 0 0 270)
			(layer "F.Fab")
			(hide yes)
			(effects
				(font
					(size 1.27 1.27)
					(thickness 0.15)
				)
			)
		)
		(property "Description" "SMD Chip Resistor, Jumper, 0 ohm, 100 mW, 0402 [1005 Metric], Thick Film, General Purpose"
			(at 0 0 270)
			(layer "F.Fab")
			(hide yes)
			(effects
				(font
					(size 1.27 1.27)
					(thickness 0.15)
				)
			)
		)
		(property "Author" "Antmicro"
			(at 13 246.5 0)
			(layer "F.Fab")
			(hide yes)
			(effects
				(font
					(size 1 1)
					(thickness 0.15)
				)
			)
		)
		(property "Current" "1A"
			(at 13 246.5 0)
			(layer "F.Fab")
			(hide yes)
			(effects
				(font
					(size 1 1)
					(thickness 0.15)
				)
			)
		)
		(property "License" "Apache-2.0"
			(at 13 246.5 0)
			(layer "F.Fab")
			(hide yes)
			(effects
				(font
					(size 1 1)
					(thickness 0.15)
				)
			)
		)
		(property "MPN" "ERJ2GE0R00X"
			(at 13 246.5 0)
			(layer "F.Fab")
			(hide yes)
			(effects
				(font
					(size 1 1)
					(thickness 0.15)
				)
			)
		)
		(property "Manufacturer" "Panasonic"
			(at 13 246.5 0)
			(layer "F.Fab")
			(hide yes)
			(effects
				(font
					(size 1 1)
					(thickness 0.15)
				)
			)
		)
		(property "Tolerance" "~"
			(at 13 246.5 0)
			(layer "F.Fab")
			(hide yes)
			(effects
				(font
					(size 1 1)
					(thickness 0.15)
				)
			)
		)
		(property "Val" "0R"
			(at 13 246.5 0)
			(layer "F.Fab")
			(hide yes)
			(effects
				(font
					(size 1 1)
					(thickness 0.15)
				)
			)
		)
		(sheetname "/Peripherals/")
		(sheetfile "peripherals.kicad_sch")
		(attr smd)
		(fp_rect
			(start -0.925 -0.47)
			(end 0.925 0.47)
			(stroke
				(width 0.05)
				(type default)
			)
			(fill no)
			(layer "F.CrtYd")
		)
		(fp_rect
			(start -0.5 -0.25)
			(end 0.5 0.25)
			(stroke
				(width 0.15)
				(type solid)
			)
			(fill no)
			(layer "F.Fab")
		)
		(fp_text user "Author: Antmicro"
			(at -0.95 4.169 270)
			(layer "F.Fab")
			(effects
				(font
					(size 0.7 0.7)
					(thickness 0.15)
				)
				(justify left bottom)
			)
		)
		(fp_text user "${REFERENCE}"
			(at -0.95 3.168 270)
			(layer "F.Fab")
			(effects
				(font
					(size 0.7 0.7)
					(thickness 0.15)
				)
				(justify left bottom)
			)
		)
		(fp_text user "License: Apache-2.0"
			(at -0.95 5.169 270)
			(layer "F.Fab")
			(effects
				(font
					(size 0.7 0.7)
					(thickness 0.15)
				)
				(justify left bottom)
			)
		)
		(pad "1" smd roundrect
			(at -0.48 0 270)
			(size 0.59 0.64)
			(layers "F.Cu" "F.Mask" "F.Paste")
			(roundrect_rratio 0.25)
			(net 106 "/Peripherals/FFC2_VSYNC1")
			(pintype "passive")
		)
		(pad "2" smd roundrect
			(at 0.48 0 270)
			(size 0.59 0.64)
			(layers "F.Cu" "F.Mask" "F.Paste")
			(roundrect_rratio 0.25)
			(net 345 "Net-(J6-Pad34)")
			(pintype "passive")
		)
	)
	(footprint "antmicro-footprints:R_0402_1005Metric"
		(layer "F.Cu")
		(at 137.115 108.55 180)
		(descr "Resistor SMD 0402")
		(tags "resistor SMD 0402")
		(property "Reference" "R35"
			(at 3.085 -0.39 180)
			(layer "F.SilkS")
			(effects
				(font
					(size 0.65 0.65)
					(thickness 0.15)
				)
				(justify left bottom)
			)
		)
		(property "Value" "R_18k7_0402"
			(at 0 1.4 180)
			(layer "F.Fab")
			(hide yes)
			(effects
				(font
					(size 0.7 0.7)
					(thickness 0.15)
				)
				(justify left bottom)
			)
		)
		(property "Datasheet" "https://www.bourns.com/docs/product-datasheets/cr.pdf"
			(at 0 0 180)
			(layer "F.Fab")
			(hide yes)
			(effects
				(font
					(size 1.27 1.27)
					(thickness 0.15)
				)
			)
		)
		(property "Description" "SMD Chip Resistor"
			(at 0 0 180)
			(layer "F.Fab")
			(hide yes)
			(effects
				(font
					(size 1.27 1.27)
					(thickness 0.15)
				)
			)
		)
		(property "Author" "Antmicro"
			(at 274.23 217.1 0)
			(layer "F.Fab")
			(hide yes)
			(effects
				(font
					(size 1 1)
					(thickness 0.15)
				)
			)
		)
		(property "License" "Apache-2.0"
			(at 274.23 217.1 0)
			(layer "F.Fab")
			(hide yes)
			(effects
				(font
					(size 1 1)
					(thickness 0.15)
				)
			)
		)
		(property "MPN" "CR0402-FX-1872GLF"
			(at 274.23 217.1 0)
			(layer "F.Fab")
			(hide yes)
			(effects
				(font
					(size 1 1)
					(thickness 0.15)
				)
			)
		)
		(property "Manufacturer" "Bourns"
			(at 274.23 217.1 0)
			(layer "F.Fab")
			(hide yes)
			(effects
				(font
					(size 1 1)
					(thickness 0.15)
				)
			)
		)
		(property "Tolerance" "1%"
			(at 274.23 217.1 0)
			(layer "F.Fab")
			(hide yes)
			(effects
				(font
					(size 1 1)
					(thickness 0.15)
				)
			)
		)
		(property "Val" "18k7"
			(at 274.23 217.1 0)
			(layer "F.Fab")
			(hide yes)
			(effects
				(font
					(size 1 1)
					(thickness 0.15)
				)
			)
		)
		(sheetname "/Power Supply/")
		(sheetfile "supply.kicad_sch")
		(attr smd)
		(fp_rect
			(start -0.925 -0.47)
			(end 0.925 0.47)
			(stroke
				(width 0.05)
				(type default)
			)
			(fill no)
			(layer "F.CrtYd")
		)
		(fp_rect
			(start -0.5 -0.25)
			(end 0.5 0.25)
			(stroke
				(width 0.15)
				(type solid)
			)
			(fill no)
			(layer "F.Fab")
		)
		(fp_text user "Author: Antmicro"
			(at -0.95 4.169 180)
			(layer "F.Fab")
			(effects
				(font
					(size 0.7 0.7)
					(thickness 0.15)
				)
				(justify left bottom)
			)
		)
		(fp_text user "${REFERENCE}"
			(at -0.95 3.168 180)
			(layer "F.Fab")
			(effects
				(font
					(size 0.7 0.7)
					(thickness 0.15)
				)
				(justify left bottom)
			)
		)
		(fp_text user "License: Apache-2.0"
			(at -0.95 5.169 180)
			(layer "F.Fab")
			(effects
				(font
					(size 0.7 0.7)
					(thickness 0.15)
				)
				(justify left bottom)
			)
		)
		(pad "1" smd roundrect
			(at -0.48 0 180)
			(size 0.59 0.64)
			(layers "F.Cu" "F.Mask" "F.Paste")
			(roundrect_rratio 0.25)
			(net 283 "Net-(U10-ADJ)")
			(pintype "passive")
		)
		(pad "2" smd roundrect
			(at 0.48 0 180)
			(size 0.59 0.64)
			(layers "F.Cu" "F.Mask" "F.Paste")
			(roundrect_rratio 0.25)
			(net 284 "Net-(U10-V_{OUT})")
			(pintype "passive")
		)
	)
	(footprint "antmicro-footprints:LED_0603_1608Metric_G"
		(layer "F.Cu")
		(at 141.46 82.5 180)
		(descr "LED SMD 0603 Green")
		(tags "LED SMD 0603 Green")
		(property "Reference" "D12"
			(at -3.27 0.36 0)
			(layer "F.SilkS")
			(effects
				(font
					(size 0.65 0.65)
					(thickness 0.15)
				)
				(justify right top)
			)
		)
		(property "Value" "LED_G_0603_LTST-C190GKT"
			(at 0 1.6 0)
			(layer "F.Fab")
			(hide yes)
			(effects
				(font
					(size 0.7 0.7)
					(thickness 0.15)
				)
				(justify right top)
			)
		)
		(property "Datasheet" "https://media.digikey.com/pdf/Data%20Sheets/Lite-On%20PDFs/LTST-C190GKT.pdf"
			(at 0 0 0)
			(layer "F.Fab")
			(hide yes)
			(effects
				(font
					(size 1.27 1.27)
					(thickness 0.15)
				)
			)
		)
		(property "Description" "LED, Green, SMD, 0603, 20 mA, 2.1 V, 569 nm"
			(at 0 0 0)
			(layer "F.Fab")
			(hide yes)
			(effects
				(font
					(size 1.27 1.27)
					(thickness 0.15)
				)
			)
		)
		(property "Author" "Antmicro"
			(at 0 0 0)
			(layer "F.Fab")
			(hide yes)
			(effects
				(font
					(size 1 1)
					(thickness 0.15)
				)
			)
		)
		(property "License" "Apache-2.0"
			(at 0 0 0)
			(layer "F.Fab")
			(hide yes)
			(effects
				(font
					(size 1 1)
					(thickness 0.15)
				)
			)
		)
		(property "MPN" "LTST-C190GKT"
			(at 0 0 0)
			(layer "F.Fab")
			(hide yes)
			(effects
				(font
					(size 1 1)
					(thickness 0.15)
				)
			)
		)
		(property "Manufacturer" "Lite-On"
			(at 0 0 0)
			(layer "F.Fab")
			(hide yes)
			(effects
				(font
					(size 1 1)
					(thickness 0.15)
				)
			)
		)
		(property "Color" "Green"
			(at 0 0 180)
			(unlocked yes)
			(layer "F.Fab")
			(hide yes)
			(effects
				(font
					(size 1 1)
					(thickness 0.15)
				)
			)
		)
		(sheetname "/Peripherals/")
		(sheetfile "peripherals.kicad_sch")
		(attr smd)
		(fp_line
			(start 0.22 0.35)
			(end -0.22 0.35)
			(stroke
				(width 0.15)
				(type solid)
			)
			(layer "F.SilkS")
		)
		(fp_line
			(start 0.22 -0.35)
			(end -0.22 -0.35)
			(stroke
				(width 0.15)
				(type solid)
			)
			(layer "F.SilkS")
		)
		(fp_line
			(start 0.105328 0.201008)
			(end 0.105328 -0.198992)
			(stroke
				(width 0.1)
				(type solid)
			)
			(layer "F.SilkS")
		)
		(fp_line
			(start 0.105328 0.201008)
			(end -0.094672 0.001008)
			(stroke
				(width 0.1)
				(type solid)
			)
			(layer "F.SilkS")
		)
		(fp_line
			(start 0.105328 0.001008)
			(end 0.24 0.001)
			(stroke
				(width 0.1)
				(type solid)
			)
			(layer "F.SilkS")
		)
		(fp_line
			(start -0.094672 0.201008)
			(end -0.094672 -0.198992)
			(stroke
				(width 0.1)
				(type solid)
			)
			(layer "F.SilkS")
		)
		(fp_line
			(start -0.094672 0.001008)
			(end 0.105328 -0.198992)
			(stroke
				(width 0.1)
				(type solid)
			)
			(layer "F.SilkS")
		)
		(fp_line
			(start -0.094672 0.001008)
			(end -0.24 0.001008)
			(stroke
				(width 0.1)
				(type solid)
			)
			(layer "F.SilkS")
		)
		(fp_line
			(start -1.18 -0.319)
			(end -1.18 0.321)
			(stroke
				(width 0.15)
				(type solid)
			)
			(layer "F.SilkS")
		)
		(fp_rect
			(start 1.25 0.65)
			(end -1.25 -0.65)
			(stroke
				(width 0.05)
				(type solid)
			)
			(fill no)
			(layer "F.CrtYd")
		)
		(fp_line
			(start 0.599 0)
			(end 0.201 0)
			(stroke
				(width 0.15)
				(type solid)
			)
			(layer "F.Fab")
		)
		(fp_line
			(start 0.201 0.2)
			(end 0.201 0)
			(stroke
				(width 0.15)
				(type solid)
			)
			(layer "F.Fab")
		)
		(fp_line
			(start 0.201 0)
			(end 0.201 -0.202)
			(stroke
				(width 0.15)
				(type solid)
			)
			(layer "F.Fab")
		)
		(fp_line
			(start 0.201 -0.202)
			(end -0.101 0)
			(stroke
				(width 0.15)
				(type solid)
			)
			(layer "F.Fab")
		)
		(fp_line
			(start -0.101 0)
			(end 0.201 0.2)
			(stroke
				(width 0.15)
				(type solid)
			)
			(layer "F.Fab")
		)
		(fp_line
			(start -0.199 0.2)
			(end -0.199 0.1)
			(stroke
				(width 0.15)
				(type solid)
			)
			(layer "F.Fab")
		)
		(fp_line
			(start -0.199 0)
			(end -0.597 0)
			(stroke
				(width 0.15)
				(type solid)
			)
			(layer "F.Fab")
		)
		(fp_line
			(start -0.199 -0.202)
			(end -0.199 0.1)
			(stroke
				(width 0.15)
				(type solid)
			)
			(layer "F.Fab")
		)
		(fp_rect
			(start 0.848 0.4)
			(end -0.85 -0.402)
			(stroke
				(width 0.15)
				(type solid)
			)
			(fill no)
			(layer "F.Fab")
		)
		(fp_text user "License: Apache-2.0"
			(at -1.4224 3.599 0)
			(layer "F.Fab")
			(effects
				(font
					(size 0.7 0.7)
					(thickness 0.15)
				)
				(justify right top)
			)
		)
		(fp_text user "${REFERENCE}"
			(at -1.4224 5.999 0)
			(layer "F.Fab")
			(effects
				(font
					(size 0.7 0.7)
					(thickness 0.15)
				)
				(justify right top)
			)
		)
		(fp_text user "Author: Antmicro"
			(at -1.4224 4.799 0)
			(layer "F.Fab")
			(effects
				(font
					(size 0.7 0.7)
					(thickness 0.15)
				)
				(justify right top)
			)
		)
		(pad "1" smd roundrect
			(at -0.7 0)
			(size 0.8 1)
			(layers "F.Cu" "F.Mask" "F.Paste")
			(roundrect_rratio 0.2)
			(net 258 "Net-(D12-C)")
			(pinfunction "C")
			(pintype "passive")
		)
		(pad "2" smd roundrect
			(at 0.7 0)
			(size 0.8 1)
			(layers "F.Cu" "F.Mask" "F.Paste")
			(roundrect_rratio 0.2)
			(net 294 "Net-(D12-A)")
			(pinfunction "A")
			(pintype "passive")
		)
	)
	(footprint "antmicro-footprints:L_0402_1005Metric"
		(layer "F.Cu")
		(at 85.2 104.15)
		(descr "Inductor SMD 0402")
		(tags "Inductor SMD 0402")
		(property "Reference" "L5"
			(at 2.43 -7.91 0)
			(layer "F.SilkS")
			(effects
				(font
					(size 0.65 0.65)
					(thickness 0.15)
				)
				(justify left bottom)
			)
		)
		(property "Value" "L_6n2_0.7A_0402"
			(at 0 1.4 0)
			(layer "F.Fab")
			(hide yes)
			(effects
				(font
					(size 0.7 0.7)
					(thickness 0.15)
				)
				(justify left bottom)
			)
		)
		(property "Datasheet" "https://www.mouser.com/datasheet/2/281/1/JELF243A_0050-1380872.pdf"
			(at 0 0 0)
			(layer "F.Fab")
			(hide yes)
			(effects
				(font
					(size 1.27 1.27)
					(thickness 0.15)
				)
			)
		)
		(property "Description" "Wirewound Inductor, 6.2 nH, 0.09 ohm, 8 GHz, 700 mA, 0402 [1005 Metric], LQW"
			(at 0 0 0)
			(layer "F.Fab")
			(hide yes)
			(effects
				(font
					(size 1.27 1.27)
					(thickness 0.15)
				)
			)
		)
		(property "Author" "Antmicro"
			(at 0 0 0)
			(layer "F.Fab")
			(hide yes)
			(effects
				(font
					(size 1 1)
					(thickness 0.15)
				)
			)
		)
		(property "IMax" "0.7 A"
			(at 0 0 0)
			(layer "F.Fab")
			(hide yes)
			(effects
				(font
					(size 1 1)
					(thickness 0.15)
				)
			)
		)
		(property "ISat" ""
			(at 0 0 0)
			(layer "F.Fab")
			(hide yes)
			(effects
				(font
					(size 1 1)
					(thickness 0.15)
				)
			)
		)
		(property "License" "Apache-2.0"
			(at 0 0 0)
			(layer "F.Fab")
			(hide yes)
			(effects
				(font
					(size 1 1)
					(thickness 0.15)
				)
			)
		)
		(property "MPN" "LQW15AN6N2C00D"
			(at 0 0 0)
			(layer "F.Fab")
			(hide yes)
			(effects
				(font
					(size 1 1)
					(thickness 0.15)
				)
			)
		)
		(property "Manufacturer" "Murata"
			(at 0 0 0)
			(layer "F.Fab")
			(hide yes)
			(effects
				(font
					(size 1 1)
					(thickness 0.15)
				)
			)
		)
		(property "Size" "1.0x0.5"
			(at 0 0 0)
			(layer "F.Fab")
			(hide yes)
			(effects
				(font
					(size 1 1)
					(thickness 0.15)
				)
			)
		)
		(property "Val" "6n2/0.7A"
			(at 0 0 0)
			(layer "F.Fab")
			(hide yes)
			(effects
				(font
					(size 1 1)
					(thickness 0.15)
				)
			)
		)
		(sheetname "/SDI/")
		(sheetfile "sdi.kicad_sch")
		(attr smd)
		(fp_rect
			(start -0.925 -0.47)
			(end 0.925 0.47)
			(stroke
				(width 0.05)
				(type default)
			)
			(fill no)
			(layer "F.CrtYd")
		)
		(fp_rect
			(start -0.499 -0.249)
			(end 0.499 0.249)
			(stroke
				(width 0.15)
				(type solid)
			)
			(fill no)
			(layer "F.Fab")
		)
		(fp_text user "${REFERENCE}"
			(at -0.932 3.168 0)
			(layer "F.Fab")
			(effects
				(font
					(size 0.7 0.7)
					(thickness 0.15)
				)
				(justify left bottom)
			)
		)
		(fp_text user "License: Apache-2.0"
			(at -0.932 5.17 0)
			(layer "F.Fab")
			(effects
				(font
					(size 0.7 0.7)
					(thickness 0.15)
				)
				(justify left bottom)
			)
		)
		(fp_text user "Author: Antmicro"
			(at -0.932 4.17 0)
			(layer "F.Fab")
			(effects
				(font
					(size 0.7 0.7)
					(thickness 0.15)
				)
				(justify left bottom)
			)
		)
		(pad "1" smd roundrect
			(at -0.48 0)
			(size 0.59 0.64)
			(layers "F.Cu" "F.Mask" "F.Paste")
			(roundrect_rratio 0.25)
			(net 251 "/SDI/SDI_OUT_F2")
			(pintype "passive")
		)
		(pad "2" smd roundrect
			(at 0.48 0)
			(size 0.59 0.64)
			(layers "F.Cu" "F.Mask" "F.Paste")
			(roundrect_rratio 0.25)
			(net 254 "/SDI/SDI_OUT_N")
			(pintype "passive")
		)
	)
	(footprint "antmicro-footprints:TP_SMD_0.75mm"
		(layer "F.Cu")
		(at 137.19 104.45 90)
		(property "Reference" "TP5"
			(at 0 -0.6 90)
			(layer "F.SilkS")
			(effects
				(font
					(size 0.65 0.65)
					(thickness 0.15)
				)
				(justify left bottom)
			)
		)
		(property "Value" "TP_0.75mm_SMD"
			(at 0 1.2 90)
			(layer "F.Fab")
			(hide yes)
			(effects
				(font
					(size 0.7 0.7)
					(thickness 0.15)
				)
				(justify left bottom)
			)
		)
		(property "Description" "SMT test point"
			(at 0 0 90)
			(layer "F.Fab")
			(hide yes)
			(effects
				(font
					(size 1.27 1.27)
					(thickness 0.15)
				)
			)
		)
		(property "Author" "Antmicro"
			(at 241.64 -32.74 0)
			(layer "F.Fab")
			(hide yes)
			(effects
				(font
					(size 1 1)
					(thickness 0.15)
				)
			)
		)
		(property "License" "Apache-2.0"
			(at 241.64 -32.74 0)
			(layer "F.Fab")
			(hide yes)
			(effects
				(font
					(size 1 1)
					(thickness 0.15)
				)
			)
		)
		(property "MPN" ""
			(at 241.64 -32.74 0)
			(layer "F.Fab")
			(hide yes)
			(effects
				(font
					(size 1 1)
					(thickness 0.15)
				)
			)
		)
		(property "Manufacturer" ""
			(at 241.64 -32.74 0)
			(layer "F.Fab")
			(hide yes)
			(effects
				(font
					(size 1 1)
					(thickness 0.15)
				)
			)
		)
		(sheetname "/Power Supply/")
		(sheetfile "supply.kicad_sch")
		(attr exclude_from_pos_files)
		(fp_circle
			(center 0 0)
			(end 0.475 0)
			(stroke
				(width 0.05)
				(type default)
			)
			(fill no)
			(layer "F.CrtYd")
		)
		(fp_text user "Author: Antmicro"
			(at -0.4 3.901 90)
			(layer "F.Fab")
			(effects
				(font
					(size 0.7 0.7)
					(thickness 0.15)
				)
				(justify left bottom)
			)
		)
		(fp_text user "${REFERENCE}"
			(at -0.4 2.7 90)
			(layer "F.Fab")
			(effects
				(font
					(size 0.7 0.7)
					(thickness 0.15)
				)
				(justify left bottom)
			)
		)
		(fp_text user "License: Apache-2.0"
			(at -0.4 5.101 90)
			(layer "F.Fab")
			(effects
				(font
					(size 0.7 0.7)
					(thickness 0.15)
				)
				(justify left bottom)
			)
		)
		(pad "1" smd circle
			(at 0 0 90)
			(size 0.75 0.75)
			(layers "F.Cu" "F.Mask")
			(net 49 "1V0_Clean")
			(pinfunction "1")
			(pintype "passive")
		)
	)
	(footprint "antmicro-footprints:C_0402_1005Metric"
		(layer "F.Cu")
		(at 129.33 67.025 -90)
		(descr "Capacitor SMD 0402")
		(tags "capacitor SMD 0402")
		(property "Reference" "C119"
			(at -1.385 -1.4 90)
			(layer "F.SilkS")
			(effects
				(font
					(size 0.65 0.65)
					(thickness 0.15)
				)
				(justify right bottom)
			)
		)
		(property "Value" "C_100n_0402"
			(at 0 1.4 90)
			(layer "F.Fab")
			(hide yes)
			(effects
				(font
					(size 0.7 0.7)
					(thickness 0.15)
				)
				(justify right bottom)
			)
		)
		(property "Datasheet" "https://www.murata.com/products/productdetail?partno=GRM155R61H104KE14%23"
			(at 0 0 270)
			(layer "F.Fab")
			(hide yes)
			(effects
				(font
					(size 1.27 1.27)
					(thickness 0.15)
				)
			)
		)
		(property "Description" "SMD Multilayer Ceramic Capacitor, 0.1 µF, 50 V, 0402 [1005 Metric], ± 10%, X5R, GRM Series"
			(at 0 0 270)
			(layer "F.Fab")
			(hide yes)
			(effects
				(font
					(size 1.27 1.27)
					(thickness 0.15)
				)
			)
		)
		(property "Author" "Antmicro"
			(at 62.305 196.355 0)
			(layer "F.Fab")
			(hide yes)
			(effects
				(font
					(size 1 1)
					(thickness 0.15)
				)
			)
		)
		(property "Dielectric" "X5R"
			(at 62.305 196.355 0)
			(layer "F.Fab")
			(hide yes)
			(effects
				(font
					(size 1 1)
					(thickness 0.15)
				)
			)
		)
		(property "License" "Apache-2.0"
			(at 62.305 196.355 0)
			(layer "F.Fab")
			(hide yes)
			(effects
				(font
					(size 1 1)
					(thickness 0.15)
				)
			)
		)
		(property "MPN" "GRM155R61H104KE14D"
			(at 62.305 196.355 0)
			(layer "F.Fab")
			(hide yes)
			(effects
				(font
					(size 1 1)
					(thickness 0.15)
				)
			)
		)
		(property "Manufacturer" "Murata"
			(at 62.305 196.355 0)
			(layer "F.Fab")
			(hide yes)
			(effects
				(font
					(size 1 1)
					(thickness 0.15)
				)
			)
		)
		(property "Val" "100n"
			(at 62.305 196.355 0)
			(layer "F.Fab")
			(hide yes)
			(effects
				(font
					(size 1 1)
					(thickness 0.15)
				)
			)
		)
		(property "Voltage" "50V"
			(at 62.305 196.355 0)
			(layer "F.Fab")
			(hide yes)
			(effects
				(font
					(size 1 1)
					(thickness 0.15)
				)
			)
		)
		(sheetname "/DDR3/")
		(sheetfile "ddr3.kicad_sch")
		(attr smd)
		(fp_rect
			(start -0.925 -0.47)
			(end 0.925 0.47)
			(stroke
				(width 0.05)
				(type default)
			)
			(fill no)
			(layer "F.CrtYd")
		)
		(fp_line
			(start -0.494 0.248)
			(end -0.494 -0.25)
			(stroke
				(width 0.15)
				(type solid)
			)
			(layer "F.Fab")
		)
		(fp_line
			(start 0.504 0.248)
			(end -0.494 0.248)
			(stroke
				(width 0.15)
				(type solid)
			)
			(layer "F.Fab")
		)
		(fp_line
			(start -0.494 -0.25)
			(end 0.504 -0.25)
			(stroke
				(width 0.15)
				(type solid)
			)
			(layer "F.Fab")
		)
		(fp_line
			(start 0.504 -0.25)
			(end 0.504 0.248)
			(stroke
				(width 0.15)
				(type solid)
			)
			(layer "F.Fab")
		)
		(fp_text user "License: Apache-2.0"
			(at -0.939 5.799 270)
			(layer "F.Fab")
			(effects
				(font
					(size 0.7 0.7)
					(thickness 0.15)
				)
				(justify left bottom)
			)
		)
		(fp_text user "Author: Antmicro"
			(at -0.939 3.399 270)
			(layer "F.Fab")
			(effects
				(font
					(size 0.7 0.7)
					(thickness 0.15)
				)
				(justify left bottom)
			)
		)
		(fp_text user "${REFERENCE}"
			(at -0.939 4.599 270)
			(layer "F.Fab")
			(effects
				(font
					(size 0.7 0.7)
					(thickness 0.15)
				)
				(justify left bottom)
			)
		)
		(pad "1" smd roundrect
			(at -0.48 0 270)
			(size 0.59 0.64)
			(layers "F.Cu" "F.Mask" "F.Paste")
			(roundrect_rratio 0.25)
			(net 5 "Vref")
			(pintype "passive")
		)
		(pad "2" smd roundrect
			(at 0.48 0 270)
			(size 0.59 0.64)
			(layers "F.Cu" "F.Mask" "F.Paste")
			(roundrect_rratio 0.25)
			(net 248 "+1V5")
			(pintype "passive")
		)
	)
	(footprint "antmicro-footprints:C_0402_1005Metric"
		(layer "F.Cu")
		(at 140.13 71.04 90)
		(descr "Capacitor SMD 0402")
		(tags "capacitor SMD 0402")
		(property "Reference" "C9"
			(at -0.8 -0.7 90)
			(layer "F.SilkS")
			(effects
				(font
					(size 0.65 0.65)
					(thickness 0.15)
				)
				(justify left bottom)
			)
		)
		(property "Value" "C_100n_0402"
			(at 0 1.4 90)
			(layer "F.Fab")
			(hide yes)
			(effects
				(font
					(size 0.7 0.7)
					(thickness 0.15)
				)
				(justify left bottom)
			)
		)
		(property "Datasheet" "https://www.murata.com/products/productdetail?partno=GRM155R61H104KE14%23"
			(at 0 0 90)
			(layer "F.Fab")
			(hide yes)
			(effects
				(font
					(size 1.27 1.27)
					(thickness 0.15)
				)
			)
		)
		(property "Description" "SMD Multilayer Ceramic Capacitor, 0.1 µF, 50 V, 0402 [1005 Metric], ± 10%, X5R, GRM Series"
			(at 0 0 90)
			(layer "F.Fab")
			(hide yes)
			(effects
				(font
					(size 1.27 1.27)
					(thickness 0.15)
				)
			)
		)
		(property "Author" "Antmicro"
			(at 211.17 -69.09 0)
			(layer "F.Fab")
			(hide yes)
			(effects
				(font
					(size 1 1)
					(thickness 0.15)
				)
			)
		)
		(property "Dielectric" "X5R"
			(at 211.17 -69.09 0)
			(layer "F.Fab")
			(hide yes)
			(effects
				(font
					(size 1 1)
					(thickness 0.15)
				)
			)
		)
		(property "License" "Apache-2.0"
			(at 211.17 -69.09 0)
			(layer "F.Fab")
			(hide yes)
			(effects
				(font
					(size 1 1)
					(thickness 0.15)
				)
			)
		)
		(property "MPN" "GRM155R61H104KE14D"
			(at 211.17 -69.09 0)
			(layer "F.Fab")
			(hide yes)
			(effects
				(font
					(size 1 1)
					(thickness 0.15)
				)
			)
		)
		(property "Manufacturer" "Murata"
			(at 211.17 -69.09 0)
			(layer "F.Fab")
			(hide yes)
			(effects
				(font
					(size 1 1)
					(thickness 0.15)
				)
			)
		)
		(property "Val" "100n"
			(at 211.17 -69.09 0)
			(layer "F.Fab")
			(hide yes)
			(effects
				(font
					(size 1 1)
					(thickness 0.15)
				)
			)
		)
		(property "Voltage" "50V"
			(at 211.17 -69.09 0)
			(layer "F.Fab")
			(hide yes)
			(effects
				(font
					(size 1 1)
					(thickness 0.15)
				)
			)
		)
		(sheetname "/Power Supply/")
		(sheetfile "supply.kicad_sch")
		(attr smd)
		(fp_rect
			(start -0.925 -0.47)
			(end 0.925 0.47)
			(stroke
				(width 0.05)
				(type default)
			)
			(fill no)
			(layer "F.CrtYd")
		)
		(fp_line
			(start 0.504 -0.25)
			(end 0.504 0.248)
			(stroke
				(width 0.15)
				(type solid)
			)
			(layer "F.Fab")
		)
		(fp_line
			(start -0.494 -0.25)
			(end 0.504 -0.25)
			(stroke
				(width 0.15)
				(type solid)
			)
			(layer "F.Fab")
		)
		(fp_line
			(start 0.504 0.248)
			(end -0.494 0.248)
			(stroke
				(width 0.15)
				(type solid)
			)
			(layer "F.Fab")
		)
		(fp_line
			(start -0.494 0.248)
			(end -0.494 -0.25)
			(stroke
				(width 0.15)
				(type solid)
			)
			(layer "F.Fab")
		)
		(fp_text user "License: Apache-2.0"
			(at -0.939 5.799 90)
			(layer "F.Fab")
			(effects
				(font
					(size 0.7 0.7)
					(thickness 0.15)
				)
				(justify left bottom)
			)
		)
		(fp_text user "${REFERENCE}"
			(at -0.939 4.599 90)
			(layer "F.Fab")
			(effects
				(font
					(size 0.7 0.7)
					(thickness 0.15)
				)
				(justify left bottom)
			)
		)
		(fp_text user "Author: Antmicro"
			(at -0.939 3.399 90)
			(layer "F.Fab")
			(effects
				(font
					(size 0.7 0.7)
					(thickness 0.15)
				)
				(justify left bottom)
			)
		)
		(pad "1" smd roundrect
			(at -0.48 0 90)
			(size 0.59 0.64)
			(layers "F.Cu" "F.Mask" "F.Paste")
			(roundrect_rratio 0.25)
			(net 276 "/Power Supply/1V0_SW")
			(pintype "passive")
		)
		(pad "2" smd roundrect
			(at 0.48 0 90)
			(size 0.59 0.64)
			(layers "F.Cu" "F.Mask" "F.Paste")
			(roundrect_rratio 0.25)
			(net 61 "Net-(U5-BST)")
			(pintype "passive")
		)
	)
	(footprint "antmicro-footprints:R_0402_1005Metric"
		(layer "F.Cu")
		(at 156.69 65.1 -90)
		(descr "Resistor SMD 0402")
		(tags "resistor SMD 0402")
		(property "Reference" "R9"
			(at 2.34 -0.34 270)
			(layer "F.SilkS")
			(effects
				(font
					(size 0.65 0.65)
					(thickness 0.15)
				)
				(justify left bottom)
			)
		)
		(property "Value" "R_10k_0402"
			(at 0 1.4 270)
			(layer "F.Fab")
			(hide yes)
			(effects
				(font
					(size 0.7 0.7)
					(thickness 0.15)
				)
				(justify left bottom)
			)
		)
		(property "Datasheet" "https://www.bourns.com/docs/product-datasheets/cr.pdf"
			(at 0 0 270)
			(layer "F.Fab")
			(hide yes)
			(effects
				(font
					(size 1.27 1.27)
					(thickness 0.15)
				)
			)
		)
		(property "Description" "SMD Chip Resistor, 10 kohm, ± 1%, 62.5 mW, 0402 [1005 Metric], Thick Film, General Purpose"
			(at 0 0 270)
			(layer "F.Fab")
			(hide yes)
			(effects
				(font
					(size 1.27 1.27)
					(thickness 0.15)
				)
			)
		)
		(property "Author" "Antmicro"
			(at 91.59 221.79 0)
			(layer "F.Fab")
			(hide yes)
			(effects
				(font
					(size 1 1)
					(thickness 0.15)
				)
			)
		)
		(property "License" "Apache-2.0"
			(at 91.59 221.79 0)
			(layer "F.Fab")
			(hide yes)
			(effects
				(font
					(size 1 1)
					(thickness 0.15)
				)
			)
		)
		(property "MPN" "CR0402-FX-1002GLF"
			(at 91.59 221.79 0)
			(layer "F.Fab")
			(hide yes)
			(effects
				(font
					(size 1 1)
					(thickness 0.15)
				)
			)
		)
		(property "Manufacturer" "Bourns"
			(at 91.59 221.79 0)
			(layer "F.Fab")
			(hide yes)
			(effects
				(font
					(size 1 1)
					(thickness 0.15)
				)
			)
		)
		(property "Tolerance" "1%"
			(at 91.59 221.79 0)
			(layer "F.Fab")
			(hide yes)
			(effects
				(font
					(size 1 1)
					(thickness 0.15)
				)
			)
		)
		(property "Val" "10k"
			(at 91.59 221.79 0)
			(layer "F.Fab")
			(hide yes)
			(effects
				(font
					(size 1 1)
					(thickness 0.15)
				)
			)
		)
		(sheetname "/Power Supply/")
		(sheetfile "supply.kicad_sch")
		(attr smd)
		(fp_rect
			(start -0.925 -0.47)
			(end 0.925 0.47)
			(stroke
				(width 0.05)
				(type default)
			)
			(fill no)
			(layer "F.CrtYd")
		)
		(fp_rect
			(start -0.5 -0.25)
			(end 0.5 0.25)
			(stroke
				(width 0.15)
				(type solid)
			)
			(fill no)
			(layer "F.Fab")
		)
		(fp_text user "Author: Antmicro"
			(at -0.95 4.169 270)
			(layer "F.Fab")
			(effects
				(font
					(size 0.7 0.7)
					(thickness 0.15)
				)
				(justify left bottom)
			)
		)
		(fp_text user "${REFERENCE}"
			(at -0.95 3.168 270)
			(layer "F.Fab")
			(effects
				(font
					(size 0.7 0.7)
					(thickness 0.15)
				)
				(justify left bottom)
			)
		)
		(fp_text user "License: Apache-2.0"
			(at -0.95 5.169 270)
			(layer "F.Fab")
			(effects
				(font
					(size 0.7 0.7)
					(thickness 0.15)
				)
				(justify left bottom)
			)
		)
		(pad "1" smd roundrect
			(at -0.48 0 270)
			(size 0.59 0.64)
			(layers "F.Cu" "F.Mask" "F.Paste")
			(roundrect_rratio 0.25)
			(net 1 "GND")
			(pintype "passive")
		)
		(pad "2" smd roundrect
			(at 0.48 0 270)
			(size 0.59 0.64)
			(layers "F.Cu" "F.Mask" "F.Paste")
			(roundrect_rratio 0.25)
			(net 325 "USB_POWER_IN")
			(pintype "passive")
		)
	)
	(footprint "antmicro-footprints:C_0603_1608Metric"
		(layer "F.Cu")
		(at 149.08 70.85 -90)
		(descr "Capacitor SMD 0603")
		(tags "capacitor 0603")
		(property "Reference" "C20"
			(at -1.46 -1.33 90)
			(layer "F.SilkS")
			(effects
				(font
					(size 0.65 0.65)
					(thickness 0.15)
				)
				(justify right bottom)
			)
		)
		(property "Value" "C_22u_0603"
			(at 0 1.6 90)
			(layer "F.Fab")
			(hide yes)
			(effects
				(font
					(size 0.7 0.7)
					(thickness 0.15)
				)
				(justify right bottom)
			)
		)
		(property "Datasheet" "https://www.murata.com/products/productdetail?partno=GRM188R60J226MEA0%23"
			(at 0 0 270)
			(layer "F.Fab")
			(hide yes)
			(effects
				(font
					(size 1.27 1.27)
					(thickness 0.15)
				)
			)
		)
		(property "Description" "SMD Multilayer Ceramic Capacitor, 22 µF, 6.3 V, 0603 [1608 Metric], ± 20%, X5R, GRM Series"
			(at 0 0 270)
			(layer "F.Fab")
			(hide yes)
			(effects
				(font
					(size 1.27 1.27)
					(thickness 0.15)
				)
			)
		)
		(property "Author" "Antmicro"
			(at 78.23 219.93 0)
			(layer "F.Fab")
			(hide yes)
			(effects
				(font
					(size 1 1)
					(thickness 0.15)
				)
			)
		)
		(property "Dielectric" ""
			(at 78.23 219.93 0)
			(layer "F.Fab")
			(hide yes)
			(effects
				(font
					(size 1 1)
					(thickness 0.15)
				)
			)
		)
		(property "License" "Apache-2.0"
			(at 78.23 219.93 0)
			(layer "F.Fab")
			(hide yes)
			(effects
				(font
					(size 1 1)
					(thickness 0.15)
				)
			)
		)
		(property "MPN" "GRM188R60J226MEA0D"
			(at 78.23 219.93 0)
			(layer "F.Fab")
			(hide yes)
			(effects
				(font
					(size 1 1)
					(thickness 0.15)
				)
			)
		)
		(property "Manufacturer" "Murata"
			(at 78.23 219.93 0)
			(layer "F.Fab")
			(hide yes)
			(effects
				(font
					(size 1 1)
					(thickness 0.15)
				)
			)
		)
		(property "Val" "22u"
			(at 78.23 219.93 0)
			(layer "F.Fab")
			(hide yes)
			(effects
				(font
					(size 1 1)
					(thickness 0.15)
				)
			)
		)
		(property "Voltage" ""
			(at 78.23 219.93 0)
			(layer "F.Fab")
			(hide yes)
			(effects
				(font
					(size 1 1)
					(thickness 0.15)
				)
			)
		)
		(sheetname "/Power Supply/")
		(sheetfile "supply.kicad_sch")
		(attr smd)
		(fp_line
			(start -0.15 0.4)
			(end 0.15 0.4)
			(stroke
				(width 0.15)
				(type solid)
			)
			(layer "F.SilkS")
		)
		(fp_line
			(start -0.15 -0.4)
			(end 0.15 -0.4)
			(stroke
				(width 0.15)
				(type solid)
			)
			(layer "F.SilkS")
		)
		(fp_rect
			(start -1.25 -0.65)
			(end 1.25 0.65)
			(stroke
				(width 0.05)
				(type solid)
			)
			(fill no)
			(layer "F.CrtYd")
		)
		(fp_rect
			(start -0.8 -0.4)
			(end 0.8 0.4)
			(stroke
				(width 0.15)
				(type solid)
			)
			(fill no)
			(layer "F.Fab")
		)
		(fp_text user "License: Apache-2.0"
			(at -1.682 5.895 270)
			(layer "F.Fab")
			(effects
				(font
					(size 0.7 0.7)
					(thickness 0.15)
				)
				(justify left bottom)
			)
		)
		(fp_text user "${REFERENCE}"
			(at -1.682 3.895 270)
			(layer "F.Fab")
			(effects
				(font
					(size 0.7 0.7)
					(thickness 0.15)
				)
				(justify left bottom)
			)
		)
		(fp_text user "Author: Antmicro"
			(at -1.682 4.894 270)
			(layer "F.Fab")
			(effects
				(font
					(size 0.7 0.7)
					(thickness 0.15)
				)
				(justify left bottom)
			)
		)
		(pad "1" smd roundrect
			(at -0.7 0 270)
			(size 0.8 1)
			(layers "F.Cu" "F.Mask" "F.Paste")
			(roundrect_rratio 0.2)
			(net 1 "GND")
			(pintype "passive")
		)
		(pad "2" smd roundrect
			(at 0.7 0 270)
			(size 0.8 1)
			(layers "F.Cu" "F.Mask" "F.Paste")
			(roundrect_rratio 0.2)
			(net 273 "/Power Supply/1V0_OUT")
			(pintype "passive")
		)
	)
	(footprint "antmicro-footprints:R_0402_1005Metric"
		(layer "F.Cu")
		(at 144.84 107.9 180)
		(descr "Resistor SMD 0402")
		(tags "resistor SMD 0402")
		(property "Reference" "R19"
			(at -0.99 -0.44 180)
			(layer "F.SilkS")
			(effects
				(font
					(size 0.65 0.65)
					(thickness 0.15)
				)
				(justify left bottom)
			)
		)
		(property "Value" "R_0R_0402"
			(at 0 1.4 180)
			(layer "F.Fab")
			(hide yes)
			(effects
				(font
					(size 0.7 0.7)
					(thickness 0.15)
				)
				(justify left bottom)
			)
		)
		(property "Datasheet" "https://industrial.panasonic.com/cdbs/www-data/pdf/RDA0000/AOA0000C301.pdf"
			(at 0 0 180)
			(layer "F.Fab")
			(hide yes)
			(effects
				(font
					(size 1.27 1.27)
					(thickness 0.15)
				)
			)
		)
		(property "Description" "SMD Chip Resistor, Jumper, 0 ohm, 100 mW, 0402 [1005 Metric], Thick Film, General Purpose"
			(at 0 0 180)
			(layer "F.Fab")
			(hide yes)
			(effects
				(font
					(size 1.27 1.27)
					(thickness 0.15)
				)
			)
		)
		(property "Author" "Antmicro"
			(at 289.68 215.8 0)
			(layer "F.Fab")
			(hide yes)
			(effects
				(font
					(size 1 1)
					(thickness 0.15)
				)
			)
		)
		(property "Current" "1A"
			(at 289.68 215.8 0)
			(layer "F.Fab")
			(hide yes)
			(effects
				(font
					(size 1 1)
					(thickness 0.15)
				)
			)
		)
		(property "License" "Apache-2.0"
			(at 289.68 215.8 0)
			(layer "F.Fab")
			(hide yes)
			(effects
				(font
					(size 1 1)
					(thickness 0.15)
				)
			)
		)
		(property "MPN" "ERJ2GE0R00X"
			(at 289.68 215.8 0)
			(layer "F.Fab")
			(hide yes)
			(effects
				(font
					(size 1 1)
					(thickness 0.15)
				)
			)
		)
		(property "Manufacturer" "Panasonic"
			(at 289.68 215.8 0)
			(layer "F.Fab")
			(hide yes)
			(effects
				(font
					(size 1 1)
					(thickness 0.15)
				)
			)
		)
		(property "Tolerance" "~"
			(at 289.68 215.8 0)
			(layer "F.Fab")
			(hide yes)
			(effects
				(font
					(size 1 1)
					(thickness 0.15)
				)
			)
		)
		(property "Val" "0R"
			(at 289.68 215.8 0)
			(layer "F.Fab")
			(hide yes)
			(effects
				(font
					(size 1 1)
					(thickness 0.15)
				)
			)
		)
		(sheetname "/Power Supply/")
		(sheetfile "supply.kicad_sch")
		(attr smd)
		(fp_rect
			(start -0.925 -0.47)
			(end 0.925 0.47)
			(stroke
				(width 0.05)
				(type default)
			)
			(fill no)
			(layer "F.CrtYd")
		)
		(fp_rect
			(start -0.5 -0.25)
			(end 0.5 0.25)
			(stroke
				(width 0.15)
				(type solid)
			)
			(fill no)
			(layer "F.Fab")
		)
		(fp_text user "License: Apache-2.0"
			(at -0.95 5.169 180)
			(layer "F.Fab")
			(effects
				(font
					(size 0.7 0.7)
					(thickness 0.15)
				)
				(justify left bottom)
			)
		)
		(fp_text user "Author: Antmicro"
			(at -0.95 4.169 180)
			(layer "F.Fab")
			(effects
				(font
					(size 0.7 0.7)
					(thickness 0.15)
				)
				(justify left bottom)
			)
		)
		(fp_text user "${REFERENCE}"
			(at -0.95 3.168 180)
			(layer "F.Fab")
			(effects
				(font
					(size 0.7 0.7)
					(thickness 0.15)
				)
				(justify left bottom)
			)
		)
		(pad "1" smd roundrect
			(at -0.48 0 180)
			(size 0.59 0.64)
			(layers "F.Cu" "F.Mask" "F.Paste")
			(roundrect_rratio 0.25)
			(net 2 "+3V3")
			(pintype "passive")
		)
		(pad "2" smd roundrect
			(at 0.48 0 180)
			(size 0.59 0.64)
			(layers "F.Cu" "F.Mask" "F.Paste")
			(roundrect_rratio 0.25)
			(net 264 "Net-(U8-V_{IN})")
			(pintype "passive")
		)
	)
	(footprint "antmicro-footprints:R_0402_1005Metric"
		(layer "F.Cu")
		(at 122.03 110.65 180)
		(descr "Resistor SMD 0402")
		(tags "resistor SMD 0402")
		(property "Reference" "R93"
			(at 0.95 -0.39 0)
			(layer "F.SilkS")
			(effects
				(font
					(size 0.65 0.65)
					(thickness 0.15)
				)
				(justify right bottom)
			)
		)
		(property "Value" "R_2k2_0402"
			(at 0 1.4 0)
			(layer "F.Fab")
			(hide yes)
			(effects
				(font
					(size 0.7 0.7)
					(thickness 0.15)
				)
				(justify right bottom)
			)
		)
		(property "Datasheet" "https://www.bourns.com/docs/product-datasheets/cr.pdf"
			(at 0 0 180)
			(layer "F.Fab")
			(hide yes)
			(effects
				(font
					(size 1.27 1.27)
					(thickness 0.15)
				)
			)
		)
		(property "Description" "SMD Chip Resistor, 2.2 kohm, ± 1%, 62.5 mW, 0402 [1005 Metric], Thick Film, General Purpose"
			(at 0 0 180)
			(layer "F.Fab")
			(hide yes)
			(effects
				(font
					(size 1.27 1.27)
					(thickness 0.15)
				)
			)
		)
		(property "Author" "Antmicro"
			(at 244.06 221.3 0)
			(layer "F.Fab")
			(hide yes)
			(effects
				(font
					(size 1 1)
					(thickness 0.15)
				)
			)
		)
		(property "License" "Apache-2.0"
			(at 244.06 221.3 0)
			(layer "F.Fab")
			(hide yes)
			(effects
				(font
					(size 1 1)
					(thickness 0.15)
				)
			)
		)
		(property "MPN" "CR0402-FX-2201GLF"
			(at 244.06 221.3 0)
			(layer "F.Fab")
			(hide yes)
			(effects
				(font
					(size 1 1)
					(thickness 0.15)
				)
			)
		)
		(property "Manufacturer" "Bourns"
			(at 244.06 221.3 0)
			(layer "F.Fab")
			(hide yes)
			(effects
				(font
					(size 1 1)
					(thickness 0.15)
				)
			)
		)
		(property "Tolerance" "1%"
			(at 244.06 221.3 0)
			(layer "F.Fab")
			(hide yes)
			(effects
				(font
					(size 1 1)
					(thickness 0.15)
				)
			)
		)
		(property "Val" "2k2"
			(at 244.06 221.3 0)
			(layer "F.Fab")
			(hide yes)
			(effects
				(font
					(size 1 1)
					(thickness 0.15)
				)
			)
		)
		(sheetname "/FPGA/")
		(sheetfile "fpga.kicad_sch")
		(attr smd)
		(fp_rect
			(start -0.925 -0.47)
			(end 0.925 0.47)
			(stroke
				(width 0.05)
				(type default)
			)
			(fill no)
			(layer "F.CrtYd")
		)
		(fp_rect
			(start -0.5 -0.25)
			(end 0.5 0.25)
			(stroke
				(width 0.15)
				(type solid)
			)
			(fill no)
			(layer "F.Fab")
		)
		(fp_text user "License: Apache-2.0"
			(at -0.95 5.169 180)
			(layer "F.Fab")
			(effects
				(font
					(size 0.7 0.7)
					(thickness 0.15)
				)
				(justify left bottom)
			)
		)
		(fp_text user "Author: Antmicro"
			(at -0.95 4.169 180)
			(layer "F.Fab")
			(effects
				(font
					(size 0.7 0.7)
					(thickness 0.15)
				)
				(justify left bottom)
			)
		)
		(fp_text user "${REFERENCE}"
			(at -0.95 3.168 180)
			(layer "F.Fab")
			(effects
				(font
					(size 0.7 0.7)
					(thickness 0.15)
				)
				(justify left bottom)
			)
		)
		(pad "1" smd roundrect
			(at -0.48 0 180)
			(size 0.59 0.64)
			(layers "F.Cu" "F.Mask" "F.Paste")
			(roundrect_rratio 0.25)
			(net 245 "Net-(D6-A)")
			(pintype "passive")
		)
		(pad "2" smd roundrect
			(at 0.48 0 180)
			(size 0.59 0.64)
			(layers "F.Cu" "F.Mask" "F.Paste")
			(roundrect_rratio 0.25)
			(net 2 "+3V3")
			(pintype "passive")
		)
	)
	(footprint "antmicro-footprints:UQFN-16-1.8x2.6mm_P0.4mm_Texas_RSV0016A"
		(layer "F.Cu")
		(at 110.205 95.79 180)
		(descr "https://www.ti.com/lit/ds/symlink/sn74avch4t245-ep.pdf?ts=1679484181203&ref_url=https%253A%252F%252Fwww.ti.com%252Fproduct%252FSN74AVCH4T245-EP%253Futm_source%253Dgoogle%2526utm_medium%253Dcpc%2526utm_campaign%253Dasc-int-null-prodfolderdynamic-cpc-pf-google-wwe_int%2526utm_content%253Dprodfolddynamic%2526ds_k%253DDYNAMIC%2BSEARCH%2BADS%2526DCM%253Dyes%2526gclid%253DCjwKCAjwzuqgBhAcEiwAdj5dRvR_WgyvqqhLxMx8zfbFv2a6tg33JIMv01Bn4M1kA4JzW1nDDW7OzhoCRbkQAvD_BwE%2526gclsrc%253Daw.ds")
		(property "Reference" "U21"
			(at 1.125 1.6 180)
			(layer "F.SilkS")
			(effects
				(font
					(size 0.7 0.7)
					(thickness 0.15)
				)
				(justify left bottom)
			)
		)
		(property "Value" "TMUX1574RSVR"
			(at -1.25 2.5 180)
			(layer "F.Fab")
			(effects
				(font
					(size 0.7 0.7)
					(thickness 0.15)
				)
				(justify left bottom)
			)
		)
		(property "Datasheet" "https://www.ti.com/lit/ds/symlink/tmux1574.pdf?ts=1672927977241&ref_url=https%253A%252F%252Fwww.ti.com%252Fproduct%252FTMUX1574%253FHQS%253DTI-null-null-octopart-df-pf-xrefTI-wwe"
			(at 0 0 180)
			(layer "F.Fab")
			(hide yes)
			(effects
				(font
					(size 1.27 1.27)
					(thickness 0.15)
				)
			)
		)
		(property "Description" "Analogue switch"
			(at 0 0 180)
			(layer "F.Fab")
			(hide yes)
			(effects
				(font
					(size 1.27 1.27)
					(thickness 0.15)
				)
			)
		)
		(property "Author" "Antmicro"
			(at 220.41 191.58 0)
			(layer "F.Fab")
			(hide yes)
			(effects
				(font
					(size 1 1)
					(thickness 0.15)
				)
			)
		)
		(property "License" "Apache-2.0"
			(at 220.41 191.58 0)
			(layer "F.Fab")
			(hide yes)
			(effects
				(font
					(size 1 1)
					(thickness 0.15)
				)
			)
		)
		(property "MPN" "TMUX1574RSVR"
			(at 220.41 191.58 0)
			(layer "F.Fab")
			(hide yes)
			(effects
				(font
					(size 1 1)
					(thickness 0.15)
				)
			)
		)
		(property "Manufacturer" "Texas Instruments"
			(at 220.41 191.58 0)
			(layer "F.Fab")
			(hide yes)
			(effects
				(font
					(size 1 1)
					(thickness 0.15)
				)
			)
		)
		(sheetname "/FPGA/")
		(sheetfile "fpga.kicad_sch")
		(attr smd)
		(fp_line
			(start 0.9 0.8)
			(end 0.899 1.3)
			(stroke
				(width 0.15)
				(type solid)
			)
			(layer "F.SilkS")
		)
		(fp_line
			(start 0.9 -1.3)
			(end 0.9 -0.8005)
			(stroke
				(width 0.15)
				(type solid)
			)
			(layer "F.SilkS")
		)
		(fp_line
			(start 0.8 1.3)
			(end 0.899 1.3)
			(stroke
				(width 0.15)
				(type solid)
			)
			(layer "F.SilkS")
		)
		(fp_line
			(start 0.8 -1.3)
			(end 0.9 -1.3)
			(stroke
				(width 0.15)
				(type solid)
			)
			(layer "F.SilkS")
		)
		(fp_line
			(start -0.8 1.2995)
			(end -0.9 1.2995)
			(stroke
				(width 0.15)
				(type solid)
			)
			(layer "F.SilkS")
		)
		(fp_line
			(start -0.8 -1.3)
			(end -0.9 -1.3)
			(stroke
				(width 0.15)
				(type solid)
			)
			(layer "F.SilkS")
		)
		(fp_line
			(start -0.9 1.2995)
			(end -0.9 0.8)
			(stroke
				(width 0.15)
				(type solid)
			)
			(layer "F.SilkS")
		)
		(fp_rect
			(start -1.25 -1.65)
			(end 1.25 1.65)
			(stroke
				(width 0.05)
				(type solid)
			)
			(fill no)
			(layer "F.CrtYd")
		)
		(fp_line
			(start 0.9 1.3)
			(end 0.9 -1.301)
			(stroke
				(width 0.15)
				(type solid)
			)
			(layer "F.Fab")
		)
		(fp_line
			(start 0.9 1.3)
			(end -0.902 1.3)
			(stroke
				(width 0.15)
				(type solid)
			)
			(layer "F.Fab")
		)
		(fp_line
			(start 0.9 -1.301)
			(end -0.902 -1.301)
			(stroke
				(width 0.15)
				(type solid)
			)
			(layer "F.Fab")
		)
		(fp_line
			(start -0.902 1.3)
			(end -0.902 -1.301)
			(stroke
				(width 0.15)
				(type solid)
			)
			(layer "F.Fab")
		)
		(fp_text user "."
			(at -1.45 -0.75 180)
			(layer "F.SilkS")
			(effects
				(font
					(size 0.7 0.7)
					(thickness 0.15)
				)
				(justify left bottom)
			)
		)
		(pad "1" smd roundrect
			(at -0.75 -0.6 180)
			(size 0.7 0.2)
			(layers "F.Cu" "F.Mask" "F.Paste")
			(roundrect_rratio 0.2272727273)
			(net 32 "/FPGA/MOSI_SOFT")
			(pinfunction "S1B")
			(pintype "bidirectional")
		)
		(pad "2" smd roundrect
			(at -0.802 -0.202 180)
			(size 0.6 0.2)
			(layers "F.Cu" "F.Mask" "F.Paste")
			(roundrect_rratio 0.2272727273)
			(net 300 "Net-(U18-SI{slash}IO0)")
			(pinfunction "D1")
			(pintype "bidirectional")
		)
		(pad "3" smd roundrect
			(at -0.802 0.2 180)
			(size 0.6 0.2)
			(layers "F.Cu" "F.Mask" "F.Paste")
			(roundrect_rratio 0.2272727273)
			(net 38 "/FPGA/SPI_DQ1_MISO")
			(pinfunction "S2A")
			(pintype "bidirectional")
		)
		(pad "4" smd roundrect
			(at -0.802 0.598 180)
			(size 0.6 0.2)
			(layers "F.Cu" "F.Mask" "F.Paste")
			(roundrect_rratio 0.2272727273)
			(net 31 "/FPGA/MISO_SOFT")
			(pinfunction "S2B")
			(pintype "bidirectional")
		)
		(pad "5" smd roundrect
			(at -0.6 1.199 270)
			(size 0.6 0.2)
			(layers "F.Cu" "F.Mask" "F.Paste")
			(roundrect_rratio 0.2272727273)
			(net 301 "Net-(U18-SO{slash}IO1)")
			(pinfunction "D2")
			(pintype "bidirectional")
		)
		(pad "6" smd roundrect
			(at -0.202 1.199 270)
			(size 0.6 0.2)
			(layers "F.Cu" "F.Mask" "F.Paste")
			(roundrect_rratio 0.2272727273)
			(net 1 "GND")
			(pinfunction "GND")
			(pintype "power_in")
		)
		(pad "7" smd roundrect
			(at 0.2 1.199 270)
			(size 0.6 0.2)
			(layers "F.Cu" "F.Mask" "F.Paste")
			(roundrect_rratio 0.2272727273)
			(net 303 "Net-(U18-SCLK)")
			(pinfunction "D3")
			(pintype "bidirectional")
		)
		(pad "8" smd roundrect
			(at 0.598 1.199 270)
			(size 0.6 0.2)
			(layers "F.Cu" "F.Mask" "F.Paste")
			(roundrect_rratio 0.2272727273)
			(net 33 "/FPGA/SPI_CLK_SOFT")
			(pinfunction "S3B")
			(pintype "bidirectional")
		)
		(pad "9" smd roundrect
			(at 0.8 0.598 180)
			(size 0.6 0.2)
			(layers "F.Cu" "F.Mask" "F.Paste")
			(roundrect_rratio 0.2272727273)
			(net 39 "/FPGA/SPI_CLK")
			(pinfunction "S3A")
			(pintype "bidirectional")
		)
		(pad "10" smd roundrect
			(at 0.8 0.2 180)
			(size 0.6 0.2)
			(layers "F.Cu" "F.Mask" "F.Paste")
			(roundrect_rratio 0.2272727273)
			(net 324 "Net-(U21-D4)")
			(pinfunction "D4")
			(pintype "bidirectional")
		)
		(pad "11" smd roundrect
			(at 0.8 -0.202 180)
			(size 0.6 0.2)
			(layers "F.Cu" "F.Mask" "F.Paste")
			(roundrect_rratio 0.2272727273)
			(net 29 "/FPGA/~{FLASH_CS_SOFT}")
			(pinfunction "S4B")
			(pintype "bidirectional")
		)
		(pad "12" smd roundrect
			(at 0.8 -0.6 180)
			(size 0.6 0.2)
			(layers "F.Cu" "F.Mask" "F.Paste")
			(roundrect_rratio 0.2272727273)
			(net 41 "/FPGA/~{FLASH_CS}")
			(pinfunction "S4A")
			(pintype "bidirectional")
		)
		(pad "13" smd roundrect
			(at 0.598 -1.2 270)
			(size 0.6 0.2)
			(layers "F.Cu" "F.Mask" "F.Paste")
			(roundrect_rratio 0.2272727273)
			(net 1 "GND")
			(pinfunction "~{EN}")
			(pintype "input")
		)
		(pad "14" smd roundrect
			(at 0.2 -1.2 270)
			(size 0.6 0.2)
			(layers "F.Cu" "F.Mask" "F.Paste")
			(roundrect_rratio 0.2272727273)
			(net 2 "+3V3")
			(pinfunction "VDD")
			(pintype "power_in")
		)
		(pad "15" smd roundrect
			(at -0.202 -1.2 270)
			(size 0.6 0.2)
			(layers "F.Cu" "F.Mask" "F.Paste")
			(roundrect_rratio 0.2272727273)
			(net 376 "/FPGA/SEL")
			(pinfunction "SEL")
			(pintype "input")
		)
		(pad "16" smd roundrect
			(at -0.6 -1.2 270)
			(size 0.6 0.2)
			(layers "F.Cu" "F.Mask" "F.Paste")
			(roundrect_rratio 0.2272727273)
			(net 37 "/FPGA/SPI_DQ0_MOSI")
			(pinfunction "S1A")
			(pintype "bidirectional")
		)
	)
	(footprint "antmicro-footprints:PinHeader_2x5_P1.27mm_SMD"
		(layer "F.Cu")
		(at 89 119.7 180)
		(property "Reference" "J5"
			(at 3.67 2.26 0)
			(layer "F.SilkS")
			(effects
				(font
					(size 0.65 0.65)
					(thickness 0.15)
				)
				(justify right bottom)
			)
		)
		(property "Value" "PinHeader_2x5_P1.27mm_SMD"
			(at 0 4.2 0)
			(layer "F.Fab")
			(hide yes)
			(effects
				(font
					(size 0.7 0.7)
					(thickness 0.15)
				)
				(justify right bottom)
			)
		)
		(property "Datasheet" "https://eu.mouser.com/datasheet/2/527/ftsh_th-2854322.pdf"
			(at 0 0 180)
			(layer "F.Fab")
			(hide yes)
			(effects
				(font
					(size 1.27 1.27)
					(thickness 0.15)
				)
			)
		)
		(property "Description" "Pin Header, Board-to-Board, Wire-to-Board, 1.27 mm, 2 Rows, 10 Contacts, Surface Mount, FTSH"
			(at 0 0 180)
			(layer "F.Fab")
			(hide yes)
			(effects
				(font
					(size 1.27 1.27)
					(thickness 0.15)
				)
			)
		)
		(property "Author" "Antmicro"
			(at 178 239.4 0)
			(layer "F.Fab")
			(hide yes)
			(effects
				(font
					(size 1 1)
					(thickness 0.15)
				)
			)
		)
		(property "License" "Apache-2.0"
			(at 178 239.4 0)
			(layer "F.Fab")
			(hide yes)
			(effects
				(font
					(size 1 1)
					(thickness 0.15)
				)
			)
		)
		(property "MPN" "FTSH-105-01-F-DV"
			(at 178 239.4 0)
			(layer "F.Fab")
			(hide yes)
			(effects
				(font
					(size 1 1)
					(thickness 0.15)
				)
			)
		)
		(property "Manufacturer" "Samtec"
			(at 178 239.4 0)
			(layer "F.Fab")
			(hide yes)
			(effects
				(font
					(size 1 1)
					(thickness 0.15)
				)
			)
		)
		(sheetname "/Peripherals/")
		(sheetfile "peripherals.kicad_sch")
		(attr smd)
		(fp_line
			(start 3.257 1.8)
			(end 3.257 1.499)
			(stroke
				(width 0.15)
				(type solid)
			)
			(layer "F.SilkS")
		)
		(fp_line
			(start 3.257 -1.801)
			(end 3.257 -1.5)
			(stroke
				(width 0.15)
				(type solid)
			)
			(layer "F.SilkS")
		)
		(fp_line
			(start 2.959 1.8)
			(end 3.257 1.8)
			(stroke
				(width 0.15)
				(type solid)
			)
			(layer "F.SilkS")
		)
		(fp_line
			(start 2.959 -1.801)
			(end 3.257 -1.801)
			(stroke
				(width 0.15)
				(type solid)
			)
			(layer "F.SilkS")
		)
		(fp_line
			(start -3.04 1.8)
			(end -3.34 1.8)
			(stroke
				(width 0.15)
				(type solid)
			)
			(layer "F.SilkS")
		)
		(fp_line
			(start -3.04 -1.801)
			(end -3.34 -1.801)
			(stroke
				(width 0.15)
				(type solid)
			)
			(layer "F.SilkS")
		)
		(fp_line
			(start -3.34 1.8)
			(end -3.34 1.499)
			(stroke
				(width 0.15)
				(type solid)
			)
			(layer "F.SilkS")
		)
		(fp_line
			(start -3.34 -1.801)
			(end -3.34 -1.5)
			(stroke
				(width 0.15)
				(type solid)
			)
			(layer "F.SilkS")
		)
		(fp_rect
			(start -3.476 -3.25)
			(end 3.373 3.249)
			(stroke
				(width 0.05)
				(type solid)
			)
			(fill no)
			(layer "F.CrtYd")
		)
		(fp_line
			(start 3.132 1.715)
			(end -3.215 1.715)
			(stroke
				(width 0.15)
				(type solid)
			)
			(layer "F.Fab")
		)
		(fp_line
			(start 3.132 -1.716)
			(end 3.132 1.715)
			(stroke
				(width 0.15)
				(type solid)
			)
			(layer "F.Fab")
		)
		(fp_line
			(start 3.132 -1.716)
			(end -3.215 -1.716)
			(stroke
				(width 0.15)
				(type solid)
			)
			(layer "F.Fab")
		)
		(fp_line
			(start -3.215 -1.716)
			(end -3.215 1.715)
			(stroke
				(width 0.15)
				(type solid)
			)
			(layer "F.Fab")
		)
		(pad "1" smd rect
			(at -2.581 1.949 180)
			(size 0.76 2.4)
			(layers "F.Cu" "F.Mask" "F.Paste")
			(net 20 "AUDIO_ACLK")
			(pintype "passive")
		)
		(pad "2" smd rect
			(at -2.581 -1.95 180)
			(size 0.76 2.4)
			(layers "F.Cu" "F.Mask" "F.Paste")
			(net 20 "AUDIO_ACLK")
			(pintype "passive")
		)
		(pad "3" smd rect
			(at -1.311 1.949 180)
			(size 0.76 2.4)
			(layers "F.Cu" "F.Mask" "F.Paste")
			(net 21 "AUDIO_WCLK")
			(pintype "passive")
		)
		(pad "4" smd rect
			(at -1.311 -1.95 180)
			(size 0.76 2.4)
			(layers "F.Cu" "F.Mask" "F.Paste")
			(net 21 "AUDIO_WCLK")
			(pintype "passive")
		)
		(pad "5" smd rect
			(at -0.042 1.949 180)
			(size 0.76 2.4)
			(layers "F.Cu" "F.Mask" "F.Paste")
			(net 22 "AUDIO_OUT_CH1_2")
			(pintype "passive")
		)
		(pad "6" smd rect
			(at -0.042 -1.95 180)
			(size 0.76 2.4)
			(layers "F.Cu" "F.Mask" "F.Paste")
			(net 23 "AUDIO_OUT_CH5_6")
			(pintype "passive")
		)
		(pad "7" smd rect
			(at 1.227 1.949 180)
			(size 0.76 2.4)
			(layers "F.Cu" "F.Mask" "F.Paste")
			(net 24 "AUDIO_OUT_CH3_4")
			(pintype "passive")
		)
		(pad "8" smd rect
			(at 1.227 -1.95 180)
			(size 0.76 2.4)
			(layers "F.Cu" "F.Mask" "F.Paste")
			(net 25 "AUDIO_OUT_CH7_8")
			(pintype "passive")
		)
		(pad "9" smd rect
			(at 2.499 1.949 180)
			(size 0.76 2.4)
			(layers "F.Cu" "F.Mask" "F.Paste")
			(net 1 "GND")
			(pintype "passive")
		)
		(pad "10" smd rect
			(at 2.499 -1.95 180)
			(size 0.76 2.4)
			(layers "F.Cu" "F.Mask" "F.Paste")
			(net 26 "AUDIO_MCLK")
			(pintype "passive")
		)
	)
	(footprint "antmicro-footprints:C_0603_1608Metric"
		(layer "F.Cu")
		(at 144.39 63.89 180)
		(descr "Capacitor SMD 0603")
		(tags "capacitor 0603")
		(property "Reference" "C21"
			(at 5.36 -0.45 0)
			(layer "F.SilkS")
			(effects
				(font
					(size 0.65 0.65)
					(thickness 0.15)
				)
				(justify right bottom)
			)
		)
		(property "Value" "C_22u_0603"
			(at 0 1.6 0)
			(layer "F.Fab")
			(hide yes)
			(effects
				(font
					(size 0.7 0.7)
					(thickness 0.15)
				)
				(justify right bottom)
			)
		)
		(property "Datasheet" "https://www.murata.com/products/productdetail?partno=GRM188R60J226MEA0%23"
			(at 0 0 180)
			(layer "F.Fab")
			(hide yes)
			(effects
				(font
					(size 1.27 1.27)
					(thickness 0.15)
				)
			)
		)
		(property "Description" "SMD Multilayer Ceramic Capacitor, 22 µF, 6.3 V, 0603 [1608 Metric], ± 20%, X5R, GRM Series"
			(at 0 0 180)
			(layer "F.Fab")
			(hide yes)
			(effects
				(font
					(size 1.27 1.27)
					(thickness 0.15)
				)
			)
		)
		(property "Author" "Antmicro"
			(at 288.78 127.78 0)
			(layer "F.Fab")
			(hide yes)
			(effects
				(font
					(size 1 1)
					(thickness 0.15)
				)
			)
		)
		(property "Dielectric" ""
			(at 288.78 127.78 0)
			(layer "F.Fab")
			(hide yes)
			(effects
				(font
					(size 1 1)
					(thickness 0.15)
				)
			)
		)
		(property "License" "Apache-2.0"
			(at 288.78 127.78 0)
			(layer "F.Fab")
			(hide yes)
			(effects
				(font
					(size 1 1)
					(thickness 0.15)
				)
			)
		)
		(property "MPN" "GRM188R60J226MEA0D"
			(at 288.78 127.78 0)
			(layer "F.Fab")
			(hide yes)
			(effects
				(font
					(size 1 1)
					(thickness 0.15)
				)
			)
		)
		(property "Manufacturer" "Murata"
			(at 288.78 127.78 0)
			(layer "F.Fab")
			(hide yes)
			(effects
				(font
					(size 1 1)
					(thickness 0.15)
				)
			)
		)
		(property "Val" "22u"
			(at 288.78 127.78 0)
			(layer "F.Fab")
			(hide yes)
			(effects
				(font
					(size 1 1)
					(thickness 0.15)
				)
			)
		)
		(property "Voltage" ""
			(at 288.78 127.78 0)
			(layer "F.Fab")
			(hide yes)
			(effects
				(font
					(size 1 1)
					(thickness 0.15)
				)
			)
		)
		(sheetname "/Power Supply/")
		(sheetfile "supply.kicad_sch")
		(attr smd)
		(fp_line
			(start -0.15 0.4)
			(end 0.15 0.4)
			(stroke
				(width 0.15)
				(type solid)
			)
			(layer "F.SilkS")
		)
		(fp_line
			(start -0.15 -0.4)
			(end 0.15 -0.4)
			(stroke
				(width 0.15)
				(type solid)
			)
			(layer "F.SilkS")
		)
		(fp_rect
			(start -1.25 -0.65)
			(end 1.25 0.65)
			(stroke
				(width 0.05)
				(type solid)
			)
			(fill no)
			(layer "F.CrtYd")
		)
		(fp_rect
			(start -0.8 -0.4)
			(end 0.8 0.4)
			(stroke
				(width 0.15)
				(type solid)
			)
			(fill no)
			(layer "F.Fab")
		)
		(fp_text user "License: Apache-2.0"
			(at -1.682 5.895 180)
			(layer "F.Fab")
			(effects
				(font
					(size 0.7 0.7)
					(thickness 0.15)
				)
				(justify left bottom)
			)
		)
		(fp_text user "Author: Antmicro"
			(at -1.682 4.894 180)
			(layer "F.Fab")
			(effects
				(font
					(size 0.7 0.7)
					(thickness 0.15)
				)
				(justify left bottom)
			)
		)
		(fp_text user "${REFERENCE}"
			(at -1.682 3.895 180)
			(layer "F.Fab")
			(effects
				(font
					(size 0.7 0.7)
					(thickness 0.15)
				)
				(justify left bottom)
			)
		)
		(pad "1" smd roundrect
			(at -0.7 0 180)
			(size 0.8 1)
			(layers "F.Cu" "F.Mask" "F.Paste")
			(roundrect_rratio 0.2)
			(net 1 "GND")
			(pintype "passive")
		)
		(pad "2" smd roundrect
			(at 0.7 0 180)
			(size 0.8 1)
			(layers "F.Cu" "F.Mask" "F.Paste")
			(roundrect_rratio 0.2)
			(net 274 "/Power Supply/1V5_OUT")
			(pintype "passive")
		)
	)
	(footprint "antmicro-footprints:R_0402_1005Metric"
		(layer "F.Cu")
		(at 92.6 104.85)
		(descr "Resistor SMD 0402")
		(tags "resistor SMD 0402")
		(property "Reference" "R57"
			(at 0.93 0.39 0)
			(layer "F.SilkS")
			(effects
				(font
					(size 0.65 0.65)
					(thickness 0.15)
				)
				(justify left bottom)
			)
		)
		(property "Value" "R_750R_0402"
			(at 0 1.4 0)
			(layer "F.Fab")
			(hide yes)
			(effects
				(font
					(size 0.7 0.7)
					(thickness 0.15)
				)
				(justify left bottom)
			)
		)
		(property "Datasheet" "https://www.bourns.com/docs/product-datasheets/cr.pdf"
			(at 0 0 0)
			(layer "F.Fab")
			(hide yes)
			(effects
				(font
					(size 1.27 1.27)
					(thickness 0.15)
				)
			)
		)
		(property "Description" "SMD Chip Resistor, 750 ohm, ± 1%, 63 mW, 0402 [1005 Metric], Thick Film, General Purpose"
			(at 0 0 0)
			(layer "F.Fab")
			(hide yes)
			(effects
				(font
					(size 1.27 1.27)
					(thickness 0.15)
				)
			)
		)
		(property "Author" "Antmicro"
			(at 0 0 0)
			(layer "F.Fab")
			(hide yes)
			(effects
				(font
					(size 1 1)
					(thickness 0.15)
				)
			)
		)
		(property "License" "Apache-2.0"
			(at 0 0 0)
			(layer "F.Fab")
			(hide yes)
			(effects
				(font
					(size 1 1)
					(thickness 0.15)
				)
			)
		)
		(property "MPN" "CR0402-FX-7500GLF"
			(at 0 0 0)
			(layer "F.Fab")
			(hide yes)
			(effects
				(font
					(size 1 1)
					(thickness 0.15)
				)
			)
		)
		(property "Manufacturer" "Bourns"
			(at 0 0 0)
			(layer "F.Fab")
			(hide yes)
			(effects
				(font
					(size 1 1)
					(thickness 0.15)
				)
			)
		)
		(property "Tolerance" "1%"
			(at 0 0 0)
			(layer "F.Fab")
			(hide yes)
			(effects
				(font
					(size 1 1)
					(thickness 0.15)
				)
			)
		)
		(property "Val" "750R"
			(at 0 0 0)
			(layer "F.Fab")
			(hide yes)
			(effects
				(font
					(size 1 1)
					(thickness 0.15)
				)
			)
		)
		(sheetname "/SDI/")
		(sheetfile "sdi.kicad_sch")
		(attr smd)
		(fp_rect
			(start -0.925 -0.47)
			(end 0.925 0.47)
			(stroke
				(width 0.05)
				(type default)
			)
			(fill no)
			(layer "F.CrtYd")
		)
		(fp_rect
			(start -0.5 -0.25)
			(end 0.5 0.25)
			(stroke
				(width 0.15)
				(type solid)
			)
			(fill no)
			(layer "F.Fab")
		)
		(fp_text user "${REFERENCE}"
			(at -0.95 3.168 0)
			(layer "F.Fab")
			(effects
				(font
					(size 0.7 0.7)
					(thickness 0.15)
				)
				(justify left bottom)
			)
		)
		(fp_text user "Author: Antmicro"
			(at -0.95 4.169 0)
			(layer "F.Fab")
			(effects
				(font
					(size 0.7 0.7)
					(thickness 0.15)
				)
				(justify left bottom)
			)
		)
		(fp_text user "License: Apache-2.0"
			(at -0.95 5.169 0)
			(layer "F.Fab")
			(effects
				(font
					(size 0.7 0.7)
					(thickness 0.15)
				)
				(justify left bottom)
			)
		)
		(pad "1" smd roundrect
			(at -0.48 0)
			(size 0.59 0.64)
			(layers "F.Cu" "F.Mask" "F.Paste")
			(roundrect_rratio 0.25)
			(net 289 "Net-(U16-RSET)")
			(pintype "passive")
		)
		(pad "2" smd roundrect
			(at 0.48 0)
			(size 0.59 0.64)
			(layers "F.Cu" "F.Mask" "F.Paste")
			(roundrect_rratio 0.25)
			(net 2 "+3V3")
			(pintype "passive")
		)
	)
	(footprint "antmicro-footprints:C_0402_1005Metric"
		(layer "F.Cu")
		(at 95.71 89.21 180)
		(descr "Capacitor SMD 0402")
		(tags "capacitor SMD 0402")
		(property "Reference" "C52"
			(at 1.08 -1.4 180)
			(layer "F.SilkS")
			(effects
				(font
					(size 0.65 0.65)
					(thickness 0.15)
				)
				(justify left bottom)
			)
		)
		(property "Value" "C_33p_0402"
			(at 0 1.4 180)
			(layer "F.Fab")
			(hide yes)
			(effects
				(font
					(size 0.7 0.7)
					(thickness 0.15)
				)
				(justify left bottom)
			)
		)
		(property "Datasheet" "https://spicat.kyocera-avx.com/product/mlcc/chartview/04025A330FAT2A/"
			(at 0 0 180)
			(layer "F.Fab")
			(hide yes)
			(effects
				(font
					(size 1.27 1.27)
					(thickness 0.15)
				)
			)
		)
		(property "Description" "SMD Multilayer Ceramic Capacitor, 33 pF, 50 V, 0402 [1005 Metric], ± 5%, C0G / NP0, MC"
			(at 0 0 180)
			(layer "F.Fab")
			(hide yes)
			(effects
				(font
					(size 1.27 1.27)
					(thickness 0.15)
				)
			)
		)
		(property "Author" "Antmicro"
			(at 191.42 178.28 0)
			(layer "F.Fab")
			(hide yes)
			(effects
				(font
					(size 1 1)
					(thickness 0.15)
				)
			)
		)
		(property "Dielectric" ""
			(at 191.42 178.28 0)
			(layer "F.Fab")
			(hide yes)
			(effects
				(font
					(size 1 1)
					(thickness 0.15)
				)
			)
		)
		(property "License" "Apache-2.0"
			(at 191.42 178.28 0)
			(layer "F.Fab")
			(hide yes)
			(effects
				(font
					(size 1 1)
					(thickness 0.15)
				)
			)
		)
		(property "MPN" "04025A330FAT2A"
			(at 191.42 178.28 0)
			(layer "F.Fab")
			(hide yes)
			(effects
				(font
					(size 1 1)
					(thickness 0.15)
				)
			)
		)
		(property "Manufacturer" "KYOCERA AVX"
			(at 191.42 178.28 0)
			(layer "F.Fab")
			(hide yes)
			(effects
				(font
					(size 1 1)
					(thickness 0.15)
				)
			)
		)
		(property "Val" "33p"
			(at 191.42 178.28 0)
			(layer "F.Fab")
			(hide yes)
			(effects
				(font
					(size 1 1)
					(thickness 0.15)
				)
			)
		)
		(property "Voltage" ""
			(at 191.42 178.28 0)
			(layer "F.Fab")
			(hide yes)
			(effects
				(font
					(size 1 1)
					(thickness 0.15)
				)
			)
		)
		(sheetname "/SDI/")
		(sheetfile "sdi.kicad_sch")
		(attr smd)
		(fp_rect
			(start -0.925 -0.47)
			(end 0.925 0.47)
			(stroke
				(width 0.05)
				(type default)
			)
			(fill no)
			(layer "F.CrtYd")
		)
		(fp_line
			(start 0.504 0.248)
			(end -0.494 0.248)
			(stroke
				(width 0.15)
				(type solid)
			)
			(layer "F.Fab")
		)
		(fp_line
			(start 0.504 -0.25)
			(end 0.504 0.248)
			(stroke
				(width 0.15)
				(type solid)
			)
			(layer "F.Fab")
		)
		(fp_line
			(start -0.494 0.248)
			(end -0.494 -0.25)
			(stroke
				(width 0.15)
				(type solid)
			)
			(layer "F.Fab")
		)
		(fp_line
			(start -0.494 -0.25)
			(end 0.504 -0.25)
			(stroke
				(width 0.15)
				(type solid)
			)
			(layer "F.Fab")
		)
		(fp_text user "Author: Antmicro"
			(at -0.939 3.399 180)
			(layer "F.Fab")
			(effects
				(font
					(size 0.7 0.7)
					(thickness 0.15)
				)
				(justify left bottom)
			)
		)
		(fp_text user "${REFERENCE}"
			(at -0.939 4.599 180)
			(layer "F.Fab")
			(effects
				(font
					(size 0.7 0.7)
					(thickness 0.15)
				)
				(justify left bottom)
			)
		)
		(fp_text user "License: Apache-2.0"
			(at -0.939 5.799 180)
			(layer "F.Fab")
			(effects
				(font
					(size 0.7 0.7)
					(thickness 0.15)
				)
				(justify left bottom)
			)
		)
		(pad "1" smd roundrect
			(at -0.48 0 180)
			(size 0.59 0.64)
			(layers "F.Cu" "F.Mask" "F.Paste")
			(roundrect_rratio 0.25)
			(net 1 "GND")
			(pintype "passive")
		)
		(pad "2" smd roundrect
			(at 0.48 0 180)
			(size 0.59 0.64)
			(layers "F.Cu" "F.Mask" "F.Paste")
			(roundrect_rratio 0.25)
			(net 45 "/SDI/XTAL1")
			(pintype "passive")
		)
	)
	(footprint "antmicro-footprints:R_0402_1005Metric"
		(layer "F.Cu")
		(at 142.19 103.95 -90)
		(descr "Resistor SMD 0402")
		(tags "resistor SMD 0402")
		(property "Reference" "R31"
			(at -0.01 -1.44 270)
			(layer "F.SilkS")
			(effects
				(font
					(size 0.65 0.65)
					(thickness 0.15)
				)
				(justify left bottom)
			)
		)
		(property "Value" "R_3k01_0402"
			(at 0 1.4 270)
			(layer "F.Fab")
			(hide yes)
			(effects
				(font
					(size 0.7 0.7)
					(thickness 0.15)
				)
				(justify left bottom)
			)
		)
		(property "Datasheet" "https://www.bourns.com/docs/product-datasheets/cr.pdf"
			(at 0 0 270)
			(layer "F.Fab")
			(hide yes)
			(effects
				(font
					(size 1.27 1.27)
					(thickness 0.15)
				)
			)
		)
		(property "Description" "SMD Chip Resistor, 3.01 kohm, ± 1%, 62.5 mW, 0402 [1005 Metric], Thick Film, General Purpose"
			(at 0 0 270)
			(layer "F.Fab")
			(hide yes)
			(effects
				(font
					(size 1.27 1.27)
					(thickness 0.15)
				)
			)
		)
		(property "Author" "Antmicro"
			(at 38.24 246.14 0)
			(layer "F.Fab")
			(hide yes)
			(effects
				(font
					(size 1 1)
					(thickness 0.15)
				)
			)
		)
		(property "License" "Apache-2.0"
			(at 38.24 246.14 0)
			(layer "F.Fab")
			(hide yes)
			(effects
				(font
					(size 1 1)
					(thickness 0.15)
				)
			)
		)
		(property "MPN" "CR0402-FX-3011GLF"
			(at 38.24 246.14 0)
			(layer "F.Fab")
			(hide yes)
			(effects
				(font
					(size 1 1)
					(thickness 0.15)
				)
			)
		)
		(property "Manufacturer" "Bourns"
			(at 38.24 246.14 0)
			(layer "F.Fab")
			(hide yes)
			(effects
				(font
					(size 1 1)
					(thickness 0.15)
				)
			)
		)
		(property "Tolerance" "1%"
			(at 38.24 246.14 0)
			(layer "F.Fab")
			(hide yes)
			(effects
				(font
					(size 1 1)
					(thickness 0.15)
				)
			)
		)
		(property "Val" "3k01"
			(at 38.24 246.14 0)
			(layer "F.Fab")
			(hide yes)
			(effects
				(font
					(size 1 1)
					(thickness 0.15)
				)
			)
		)
		(sheetname "/Power Supply/")
		(sheetfile "supply.kicad_sch")
		(attr smd)
		(fp_rect
			(start -0.925 -0.47)
			(end 0.925 0.47)
			(stroke
				(width 0.05)
				(type default)
			)
			(fill no)
			(layer "F.CrtYd")
		)
		(fp_rect
			(start -0.5 -0.25)
			(end 0.5 0.25)
			(stroke
				(width 0.15)
				(type solid)
			)
			(fill no)
			(layer "F.Fab")
		)
		(fp_text user "License: Apache-2.0"
			(at -0.95 5.169 270)
			(layer "F.Fab")
			(effects
				(font
					(size 0.7 0.7)
					(thickness 0.15)
				)
				(justify left bottom)
			)
		)
		(fp_text user "Author: Antmicro"
			(at -0.95 4.169 270)
			(layer "F.Fab")
			(effects
				(font
					(size 0.7 0.7)
					(thickness 0.15)
				)
				(justify left bottom)
			)
		)
		(fp_text user "${REFERENCE}"
			(at -0.95 3.168 270)
			(layer "F.Fab")
			(effects
				(font
					(size 0.7 0.7)
					(thickness 0.15)
				)
				(justify left bottom)
			)
		)
		(pad "1" smd roundrect
			(at -0.48 0 270)
			(size 0.59 0.64)
			(layers "F.Cu" "F.Mask" "F.Paste")
			(roundrect_rratio 0.25)
			(net 280 "Net-(U8-ADJ)")
			(pintype "passive")
		)
		(pad "2" smd roundrect
			(at 0.48 0 270)
			(size 0.59 0.64)
			(layers "F.Cu" "F.Mask" "F.Paste")
			(roundrect_rratio 0.25)
			(net 272 "Net-(U8-V_{OUT})")
			(pintype "passive")
		)
	)
	(footprint "antmicro-footprints:R_0402_1005Metric"
		(layer "F.Cu")
		(at 122.03 115.15)
		(descr "Resistor SMD 0402")
		(tags "resistor SMD 0402")
		(property "Reference" "R77"
			(at -3.9 0.29 0)
			(layer "F.SilkS")
			(effects
				(font
					(size 0.65 0.65)
					(thickness 0.15)
				)
				(justify left bottom)
			)
		)
		(property "Value" "R_0R_0402"
			(at 0 1.4 0)
			(layer "F.Fab")
			(hide yes)
			(effects
				(font
					(size 0.7 0.7)
					(thickness 0.15)
				)
				(justify left bottom)
			)
		)
		(property "Datasheet" "https://industrial.panasonic.com/cdbs/www-data/pdf/RDA0000/AOA0000C301.pdf"
			(at 0 0 0)
			(layer "F.Fab")
			(hide yes)
			(effects
				(font
					(size 1.27 1.27)
					(thickness 0.15)
				)
			)
		)
		(property "Description" "SMD Chip Resistor, Jumper, 0 ohm, 100 mW, 0402 [1005 Metric], Thick Film, General Purpose"
			(at 0 0 0)
			(layer "F.Fab")
			(hide yes)
			(effects
				(font
					(size 1.27 1.27)
					(thickness 0.15)
				)
			)
		)
		(property "Author" "Antmicro"
			(at 0 0 0)
			(layer "F.Fab")
			(hide yes)
			(effects
				(font
					(size 1 1)
					(thickness 0.15)
				)
			)
		)
		(property "Current" "1A"
			(at 0 0 0)
			(layer "F.Fab")
			(hide yes)
			(effects
				(font
					(size 1 1)
					(thickness 0.15)
				)
			)
		)
		(property "License" "Apache-2.0"
			(at 0 0 0)
			(layer "F.Fab")
			(hide yes)
			(effects
				(font
					(size 1 1)
					(thickness 0.15)
				)
			)
		)
		(property "MPN" "ERJ2GE0R00X"
			(at 0 0 0)
			(layer "F.Fab")
			(hide yes)
			(effects
				(font
					(size 1 1)
					(thickness 0.15)
				)
			)
		)
		(property "Manufacturer" "Panasonic"
			(at 0 0 0)
			(layer "F.Fab")
			(hide yes)
			(effects
				(font
					(size 1 1)
					(thickness 0.15)
				)
			)
		)
		(property "Tolerance" "~"
			(at 0 0 0)
			(layer "F.Fab")
			(hide yes)
			(effects
				(font
					(size 1 1)
					(thickness 0.15)
				)
			)
		)
		(property "Val" "0R"
			(at 0 0 0)
			(layer "F.Fab")
			(hide yes)
			(effects
				(font
					(size 1 1)
					(thickness 0.15)
				)
			)
		)
		(sheetname "/FPGA/")
		(sheetfile "fpga.kicad_sch")
		(attr smd)
		(fp_rect
			(start -0.925 -0.47)
			(end 0.925 0.47)
			(stroke
				(width 0.05)
				(type default)
			)
			(fill no)
			(layer "F.CrtYd")
		)
		(fp_rect
			(start -0.5 -0.25)
			(end 0.5 0.25)
			(stroke
				(width 0.15)
				(type solid)
			)
			(fill no)
			(layer "F.Fab")
		)
		(fp_text user "License: Apache-2.0"
			(at -0.95 5.169 0)
			(layer "F.Fab")
			(effects
				(font
					(size 0.7 0.7)
					(thickness 0.15)
				)
				(justify left bottom)
			)
		)
		(fp_text user "Author: Antmicro"
			(at -0.95 4.169 0)
			(layer "F.Fab")
			(effects
				(font
					(size 0.7 0.7)
					(thickness 0.15)
				)
				(justify left bottom)
			)
		)
		(fp_text user "${REFERENCE}"
			(at -0.95 3.168 0)
			(layer "F.Fab")
			(effects
				(font
					(size 0.7 0.7)
					(thickness 0.15)
				)
				(justify left bottom)
			)
		)
		(pad "1" smd roundrect
			(at -0.48 0)
			(size 0.59 0.64)
			(layers "F.Cu" "F.Mask" "F.Paste")
			(roundrect_rratio 0.25)
			(net 40 "/FPGA/DONE")
			(pintype "passive")
		)
		(pad "2" smd roundrect
			(at 0.48 0)
			(size 0.59 0.64)
			(layers "F.Cu" "F.Mask" "F.Paste")
			(roundrect_rratio 0.25)
			(net 363 "/FPGA/DONE_SOFT")
			(pintype "passive")
		)
	)
	(footprint "antmicro-footprints:R_0402_1005Metric"
		(layer "F.Cu")
		(at 144.49 111.2 90)
		(descr "Resistor SMD 0402")
		(tags "resistor SMD 0402")
		(property "Reference" "R28"
			(at 0.86 0.34 90)
			(layer "F.SilkS")
			(effects
				(font
					(size 0.65 0.65)
					(thickness 0.15)
				)
				(justify left bottom)
			)
		)
		(property "Value" "R_0R_0402"
			(at 0 1.4 90)
			(layer "F.Fab")
			(hide yes)
			(effects
				(font
					(size 0.7 0.7)
					(thickness 0.15)
				)
				(justify left bottom)
			)
		)
		(property "Datasheet" "https://industrial.panasonic.com/cdbs/www-data/pdf/RDA0000/AOA0000C301.pdf"
			(at 0 0 90)
			(layer "F.Fab")
			(hide yes)
			(effects
				(font
					(size 1.27 1.27)
					(thickness 0.15)
				)
			)
		)
		(property "Description" "SMD Chip Resistor, Jumper, 0 ohm, 100 mW, 0402 [1005 Metric], Thick Film, General Purpose"
			(at 0 0 90)
			(layer "F.Fab")
			(hide yes)
			(effects
				(font
					(size 1.27 1.27)
					(thickness 0.15)
				)
			)
		)
		(property "Author" "Antmicro"
			(at 255.69 -33.29 0)
			(layer "F.Fab")
			(hide yes)
			(effects
				(font
					(size 1 1)
					(thickness 0.15)
				)
			)
		)
		(property "Current" "1A"
			(at 255.69 -33.29 0)
			(layer "F.Fab")
			(hide yes)
			(effects
				(font
					(size 1 1)
					(thickness 0.15)
				)
			)
		)
		(property "License" "Apache-2.0"
			(at 255.69 -33.29 0)
			(layer "F.Fab")
			(hide yes)
			(effects
				(font
					(size 1 1)
					(thickness 0.15)
				)
			)
		)
		(property "MPN" "ERJ2GE0R00X"
			(at 255.69 -33.29 0)
			(layer "F.Fab")
			(hide yes)
			(effects
				(font
					(size 1 1)
					(thickness 0.15)
				)
			)
		)
		(property "Manufacturer" "Panasonic"
			(at 255.69 -33.29 0)
			(layer "F.Fab")
			(hide yes)
			(effects
				(font
					(size 1 1)
					(thickness 0.15)
				)
			)
		)
		(property "Tolerance" "~"
			(at 255.69 -33.29 0)
			(layer "F.Fab")
			(hide yes)
			(effects
				(font
					(size 1 1)
					(thickness 0.15)
				)
			)
		)
		(property "Val" "0R"
			(at 255.69 -33.29 0)
			(layer "F.Fab")
			(hide yes)
			(effects
				(font
					(size 1 1)
					(thickness 0.15)
				)
			)
		)
		(sheetname "/Power Supply/")
		(sheetfile "supply.kicad_sch")
		(attr smd)
		(fp_rect
			(start -0.925 -0.47)
			(end 0.925 0.47)
			(stroke
				(width 0.05)
				(type default)
			)
			(fill no)
			(layer "F.CrtYd")
		)
		(fp_rect
			(start -0.5 -0.25)
			(end 0.5 0.25)
			(stroke
				(width 0.15)
				(type solid)
			)
			(fill no)
			(layer "F.Fab")
		)
		(fp_text user "${REFERENCE}"
			(at -0.95 3.168 90)
			(layer "F.Fab")
			(effects
				(font
					(size 0.7 0.7)
					(thickness 0.15)
				)
				(justify left bottom)
			)
		)
		(fp_text user "Author: Antmicro"
			(at -0.95 4.169 90)
			(layer "F.Fab")
			(effects
				(font
					(size 0.7 0.7)
					(thickness 0.15)
				)
				(justify left bottom)
			)
		)
		(fp_text user "License: Apache-2.0"
			(at -0.95 5.169 90)
			(layer "F.Fab")
			(effects
				(font
					(size 0.7 0.7)
					(thickness 0.15)
				)
				(justify left bottom)
			)
		)
		(pad "1" smd roundrect
			(at -0.48 0 90)
			(size 0.59 0.64)
			(layers "F.Cu" "F.Mask" "F.Paste")
			(roundrect_rratio 0.25)
			(net 266 "Net-(U10-V_{IN})")
			(pintype "passive")
		)
		(pad "2" smd roundrect
			(at 0.48 0 90)
			(size 0.59 0.64)
			(layers "F.Cu" "F.Mask" "F.Paste")
			(roundrect_rratio 0.25)
			(net 271 "Net-(U10-EN)")
			(pintype "passive")
		)
	)
	(footprint "antmicro-footprints:LED_0603_1608Metric_G"
		(layer "F.Cu")
		(at 108.75 73.4 90)
		(descr "LED SMD 0603 Green")
		(tags "LED SMD 0603 Green")
		(property "Reference" "D8"
			(at -2.94 -0.32 90)
			(layer "F.SilkS")
			(effects
				(font
					(size 0.65 0.65)
					(thickness 0.15)
				)
				(justify left top)
			)
		)
		(property "Value" "LED_G_0603_LTST-C190GKT"
			(at 0 1.6 90)
			(layer "F.Fab")
			(hide yes)
			(effects
				(font
					(size 0.7 0.7)
					(thickness 0.15)
				)
				(justify left top)
			)
		)
		(property "Datasheet" "https://media.digikey.com/pdf/Data%20Sheets/Lite-On%20PDFs/LTST-C190GKT.pdf"
			(at 0 0 90)
			(layer "F.Fab")
			(hide yes)
			(effects
				(font
					(size 1.27 1.27)
					(thickness 0.15)
				)
			)
		)
		(property "Description" "LED, Green, SMD, 0603, 20 mA, 2.1 V, 569 nm"
			(at 0 0 90)
			(layer "F.Fab")
			(hide yes)
			(effects
				(font
					(size 1.27 1.27)
					(thickness 0.15)
				)
			)
		)
		(property "Author" "Antmicro"
			(at 35.35 182.15 0)
			(layer "F.Fab")
			(hide yes)
			(effects
				(font
					(size 1 1)
					(thickness 0.15)
				)
			)
		)
		(property "License" "Apache-2.0"
			(at 35.35 182.15 0)
			(layer "F.Fab")
			(hide yes)
			(effects
				(font
					(size 1 1)
					(thickness 0.15)
				)
			)
		)
		(property "MPN" "LTST-C190GKT"
			(at 35.35 182.15 0)
			(layer "F.Fab")
			(hide yes)
			(effects
				(font
					(size 1 1)
					(thickness 0.15)
				)
			)
		)
		(property "Manufacturer" "Lite-On"
			(at 35.35 182.15 0)
			(layer "F.Fab")
			(hide yes)
			(effects
				(font
					(size 1 1)
					(thickness 0.15)
				)
			)
		)
		(property "Color" "Green"
			(at 0 0 90)
			(unlocked yes)
			(layer "F.Fab")
			(hide yes)
			(effects
				(font
					(size 1 1)
					(thickness 0.15)
				)
			)
		)
		(sheetname "/SDI/")
		(sheetfile "sdi.kicad_sch")
		(attr smd)
		(fp_line
			(start 0.22 -0.35)
			(end -0.22 -0.35)
			(stroke
				(width 0.15)
				(type solid)
			)
			(layer "F.SilkS")
		)
		(fp_line
			(start -1.18 -0.319)
			(end -1.18 0.321)
			(stroke
				(width 0.15)
				(type solid)
			)
			(layer "F.SilkS")
		)
		(fp_line
			(start 0.105328 0.001008)
			(end 0.24 0.001)
			(stroke
				(width 0.1)
				(type solid)
			)
			(layer "F.SilkS")
		)
		(fp_line
			(start -0.094672 0.001008)
			(end 0.105328 -0.198992)
			(stroke
				(width 0.1)
				(type solid)
			)
			(layer "F.SilkS")
		)
		(fp_line
			(start -0.094672 0.001008)
			(end -0.24 0.001008)
			(stroke
				(width 0.1)
				(type solid)
			)
			(layer "F.SilkS")
		)
		(fp_line
			(start 0.105328 0.201008)
			(end 0.105328 -0.198992)
			(stroke
				(width 0.1)
				(type solid)
			)
			(layer "F.SilkS")
		)
		(fp_line
			(start 0.105328 0.201008)
			(end -0.094672 0.001008)
			(stroke
				(width 0.1)
				(type solid)
			)
			(layer "F.SilkS")
		)
		(fp_line
			(start -0.094672 0.201008)
			(end -0.094672 -0.198992)
			(stroke
				(width 0.1)
				(type solid)
			)
			(layer "F.SilkS")
		)
		(fp_line
			(start 0.22 0.35)
			(end -0.22 0.35)
			(stroke
				(width 0.15)
				(type solid)
			)
			(layer "F.SilkS")
		)
		(fp_rect
			(start 1.25 0.65)
			(end -1.25 -0.65)
			(stroke
				(width 0.05)
				(type solid)
			)
			(fill no)
			(layer "F.CrtYd")
		)
		(fp_line
			(start 0.201 -0.202)
			(end -0.101 0)
			(stroke
				(width 0.15)
				(type solid)
			)
			(layer "F.Fab")
		)
		(fp_line
			(start -0.199 -0.202)
			(end -0.199 0.1)
			(stroke
				(width 0.15)
				(type solid)
			)
			(layer "F.Fab")
		)
		(fp_line
			(start 0.599 0)
			(end 0.201 0)
			(stroke
				(width 0.15)
				(type solid)
			)
			(layer "F.Fab")
		)
		(fp_line
			(start 0.201 0)
			(end 0.201 -0.202)
			(stroke
				(width 0.15)
				(type solid)
			)
			(layer "F.Fab")
		)
		(fp_line
			(start -0.101 0)
			(end 0.201 0.2)
			(stroke
				(width 0.15)
				(type solid)
			)
			(layer "F.Fab")
		)
		(fp_line
			(start -0.199 0)
			(end -0.597 0)
			(stroke
				(width 0.15)
				(type solid)
			)
			(layer "F.Fab")
		)
		(fp_line
			(start 0.201 0.2)
			(end 0.201 0)
			(stroke
				(width 0.15)
				(type solid)
			)
			(layer "F.Fab")
		)
		(fp_line
			(start -0.199 0.2)
			(end -0.199 0.1)
			(stroke
				(width 0.15)
				(type solid)
			)
			(layer "F.Fab")
		)
		(fp_rect
			(start 0.848 0.4)
			(end -0.85 -0.402)
			(stroke
				(width 0.15)
				(type solid)
			)
			(fill no)
			(layer "F.Fab")
		)
		(fp_text user "License: Apache-2.0"
			(at -1.4224 3.599 90)
			(layer "F.Fab")
			(effects
				(font
					(size 0.7 0.7)
					(thickness 0.15)
				)
				(justify left bottom)
			)
		)
		(fp_text user "Author: Antmicro"
			(at -1.4224 4.799 90)
			(layer "F.Fab")
			(effects
				(font
					(size 0.7 0.7)
					(thickness 0.15)
				)
				(justify left bottom)
			)
		)
		(fp_text user "${REFERENCE}"
			(at -1.4224 5.999 90)
			(layer "F.Fab")
			(effects
				(font
					(size 0.7 0.7)
					(thickness 0.15)
				)
				(justify left bottom)
			)
		)
		(pad "1" smd roundrect
			(at -0.7 0 270)
			(size 0.8 1)
			(layers "F.Cu" "F.Mask" "F.Paste")
			(roundrect_rratio 0.2)
			(net 1 "GND")
			(pinfunction "C")
			(pintype "passive")
		)
		(pad "2" smd roundrect
			(at 0.7 0 270)
			(size 0.8 1)
			(layers "F.Cu" "F.Mask" "F.Paste")
			(roundrect_rratio 0.2)
			(net 247 "Net-(D8-A)")
			(pinfunction "A")
			(pintype "passive")
		)
	)
	(footprint "antmicro-footprints:R_0402_1005Metric"
		(layer "F.Cu")
		(at 86.6 75.4)
		(descr "Resistor SMD 0402")
		(tags "resistor SMD 0402")
		(property "Reference" "R51"
			(at -2.77 -6.26 0)
			(layer "F.SilkS")
			(effects
				(font
					(size 0.65 0.65)
					(thickness 0.15)
				)
				(justify left bottom)
			)
		)
		(property "Value" "R_75R_0402"
			(at 0 1.4 0)
			(layer "F.Fab")
			(hide yes)
			(effects
				(font
					(size 0.7 0.7)
					(thickness 0.15)
				)
				(justify left bottom)
			)
		)
		(property "Datasheet" "https://www.bourns.com/docs/product-datasheets/cr.pdf"
			(at 0 0 0)
			(layer "F.Fab")
			(hide yes)
			(effects
				(font
					(size 1.27 1.27)
					(thickness 0.15)
				)
			)
		)
		(property "Description" "SMD Chip Resistor, 75 ohm, ± 1%, 62.5 mW, 0402 [1005 Metric], Thick Film, General Purpose"
			(at 0 0 0)
			(layer "F.Fab")
			(hide yes)
			(effects
				(font
					(size 1.27 1.27)
					(thickness 0.15)
				)
			)
		)
		(property "Author" "Antmicro"
			(at 0 0 0)
			(layer "F.Fab")
			(hide yes)
			(effects
				(font
					(size 1 1)
					(thickness 0.15)
				)
			)
		)
		(property "License" "Apache-2.0"
			(at 0 0 0)
			(layer "F.Fab")
			(hide yes)
			(effects
				(font
					(size 1 1)
					(thickness 0.15)
				)
			)
		)
		(property "MPN" "CR0402-FX-75R0GLF"
			(at 0 0 0)
			(layer "F.Fab")
			(hide yes)
			(effects
				(font
					(size 1 1)
					(thickness 0.15)
				)
			)
		)
		(property "Manufacturer" "Bourns"
			(at 0 0 0)
			(layer "F.Fab")
			(hide yes)
			(effects
				(font
					(size 1 1)
					(thickness 0.15)
				)
			)
		)
		(property "Tolerance" "1%"
			(at 0 0 0)
			(layer "F.Fab")
			(hide yes)
			(effects
				(font
					(size 1 1)
					(thickness 0.15)
				)
			)
		)
		(property "Val" "75R"
			(at 0 0 0)
			(layer "F.Fab")
			(hide yes)
			(effects
				(font
					(size 1 1)
					(thickness 0.15)
				)
			)
		)
		(sheetname "/SDI/")
		(sheetfile "sdi.kicad_sch")
		(attr smd)
		(fp_rect
			(start -0.925 -0.47)
			(end 0.925 0.47)
			(stroke
				(width 0.05)
				(type default)
			)
			(fill no)
			(layer "F.CrtYd")
		)
		(fp_rect
			(start -0.5 -0.25)
			(end 0.5 0.25)
			(stroke
				(width 0.15)
				(type solid)
			)
			(fill no)
			(layer "F.Fab")
		)
		(fp_text user "Author: Antmicro"
			(at -0.95 4.169 0)
			(layer "F.Fab")
			(effects
				(font
					(size 0.7 0.7)
					(thickness 0.15)
				)
				(justify left bottom)
			)
		)
		(fp_text user "License: Apache-2.0"
			(at -0.95 5.169 0)
			(layer "F.Fab")
			(effects
				(font
					(size 0.7 0.7)
					(thickness 0.15)
				)
				(justify left bottom)
			)
		)
		(fp_text user "${REFERENCE}"
			(at -0.95 3.168 0)
			(layer "F.Fab")
			(effects
				(font
					(size 0.7 0.7)
					(thickness 0.15)
				)
				(justify left bottom)
			)
		)
		(pad "1" smd roundrect
			(at -0.48 0)
			(size 0.59 0.64)
			(layers "F.Cu" "F.Mask" "F.Paste")
			(roundrect_rratio 0.25)
			(net 253 "/SDI/SDI_IN")
			(pintype "passive")
		)
		(pad "2" smd roundrect
			(at 0.48 0)
			(size 0.59 0.64)
			(layers "F.Cu" "F.Mask" "F.Paste")
			(roundrect_rratio 0.25)
			(net 243 "/SDI/SDI_IN_F")
			(pintype "passive")
		)
	)
	(footprint "antmicro-footprints:R_0805_2012Metric"
		(layer "F.Cu")
		(at 146.98 67.85 180)
		(property "Reference" "R15"
			(at -0.95 1.01 0)
			(layer "F.SilkS")
			(effects
				(font
					(size 0.65 0.65)
					(thickness 0.15)
				)
				(justify right bottom)
			)
		)
		(property "Value" "R_0R_0805"
			(at 0 1.8 0)
			(layer "F.Fab")
			(hide yes)
			(effects
				(font
					(size 0.7 0.7)
					(thickness 0.15)
				)
				(justify right bottom)
			)
		)
		(property "Datasheet" "https://www.vishay.com/docs/20035/dcrcwe3.pdf"
			(at 0 0 180)
			(layer "F.Fab")
			(hide yes)
			(effects
				(font
					(size 1.27 1.27)
					(thickness 0.15)
				)
			)
		)
		(property "Description" "Zero Ohm Resistor, Jumper, 0805 [2012 Metric], Thick Film, 125 mW, 2.5 A, Surface Mount Device"
			(at 0 0 180)
			(layer "F.Fab")
			(hide yes)
			(effects
				(font
					(size 1.27 1.27)
					(thickness 0.15)
				)
			)
		)
		(property "Author" "Antmicro"
			(at 293.96 135.7 0)
			(layer "F.Fab")
			(hide yes)
			(effects
				(font
					(size 1 1)
					(thickness 0.15)
				)
			)
		)
		(property "Current" "2.5A"
			(at 293.96 135.7 0)
			(layer "F.Fab")
			(hide yes)
			(effects
				(font
					(size 1 1)
					(thickness 0.15)
				)
			)
		)
		(property "License" "Apache-2.0"
			(at 293.96 135.7 0)
			(layer "F.Fab")
			(hide yes)
			(effects
				(font
					(size 1 1)
					(thickness 0.15)
				)
			)
		)
		(property "MPN" "CRCW08050000Z0EA"
			(at 293.96 135.7 0)
			(layer "F.Fab")
			(hide yes)
			(effects
				(font
					(size 1 1)
					(thickness 0.15)
				)
			)
		)
		(property "Manufacturer" "Vishay"
			(at 293.96 135.7 0)
			(layer "F.Fab")
			(hide yes)
			(effects
				(font
					(size 1 1)
					(thickness 0.15)
				)
			)
		)
		(property "Tolerance" "~"
			(at 293.96 135.7 0)
			(layer "F.Fab")
			(hide yes)
			(effects
				(font
					(size 1 1)
					(thickness 0.15)
				)
			)
		)
		(property "Val" "0R"
			(at 293.96 135.7 0)
			(layer "F.Fab")
			(hide yes)
			(effects
				(font
					(size 1 1)
					(thickness 0.15)
				)
			)
		)
		(sheetname "/Power Supply/")
		(sheetfile "supply.kicad_sch")
		(attr smd)
		(fp_line
			(start -0.3 -0.701)
			(end 0.298 -0.701)
			(stroke
				(width 0.15)
				(type solid)
			)
			(layer "F.SilkS")
		)
		(fp_line
			(start -0.32 0.699)
			(end 0.28 0.699)
			(stroke
				(width 0.15)
				(type solid)
			)
			(layer "F.SilkS")
		)
		(fp_rect
			(start 1.95 -0.9)
			(end -1.95 0.9)
			(stroke
				(width 0.05)
				(type default)
			)
			(fill no)
			(layer "F.CrtYd")
		)
		(fp_line
			(start 0.949 -0.677)
			(end 0.949 0.675)
			(stroke
				(width 0.15)
				(type solid)
			)
			(layer "F.Fab")
		)
		(fp_line
			(start -0.951 0.68)
			(end 0.949 0.68)
			(stroke
				(width 0.15)
				(type solid)
			)
			(layer "F.Fab")
		)
		(fp_line
			(start -0.951 -0.677)
			(end -0.951 0.675)
			(stroke
				(width 0.15)
				(type solid)
			)
			(layer "F.Fab")
		)
		(fp_line
			(start -0.951 -0.682)
			(end 0.949 -0.682)
			(stroke
				(width 0.15)
				(type solid)
			)
			(layer "F.Fab")
		)
		(fp_text user "${REFERENCE}"
			(at -1.9 3.1 180)
			(layer "F.Fab")
			(effects
				(font
					(size 0.7 0.7)
					(thickness 0.15)
				)
				(justify left bottom)
			)
		)
		(fp_text user "License: Apache-2.0"
			(at -1.9 5.75 180)
			(layer "F.Fab")
			(effects
				(font
					(size 0.7 0.7)
					(thickness 0.15)
				)
				(justify left bottom)
			)
		)
		(fp_text user "Author: Antmicro"
			(at -1.9 4.4 180)
			(layer "F.Fab")
			(effects
				(font
					(size 0.7 0.7)
					(thickness 0.15)
				)
				(justify left bottom)
			)
		)
		(pad "1" smd roundrect
			(at -1.1 0 180)
			(size 1.2 1.3)
			(layers "F.Cu" "F.Mask" "F.Paste")
			(roundrect_rratio 0.25)
			(net 14 "+5V")
			(pintype "passive")
		)
		(pad "2" smd roundrect
			(at 1.1 0 180)
			(size 1.2 1.3)
			(layers "F.Cu" "F.Mask" "F.Paste")
			(roundrect_rratio 0.25)
			(net 326 "/Power Supply/5V_1V0_IN")
			(pintype "passive")
		)
	)
	(footprint "antmicro-footprints:R_0402_1005Metric"
		(layer "F.Cu")
		(at 146.34 116.55 180)
		(descr "Resistor SMD 0402")
		(tags "resistor SMD 0402")
		(property "Reference" "R20"
			(at -0.89 -0.29 180)
			(layer "F.SilkS")
			(effects
				(font
					(size 0.65 0.65)
					(thickness 0.15)
				)
				(justify left bottom)
			)
		)
		(property "Value" "R_0R_0402"
			(at 0 1.4 180)
			(layer "F.Fab")
			(hide yes)
			(effects
				(font
					(size 0.7 0.7)
					(thickness 0.15)
				)
				(justify left bottom)
			)
		)
		(property "Datasheet" "https://industrial.panasonic.com/cdbs/www-data/pdf/RDA0000/AOA0000C301.pdf"
			(at 0 0 180)
			(layer "F.Fab")
			(hide yes)
			(effects
				(font
					(size 1.27 1.27)
					(thickness 0.15)
				)
			)
		)
		(property "Description" "SMD Chip Resistor, Jumper, 0 ohm, 100 mW, 0402 [1005 Metric], Thick Film, General Purpose"
			(at 0 0 180)
			(layer "F.Fab")
			(hide yes)
			(effects
				(font
					(size 1.27 1.27)
					(thickness 0.15)
				)
			)
		)
		(property "Author" "Antmicro"
			(at 292.68 233.1 0)
			(layer "F.Fab")
			(hide yes)
			(effects
				(font
					(size 1 1)
					(thickness 0.15)
				)
			)
		)
		(property "Current" "1A"
			(at 292.68 233.1 0)
			(layer "F.Fab")
			(hide yes)
			(effects
				(font
					(size 1 1)
					(thickness 0.15)
				)
			)
		)
		(property "License" "Apache-2.0"
			(at 292.68 233.1 0)
			(layer "F.Fab")
			(hide yes)
			(effects
				(font
					(size 1 1)
					(thickness 0.15)
				)
			)
		)
		(property "MPN" "ERJ2GE0R00X"
			(at 292.68 233.1 0)
			(layer "F.Fab")
			(hide yes)
			(effects
				(font
					(size 1 1)
					(thickness 0.15)
				)
			)
		)
		(property "Manufacturer" "Panasonic"
			(at 292.68 233.1 0)
			(layer "F.Fab")
			(hide yes)
			(effects
				(font
					(size 1 1)
					(thickness 0.15)
				)
			)
		)
		(property "Tolerance" "~"
			(at 292.68 233.1 0)
			(layer "F.Fab")
			(hide yes)
			(effects
				(font
					(size 1 1)
					(thickness 0.15)
				)
			)
		)
		(property "Val" "0R"
			(at 292.68 233.1 0)
			(layer "F.Fab")
			(hide yes)
			(effects
				(font
					(size 1 1)
					(thickness 0.15)
				)
			)
		)
		(sheetname "/Power Supply/")
		(sheetfile "supply.kicad_sch")
		(attr smd)
		(fp_rect
			(start -0.925 -0.47)
			(end 0.925 0.47)
			(stroke
				(width 0.05)
				(type default)
			)
			(fill no)
			(layer "F.CrtYd")
		)
		(fp_rect
			(start -0.5 -0.25)
			(end 0.5 0.25)
			(stroke
				(width 0.15)
				(type solid)
			)
			(fill no)
			(layer "F.Fab")
		)
		(fp_text user "Author: Antmicro"
			(at -0.95 4.169 180)
			(layer "F.Fab")
			(effects
				(font
					(size 0.7 0.7)
					(thickness 0.15)
				)
				(justify left bottom)
			)
		)
		(fp_text user "${REFERENCE}"
			(at -0.95 3.168 180)
			(layer "F.Fab")
			(effects
				(font
					(size 0.7 0.7)
					(thickness 0.15)
				)
				(justify left bottom)
			)
		)
		(fp_text user "License: Apache-2.0"
			(at -0.95 5.169 180)
			(layer "F.Fab")
			(effects
				(font
					(size 0.7 0.7)
					(thickness 0.15)
				)
				(justify left bottom)
			)
		)
		(pad "1" smd roundrect
			(at -0.48 0 180)
			(size 0.59 0.64)
			(layers "F.Cu" "F.Mask" "F.Paste")
			(roundrect_rratio 0.25)
			(net 2 "+3V3")
			(pintype "passive")
		)
		(pad "2" smd roundrect
			(at 0.48 0 180)
			(size 0.59 0.64)
			(layers "F.Cu" "F.Mask" "F.Paste")
			(roundrect_rratio 0.25)
			(net 265 "Net-(U9-V_{IN})")
			(pintype "passive")
		)
	)
	(footprint "antmicro-footprints:R_0402_1005Metric"
		(layer "F.Cu")
		(at 133.83 113.15 180)
		(descr "Resistor SMD 0402")
		(tags "resistor SMD 0402")
		(property "Reference" "R72"
			(at 3.2 0.01 180)
			(layer "F.SilkS")
			(effects
				(font
					(size 0.65 0.65)
					(thickness 0.15)
				)
				(justify left bottom)
			)
		)
		(property "Value" "R_100R_0402"
			(at 0 1.4 180)
			(layer "F.Fab")
			(hide yes)
			(effects
				(font
					(size 0.7 0.7)
					(thickness 0.15)
				)
				(justify left bottom)
			)
		)
		(property "Datasheet" "https://www.bourns.com/docs/product-datasheets/cr.pdf"
			(at 0 0 180)
			(layer "F.Fab")
			(hide yes)
			(effects
				(font
					(size 1.27 1.27)
					(thickness 0.15)
				)
			)
		)
		(property "Description" "SMD Chip Resistor, 100 ohm, ± 1%, 62.5 mW, 0402 [1005 Metric], Thick Film, General Purpose"
			(at 0 0 180)
			(layer "F.Fab")
			(hide yes)
			(effects
				(font
					(size 1.27 1.27)
					(thickness 0.15)
				)
			)
		)
		(property "Author" "Antmicro"
			(at 267.66 226.3 0)
			(layer "F.Fab")
			(hide yes)
			(effects
				(font
					(size 1 1)
					(thickness 0.15)
				)
			)
		)
		(property "License" "Apache-2.0"
			(at 267.66 226.3 0)
			(layer "F.Fab")
			(hide yes)
			(effects
				(font
					(size 1 1)
					(thickness 0.15)
				)
			)
		)
		(property "MPN" "CR0402-FX-1000GLF"
			(at 267.66 226.3 0)
			(layer "F.Fab")
			(hide yes)
			(effects
				(font
					(size 1 1)
					(thickness 0.15)
				)
			)
		)
		(property "Manufacturer" "Bourns"
			(at 267.66 226.3 0)
			(layer "F.Fab")
			(hide yes)
			(effects
				(font
					(size 1 1)
					(thickness 0.15)
				)
			)
		)
		(property "Tolerance" "1%"
			(at 267.66 226.3 0)
			(layer "F.Fab")
			(hide yes)
			(effects
				(font
					(size 1 1)
					(thickness 0.15)
				)
			)
		)
		(property "Val" "100R"
			(at 267.66 226.3 0)
			(layer "F.Fab")
			(hide yes)
			(effects
				(font
					(size 1 1)
					(thickness 0.15)
				)
			)
		)
		(sheetname "/FPGA/")
		(sheetfile "fpga.kicad_sch")
		(attr smd)
		(fp_rect
			(start -0.925 -0.47)
			(end 0.925 0.47)
			(stroke
				(width 0.05)
				(type default)
			)
			(fill no)
			(layer "F.CrtYd")
		)
		(fp_rect
			(start -0.5 -0.25)
			(end 0.5 0.25)
			(stroke
				(width 0.15)
				(type solid)
			)
			(fill no)
			(layer "F.Fab")
		)
		(fp_text user "License: Apache-2.0"
			(at -0.95 5.169 180)
			(layer "F.Fab")
			(effects
				(font
					(size 0.7 0.7)
					(thickness 0.15)
				)
				(justify left bottom)
			)
		)
		(fp_text user "Author: Antmicro"
			(at -0.95 4.169 180)
			(layer "F.Fab")
			(effects
				(font
					(size 0.7 0.7)
					(thickness 0.15)
				)
				(justify left bottom)
			)
		)
		(fp_text user "${REFERENCE}"
			(at -0.95 3.168 180)
			(layer "F.Fab")
			(effects
				(font
					(size 0.7 0.7)
					(thickness 0.15)
				)
				(justify left bottom)
			)
		)
		(pad "1" smd roundrect
			(at -0.48 0 180)
			(size 0.59 0.64)
			(layers "F.Cu" "F.Mask" "F.Paste")
			(roundrect_rratio 0.25)
			(net 381 "Net-(C80-Pad2)")
			(pintype "passive")
		)
		(pad "2" smd roundrect
			(at 0.48 0 180)
			(size 0.59 0.64)
			(layers "F.Cu" "F.Mask" "F.Paste")
			(roundrect_rratio 0.25)
			(net 281 "Net-(R72-Pad2)")
			(pintype "passive")
		)
	)
	(footprint "antmicro-footprints:C_0402_1005Metric"
		(layer "F.Cu")
		(at 109.3 98.7 180)
		(descr "Capacitor SMD 0402")
		(tags "capacitor SMD 0402")
		(property "Reference" "C125"
			(at -0.93 -0.34 180)
			(layer "F.SilkS")
			(effects
				(font
					(size 0.65 0.65)
					(thickness 0.15)
				)
				(justify left bottom)
			)
		)
		(property "Value" "C_100n_0402"
			(at 0 1.4 180)
			(layer "F.Fab")
			(hide yes)
			(effects
				(font
					(size 0.7 0.7)
					(thickness 0.15)
				)
				(justify left bottom)
			)
		)
		(property "Datasheet" "https://www.murata.com/products/productdetail?partno=GRM155R61H104KE14%23"
			(at 0 0 180)
			(layer "F.Fab")
			(hide yes)
			(effects
				(font
					(size 1.27 1.27)
					(thickness 0.15)
				)
			)
		)
		(property "Description" "SMD Multilayer Ceramic Capacitor, 0.1 µF, 50 V, 0402 [1005 Metric], ± 10%, X5R, GRM Series"
			(at 0 0 180)
			(layer "F.Fab")
			(hide yes)
			(effects
				(font
					(size 1.27 1.27)
					(thickness 0.15)
				)
			)
		)
		(property "Author" "Antmicro"
			(at 218.6 197.4 0)
			(layer "F.Fab")
			(hide yes)
			(effects
				(font
					(size 1 1)
					(thickness 0.15)
				)
			)
		)
		(property "Dielectric" "X5R"
			(at 218.6 197.4 0)
			(layer "F.Fab")
			(hide yes)
			(effects
				(font
					(size 1 1)
					(thickness 0.15)
				)
			)
		)
		(property "License" "Apache-2.0"
			(at 218.6 197.4 0)
			(layer "F.Fab")
			(hide yes)
			(effects
				(font
					(size 1 1)
					(thickness 0.15)
				)
			)
		)
		(property "MPN" "GRM155R61H104KE14D"
			(at 218.6 197.4 0)
			(layer "F.Fab")
			(hide yes)
			(effects
				(font
					(size 1 1)
					(thickness 0.15)
				)
			)
		)
		(property "Manufacturer" "Murata"
			(at 218.6 197.4 0)
			(layer "F.Fab")
			(hide yes)
			(effects
				(font
					(size 1 1)
					(thickness 0.15)
				)
			)
		)
		(property "Val" "100n"
			(at 218.6 197.4 0)
			(layer "F.Fab")
			(hide yes)
			(effects
				(font
					(size 1 1)
					(thickness 0.15)
				)
			)
		)
		(property "Voltage" "50V"
			(at 218.6 197.4 0)
			(layer "F.Fab")
			(hide yes)
			(effects
				(font
					(size 1 1)
					(thickness 0.15)
				)
			)
		)
		(sheetname "/FPGA/")
		(sheetfile "fpga.kicad_sch")
		(attr smd)
		(fp_rect
			(start -0.925 -0.47)
			(end 0.925 0.47)
			(stroke
				(width 0.05)
				(type default)
			)
			(fill no)
			(layer "F.CrtYd")
		)
		(fp_line
			(start 0.504 0.248)
			(end -0.494 0.248)
			(stroke
				(width 0.15)
				(type solid)
			)
			(layer "F.Fab")
		)
		(fp_line
			(start 0.504 -0.25)
			(end 0.504 0.248)
			(stroke
				(width 0.15)
				(type solid)
			)
			(layer "F.Fab")
		)
		(fp_line
			(start -0.494 0.248)
			(end -0.494 -0.25)
			(stroke
				(width 0.15)
				(type solid)
			)
			(layer "F.Fab")
		)
		(fp_line
			(start -0.494 -0.25)
			(end 0.504 -0.25)
			(stroke
				(width 0.15)
				(type solid)
			)
			(layer "F.Fab")
		)
		(fp_text user "${REFERENCE}"
			(at -0.939 4.599 180)
			(layer "F.Fab")
			(effects
				(font
					(size 0.7 0.7)
					(thickness 0.15)
				)
				(justify left bottom)
			)
		)
		(fp_text user "License: Apache-2.0"
			(at -0.939 5.799 180)
			(layer "F.Fab")
			(effects
				(font
					(size 0.7 0.7)
					(thickness 0.15)
				)
				(justify left bottom)
			)
		)
		(fp_text user "Author: Antmicro"
			(at -0.939 3.399 180)
			(layer "F.Fab")
			(effects
				(font
					(size 0.7 0.7)
					(thickness 0.15)
				)
				(justify left bottom)
			)
		)
		(pad "1" smd roundrect
			(at -0.48 0 180)
			(size 0.59 0.64)
			(layers "F.Cu" "F.Mask" "F.Paste")
			(roundrect_rratio 0.25)
			(net 2 "+3V3")
			(pintype "passive")
		)
		(pad "2" smd roundrect
			(at 0.48 0 180)
			(size 0.59 0.64)
			(layers "F.Cu" "F.Mask" "F.Paste")
			(roundrect_rratio 0.25)
			(net 1 "GND")
			(pintype "passive")
		)
	)
	(footprint "antmicro-footprints:R_0402_1005Metric"
		(layer "F.Cu")
		(at 100.94 115.185 90)
		(descr "Resistor SMD 0402")
		(tags "resistor SMD 0402")
		(property "Reference" "R94"
			(at 0.895 0.39 90)
			(layer "F.SilkS")
			(effects
				(font
					(size 0.65 0.65)
					(thickness 0.15)
				)
				(justify left bottom)
			)
		)
		(property "Value" "R_0R_0402"
			(at 0 1.4 90)
			(layer "F.Fab")
			(hide yes)
			(effects
				(font
					(size 0.7 0.7)
					(thickness 0.15)
				)
				(justify left bottom)
			)
		)
		(property "Datasheet" "https://industrial.panasonic.com/cdbs/www-data/pdf/RDA0000/AOA0000C301.pdf"
			(at 0 0 90)
			(layer "F.Fab")
			(hide yes)
			(effects
				(font
					(size 1.27 1.27)
					(thickness 0.15)
				)
			)
		)
		(property "Description" "SMD Chip Resistor, Jumper, 0 ohm, 100 mW, 0402 [1005 Metric], Thick Film, General Purpose"
			(at 0 0 90)
			(layer "F.Fab")
			(hide yes)
			(effects
				(font
					(size 1.27 1.27)
					(thickness 0.15)
				)
			)
		)
		(property "Author" "Antmicro"
			(at 216.125 14.245 0)
			(layer "F.Fab")
			(hide yes)
			(effects
				(font
					(size 1 1)
					(thickness 0.15)
				)
			)
		)
		(property "Current" "1A"
			(at 216.125 14.245 0)
			(layer "F.Fab")
			(hide yes)
			(effects
				(font
					(size 1 1)
					(thickness 0.15)
				)
			)
		)
		(property "License" "Apache-2.0"
			(at 216.125 14.245 0)
			(layer "F.Fab")
			(hide yes)
			(effects
				(font
					(size 1 1)
					(thickness 0.15)
				)
			)
		)
		(property "MPN" "ERJ2GE0R00X"
			(at 216.125 14.245 0)
			(layer "F.Fab")
			(hide yes)
			(effects
				(font
					(size 1 1)
					(thickness 0.15)
				)
			)
		)
		(property "Manufacturer" "Panasonic"
			(at 216.125 14.245 0)
			(layer "F.Fab")
			(hide yes)
			(effects
				(font
					(size 1 1)
					(thickness 0.15)
				)
			)
		)
		(property "Tolerance" "~"
			(at 216.125 14.245 0)
			(layer "F.Fab")
			(hide yes)
			(effects
				(font
					(size 1 1)
					(thickness 0.15)
				)
			)
		)
		(property "Val" "0R"
			(at 216.125 14.245 0)
			(layer "F.Fab")
			(hide yes)
			(effects
				(font
					(size 1 1)
					(thickness 0.15)
				)
			)
		)
		(sheetname "/FPGA/")
		(sheetfile "fpga.kicad_sch")
		(attr smd)
		(fp_rect
			(start -0.925 -0.47)
			(end 0.925 0.47)
			(stroke
				(width 0.05)
				(type default)
			)
			(fill no)
			(layer "F.CrtYd")
		)
		(fp_rect
			(start -0.5 -0.25)
			(end 0.5 0.25)
			(stroke
				(width 0.15)
				(type solid)
			)
			(fill no)
			(layer "F.Fab")
		)
		(fp_text user "Author: Antmicro"
			(at -0.95 4.169 90)
			(layer "F.Fab")
			(effects
				(font
					(size 0.7 0.7)
					(thickness 0.15)
				)
				(justify left bottom)
			)
		)
		(fp_text user "${REFERENCE}"
			(at -0.95 3.168 90)
			(layer "F.Fab")
			(effects
				(font
					(size 0.7 0.7)
					(thickness 0.15)
				)
				(justify left bottom)
			)
		)
		(fp_text user "License: Apache-2.0"
			(at -0.95 5.169 90)
			(layer "F.Fab")
			(effects
				(font
					(size 0.7 0.7)
					(thickness 0.15)
				)
				(justify left bottom)
			)
		)
		(pad "1" smd roundrect
			(at -0.48 0 90)
			(size 0.59 0.64)
			(layers "F.Cu" "F.Mask" "F.Paste")
			(roundrect_rratio 0.25)
			(net 136 "Net-(J7-Pad6)")
			(pintype "passive")
		)
		(pad "2" smd roundrect
			(at 0.48 0 90)
			(size 0.59 0.64)
			(layers "F.Cu" "F.Mask" "F.Paste")
			(roundrect_rratio 0.25)
			(net 171 "TDO")
			(pintype "passive")
		)
	)
	(footprint "antmicro-footprints:R_0603_1608Metric"
		(layer "F.Cu")
		(at 165.53 87.4 90)
		(descr "Resistor SMD 0603")
		(tags "resistor SMD 0603")
		(property "Reference" "R108"
			(at -2.14 -2.1 180)
			(layer "F.SilkS")
			(effects
				(font
					(size 0.65 0.65)
					(thickness 0.15)
				)
				(justify left bottom)
			)
		)
		(property "Value" "R_15k_0603"
			(at 0 1.6 90)
			(layer "F.Fab")
			(hide yes)
			(effects
				(font
					(size 0.7 0.7)
					(thickness 0.15)
				)
				(justify left bottom)
			)
		)
		(property "Datasheet" "https://www.bourns.com/docs/product-datasheets/cr.pdf"
			(at 0 0 90)
			(layer "F.Fab")
			(hide yes)
			(effects
				(font
					(size 1.27 1.27)
					(thickness 0.15)
				)
			)
		)
		(property "Description" "SMD Chip Resistor, 15 kohm, ± 1%, 100 mW, 0603 [1608 Metric], Thick Film, General Purpose"
			(at 0 0 90)
			(layer "F.Fab")
			(hide yes)
			(effects
				(font
					(size 1.27 1.27)
					(thickness 0.15)
				)
			)
		)
		(property "Author" "Antmicro"
			(at 252.93 -78.13 0)
			(layer "F.Fab")
			(hide yes)
			(effects
				(font
					(size 1 1)
					(thickness 0.15)
				)
			)
		)
		(property "License" "Apache-2.0"
			(at 252.93 -78.13 0)
			(layer "F.Fab")
			(hide yes)
			(effects
				(font
					(size 1 1)
					(thickness 0.15)
				)
			)
		)
		(property "MPN" "CR0603-FX-1502ELF"
			(at 252.93 -78.13 0)
			(layer "F.Fab")
			(hide yes)
			(effects
				(font
					(size 1 1)
					(thickness 0.15)
				)
			)
		)
		(property "Manufacturer" "Bourns"
			(at 252.93 -78.13 0)
			(layer "F.Fab")
			(hide yes)
			(effects
				(font
					(size 1 1)
					(thickness 0.15)
				)
			)
		)
		(property "Tolerance" "1%"
			(at 252.93 -78.13 0)
			(layer "F.Fab")
			(hide yes)
			(effects
				(font
					(size 1 1)
					(thickness 0.15)
				)
			)
		)
		(property "Val" "15k"
			(at 252.93 -78.13 0)
			(layer "F.Fab")
			(hide yes)
			(effects
				(font
					(size 1 1)
					(thickness 0.15)
				)
			)
		)
		(sheetname "/Peripherals/")
		(sheetfile "peripherals.kicad_sch")
		(attr smd)
		(fp_line
			(start -0.15 -0.4)
			(end 0.15 -0.4)
			(stroke
				(width 0.15)
				(type solid)
			)
			(layer "F.SilkS")
		)
		(fp_line
			(start -0.15 0.4)
			(end 0.15 0.4)
			(stroke
				(width 0.15)
				(type solid)
			)
			(layer "F.SilkS")
		)
		(fp_rect
			(start -1.25 -0.65)
			(end 1.25 0.65)
			(stroke
				(width 0.05)
				(type solid)
			)
			(fill no)
			(layer "F.CrtYd")
		)
		(fp_rect
			(start -0.8 -0.4)
			(end 0.8 0.4)
			(stroke
				(width 0.15)
				(type solid)
			)
			(fill no)
			(layer "F.Fab")
		)
		(fp_text user "${REFERENCE}"
			(at -1.25 3.898 90)
			(layer "F.Fab")
			(effects
				(font
					(size 0.7 0.7)
					(thickness 0.15)
				)
				(justify left bottom)
			)
		)
		(fp_text user "Author: Antmicro"
			(at -1.25 4.9 90)
			(layer "F.Fab")
			(effects
				(font
					(size 0.7 0.7)
					(thickness 0.15)
				)
				(justify left bottom)
			)
		)
		(fp_text user "License: Apache-2.0"
			(at -1.25 5.9 90)
			(layer "F.Fab")
			(effects
				(font
					(size 0.7 0.7)
					(thickness 0.15)
				)
				(justify left bottom)
			)
		)
		(pad "1" smd roundrect
			(at -0.7 0 90)
			(size 0.8 1)
			(layers "F.Cu" "F.Mask" "F.Paste")
			(roundrect_rratio 0.2)
			(net 1 "GND")
			(pintype "passive")
		)
		(pad "2" smd roundrect
			(at 0.7 0 90)
			(size 0.8 1)
			(layers "F.Cu" "F.Mask" "F.Paste")
			(roundrect_rratio 0.2)
			(net 354 "Net-(U14-ILIM)")
			(pintype "passive")
		)
	)
	(footprint "antmicro-footprints:R_0402_1005Metric"
		(layer "F.Cu")
		(at 84.2 106.15)
		(descr "Resistor SMD 0402")
		(tags "resistor SMD 0402")
		(property "Reference" "R59"
			(at 2.13 -7.91 0)
			(layer "F.SilkS")
			(effects
				(font
					(size 0.65 0.65)
					(thickness 0.15)
				)
				(justify left bottom)
			)
		)
		(property "Value" "R_75R_0402"
			(at 0 1.4 0)
			(layer "F.Fab")
			(hide yes)
			(effects
				(font
					(size 0.7 0.7)
					(thickness 0.15)
				)
				(justify left bottom)
			)
		)
		(property "Datasheet" "https://www.bourns.com/docs/product-datasheets/cr.pdf"
			(at 0 0 0)
			(layer "F.Fab")
			(hide yes)
			(effects
				(font
					(size 1.27 1.27)
					(thickness 0.15)
				)
			)
		)
		(property "Description" "SMD Chip Resistor, 75 ohm, ± 1%, 62.5 mW, 0402 [1005 Metric], Thick Film, General Purpose"
			(at 0 0 0)
			(layer "F.Fab")
			(hide yes)
			(effects
				(font
					(size 1.27 1.27)
					(thickness 0.15)
				)
			)
		)
		(property "Author" "Antmicro"
			(at 0 0 0)
			(layer "F.Fab")
			(hide yes)
			(effects
				(font
					(size 1 1)
					(thickness 0.15)
				)
			)
		)
		(property "License" "Apache-2.0"
			(at 0 0 0)
			(layer "F.Fab")
			(hide yes)
			(effects
				(font
					(size 1 1)
					(thickness 0.15)
				)
			)
		)
		(property "MPN" "CR0402-FX-75R0GLF"
			(at 0 0 0)
			(layer "F.Fab")
			(hide yes)
			(effects
				(font
					(size 1 1)
					(thickness 0.15)
				)
			)
		)
		(property "Manufacturer" "Bourns"
			(at 0 0 0)
			(layer "F.Fab")
			(hide yes)
			(effects
				(font
					(size 1 1)
					(thickness 0.15)
				)
			)
		)
		(property "Tolerance" "1%"
			(at 0 0 0)
			(layer "F.Fab")
			(hide yes)
			(effects
				(font
					(size 1 1)
					(thickness 0.15)
				)
			)
		)
		(property "Val" "75R"
			(at 0 0 0)
			(layer "F.Fab")
			(hide yes)
			(effects
				(font
					(size 1 1)
					(thickness 0.15)
				)
			)
		)
		(sheetname "/SDI/")
		(sheetfile "sdi.kicad_sch")
		(attr smd)
		(fp_rect
			(start -0.925 -0.47)
			(end 0.925 0.47)
			(stroke
				(width 0.05)
				(type default)
			)
			(fill no)
			(layer "F.CrtYd")
		)
		(fp_rect
			(start -0.5 -0.25)
			(end 0.5 0.25)
			(stroke
				(width 0.15)
				(type solid)
			)
			(fill no)
			(layer "F.Fab")
		)
		(fp_text user "Author: Antmicro"
			(at -0.95 4.169 0)
			(layer "F.Fab")
			(effects
				(font
					(size 0.7 0.7)
					(thickness 0.15)
				)
				(justify left bottom)
			)
		)
		(fp_text user "License: Apache-2.0"
			(at -0.95 5.169 0)
			(layer "F.Fab")
			(effects
				(font
					(size 0.7 0.7)
					(thickness 0.15)
				)
				(justify left bottom)
			)
		)
		(fp_text user "${REFERENCE}"
			(at -0.95 3.168 0)
			(layer "F.Fab")
			(effects
				(font
					(size 0.7 0.7)
					(thickness 0.15)
				)
				(justify left bottom)
			)
		)
		(pad "1" smd roundrect
			(at -0.48 0)
			(size 0.59 0.64)
			(layers "F.Cu" "F.Mask" "F.Paste")
			(roundrect_rratio 0.25)
			(net 2 "+3V3")
			(pintype "passive")
		)
		(pad "2" smd roundrect
			(at 0.48 0)
			(size 0.59 0.64)
			(layers "F.Cu" "F.Mask" "F.Paste")
			(roundrect_rratio 0.25)
			(net 254 "/SDI/SDI_OUT_N")
			(pintype "passive")
		)
	)
	(footprint "antmicro-footprints:C_0603_1608Metric"
		(layer "F.Cu")
		(at 138.19 110.9)
		(descr "Capacitor SMD 0603")
		(tags "capacitor 0603")
		(property "Reference" "C31"
			(at -3.36 0.24 0)
			(layer "F.SilkS")
			(effects
				(font
					(size 0.65 0.65)
					(thickness 0.15)
				)
				(justify left bottom)
			)
		)
		(property "Value" "C_10u_0603"
			(at 0 1.6 0)
			(layer "F.Fab")
			(hide yes)
			(effects
				(font
					(size 0.7 0.7)
					(thickness 0.15)
				)
				(justify left bottom)
			)
		)
		(property "Datasheet" "https://www.murata.com/products/productdetail?partno=GRM188R61A106KE69%23"
			(at 0 0 0)
			(layer "F.Fab")
			(hide yes)
			(effects
				(font
					(size 1.27 1.27)
					(thickness 0.15)
				)
			)
		)
		(property "Description" "SMD Multilayer Ceramic Capacitor, 10 µF, 10 V, 0603 [1608 Metric], ± 10%, X5R, GRM Series"
			(at 0 0 0)
			(layer "F.Fab")
			(hide yes)
			(effects
				(font
					(size 1.27 1.27)
					(thickness 0.15)
				)
			)
		)
		(property "Author" "Antmicro"
			(at 0 0 0)
			(layer "F.Fab")
			(hide yes)
			(effects
				(font
					(size 1 1)
					(thickness 0.15)
				)
			)
		)
		(property "License" "Apache-2.0"
			(at 0 0 0)
			(layer "F.Fab")
			(hide yes)
			(effects
				(font
					(size 1 1)
					(thickness 0.15)
				)
			)
		)
		(property "MPN" "GRM188R61A106KE69D"
			(at 0 0 0)
			(layer "F.Fab")
			(hide yes)
			(effects
				(font
					(size 1 1)
					(thickness 0.15)
				)
			)
		)
		(property "Manufacturer" "Murata"
			(at 0 0 0)
			(layer "F.Fab")
			(hide yes)
			(effects
				(font
					(size 1 1)
					(thickness 0.15)
				)
			)
		)
		(property "Val" "10u"
			(at 0 0 0)
			(layer "F.Fab")
			(hide yes)
			(effects
				(font
					(size 1 1)
					(thickness 0.15)
				)
			)
		)
		(property "Voltage" ""
			(at 0 0 0)
			(layer "F.Fab")
			(hide yes)
			(effects
				(font
					(size 1 1)
					(thickness 0.15)
				)
			)
		)
		(property "Dielectric" "template_dielectric"
			(at 0 0 0)
			(unlocked yes)
			(layer "F.Fab")
			(hide yes)
			(effects
				(font
					(size 1 1)
					(thickness 0.15)
				)
			)
		)
		(sheetname "/Power Supply/")
		(sheetfile "supply.kicad_sch")
		(attr smd)
		(fp_line
			(start -0.15 -0.4)
			(end 0.15 -0.4)
			(stroke
				(width 0.15)
				(type solid)
			)
			(layer "F.SilkS")
		)
		(fp_line
			(start -0.15 0.4)
			(end 0.15 0.4)
			(stroke
				(width 0.15)
				(type solid)
			)
			(layer "F.SilkS")
		)
		(fp_rect
			(start -1.25 -0.65)
			(end 1.25 0.65)
			(stroke
				(width 0.05)
				(type solid)
			)
			(fill no)
			(layer "F.CrtYd")
		)
		(fp_rect
			(start -0.8 -0.4)
			(end 0.8 0.4)
			(stroke
				(width 0.15)
				(type solid)
			)
			(fill no)
			(layer "F.Fab")
		)
		(fp_text user "${REFERENCE}"
			(at -1.682 3.895 0)
			(layer "F.Fab")
			(effects
				(font
					(size 0.7 0.7)
					(thickness 0.15)
				)
				(justify left bottom)
			)
		)
		(fp_text user "Author: Antmicro"
			(at -1.682 4.894 0)
			(layer "F.Fab")
			(effects
				(font
					(size 0.7 0.7)
					(thickness 0.15)
				)
				(justify left bottom)
			)
		)
		(fp_text user "License: Apache-2.0"
			(at -1.682 5.895 0)
			(layer "F.Fab")
			(effects
				(font
					(size 0.7 0.7)
					(thickness 0.15)
				)
				(justify left bottom)
			)
		)
		(pad "1" smd roundrect
			(at -0.7 0)
			(size 0.8 1)
			(layers "F.Cu" "F.Mask" "F.Paste")
			(roundrect_rratio 0.2)
			(net 1 "GND")
			(pintype "passive")
		)
		(pad "2" smd roundrect
			(at 0.7 0)
			(size 0.8 1)
			(layers "F.Cu" "F.Mask" "F.Paste")
			(roundrect_rratio 0.2)
			(net 50 "+1V8")
			(pintype "passive")
		)
	)
	(footprint "antmicro-footprints:C_0402_1005Metric"
		(layer "F.Cu")
		(at 133.83 112.15)
		(descr "Capacitor SMD 0402")
		(tags "capacitor SMD 0402")
		(property "Reference" "C80"
			(at -3.2 -0.01 0)
			(layer "F.SilkS")
			(effects
				(font
					(size 0.65 0.65)
					(thickness 0.15)
				)
				(justify left bottom)
			)
		)
		(property "Value" "C_100n_0402"
			(at 0 1.4 0)
			(layer "F.Fab")
			(hide yes)
			(effects
				(font
					(size 0.7 0.7)
					(thickness 0.15)
				)
				(justify left bottom)
			)
		)
		(property "Datasheet" "https://www.murata.com/products/productdetail?partno=GRM155R61H104KE14%23"
			(at 0 0 0)
			(layer "F.Fab")
			(hide yes)
			(effects
				(font
					(size 1.27 1.27)
					(thickness 0.15)
				)
			)
		)
		(property "Description" "SMD Multilayer Ceramic Capacitor, 0.1 µF, 50 V, 0402 [1005 Metric], ± 10%, X5R, GRM Series"
			(at 0 0 0)
			(layer "F.Fab")
			(hide yes)
			(effects
				(font
					(size 1.27 1.27)
					(thickness 0.15)
				)
			)
		)
		(property "Author" "Antmicro"
			(at 0 0 0)
			(layer "F.Fab")
			(hide yes)
			(effects
				(font
					(size 1 1)
					(thickness 0.15)
				)
			)
		)
		(property "Dielectric" "X5R"
			(at 0 0 0)
			(layer "F.Fab")
			(hide yes)
			(effects
				(font
					(size 1 1)
					(thickness 0.15)
				)
			)
		)
		(property "License" "Apache-2.0"
			(at 0 0 0)
			(layer "F.Fab")
			(hide yes)
			(effects
				(font
					(size 1 1)
					(thickness 0.15)
				)
			)
		)
		(property "MPN" "GRM155R61H104KE14D"
			(at 0 0 0)
			(layer "F.Fab")
			(hide yes)
			(effects
				(font
					(size 1 1)
					(thickness 0.15)
				)
			)
		)
		(property "Manufacturer" "Murata"
			(at 0 0 0)
			(layer "F.Fab")
			(hide yes)
			(effects
				(font
					(size 1 1)
					(thickness 0.15)
				)
			)
		)
		(property "Val" "100n"
			(at 0 0 0)
			(layer "F.Fab")
			(hide yes)
			(effects
				(font
					(size 1 1)
					(thickness 0.15)
				)
			)
		)
		(property "Voltage" "50V"
			(at 0 0 0)
			(layer "F.Fab")
			(hide yes)
			(effects
				(font
					(size 1 1)
					(thickness 0.15)
				)
			)
		)
		(sheetname "/FPGA/")
		(sheetfile "fpga.kicad_sch")
		(attr smd)
		(fp_rect
			(start -0.925 -0.47)
			(end 0.925 0.47)
			(stroke
				(width 0.05)
				(type default)
			)
			(fill no)
			(layer "F.CrtYd")
		)
		(fp_line
			(start -0.494 -0.25)
			(end 0.504 -0.25)
			(stroke
				(width 0.15)
				(type solid)
			)
			(layer "F.Fab")
		)
		(fp_line
			(start -0.494 0.248)
			(end -0.494 -0.25)
			(stroke
				(width 0.15)
				(type solid)
			)
			(layer "F.Fab")
		)
		(fp_line
			(start 0.504 -0.25)
			(end 0.504 0.248)
			(stroke
				(width 0.15)
				(type solid)
			)
			(layer "F.Fab")
		)
		(fp_line
			(start 0.504 0.248)
			(end -0.494 0.248)
			(stroke
				(width 0.15)
				(type solid)
			)
			(layer "F.Fab")
		)
		(fp_text user "License: Apache-2.0"
			(at -0.939 5.799 0)
			(layer "F.Fab")
			(effects
				(font
					(size 0.7 0.7)
					(thickness 0.15)
				)
				(justify left bottom)
			)
		)
		(fp_text user "Author: Antmicro"
			(at -0.939 3.399 0)
			(layer "F.Fab")
			(effects
				(font
					(size 0.7 0.7)
					(thickness 0.15)
				)
				(justify left bottom)
			)
		)
		(fp_text user "${REFERENCE}"
			(at -0.939 4.599 0)
			(layer "F.Fab")
			(effects
				(font
					(size 0.7 0.7)
					(thickness 0.15)
				)
				(justify left bottom)
			)
		)
		(pad "1" smd roundrect
			(at -0.48 0)
			(size 0.59 0.64)
			(layers "F.Cu" "F.Mask" "F.Paste")
			(roundrect_rratio 0.25)
			(net 1 "GND")
			(pintype "passive")
		)
		(pad "2" smd roundrect
			(at 0.48 0)
			(size 0.59 0.64)
			(layers "F.Cu" "F.Mask" "F.Paste")
			(roundrect_rratio 0.25)
			(net 381 "Net-(C80-Pad2)")
			(pintype "passive")
		)
	)
	(footprint "antmicro-footprints:R_0402_1005Metric"
		(layer "F.Cu")
		(at 89.97 109.55 -90)
		(descr "Resistor SMD 0402")
		(tags "resistor SMD 0402")
		(property "Reference" "R38"
			(at -1.11 -1.46 90)
			(layer "F.SilkS")
			(effects
				(font
					(size 0.65 0.65)
					(thickness 0.15)
				)
				(justify right bottom)
			)
		)
		(property "Value" "R_0R_0402"
			(at 0 1.4 90)
			(layer "F.Fab")
			(hide yes)
			(effects
				(font
					(size 0.7 0.7)
					(thickness 0.15)
				)
				(justify right bottom)
			)
		)
		(property "Datasheet" "https://industrial.panasonic.com/cdbs/www-data/pdf/RDA0000/AOA0000C301.pdf"
			(at 0 0 270)
			(layer "F.Fab")
			(hide yes)
			(effects
				(font
					(size 1.27 1.27)
					(thickness 0.15)
				)
			)
		)
		(property "Description" "SMD Chip Resistor, Jumper, 0 ohm, 100 mW, 0402 [1005 Metric], Thick Film, General Purpose"
			(at 0 0 270)
			(layer "F.Fab")
			(hide yes)
			(effects
				(font
					(size 1.27 1.27)
					(thickness 0.15)
				)
			)
		)
		(property "Author" "Antmicro"
			(at -19.58 199.52 0)
			(layer "F.Fab")
			(hide yes)
			(effects
				(font
					(size 1 1)
					(thickness 0.15)
				)
			)
		)
		(property "Current" "1A"
			(at -19.58 199.52 0)
			(layer "F.Fab")
			(hide yes)
			(effects
				(font
					(size 1 1)
					(thickness 0.15)
				)
			)
		)
		(property "License" "Apache-2.0"
			(at -19.58 199.52 0)
			(layer "F.Fab")
			(hide yes)
			(effects
				(font
					(size 1 1)
					(thickness 0.15)
				)
			)
		)
		(property "MPN" "ERJ2GE0R00X"
			(at -19.58 199.52 0)
			(layer "F.Fab")
			(hide yes)
			(effects
				(font
					(size 1 1)
					(thickness 0.15)
				)
			)
		)
		(property "Manufacturer" "Panasonic"
			(at -19.58 199.52 0)
			(layer "F.Fab")
			(hide yes)
			(effects
				(font
					(size 1 1)
					(thickness 0.15)
				)
			)
		)
		(property "Tolerance" "~"
			(at -19.58 199.52 0)
			(layer "F.Fab")
			(hide yes)
			(effects
				(font
					(size 1 1)
					(thickness 0.15)
				)
			)
		)
		(property "Val" "0R"
			(at -19.58 199.52 0)
			(layer "F.Fab")
			(hide yes)
			(effects
				(font
					(size 1 1)
					(thickness 0.15)
				)
			)
		)
		(sheetname "/SDI/")
		(sheetfile "sdi.kicad_sch")
		(attr smd)
		(fp_rect
			(start -0.925 -0.47)
			(end 0.925 0.47)
			(stroke
				(width 0.05)
				(type default)
			)
			(fill no)
			(layer "F.CrtYd")
		)
		(fp_rect
			(start -0.5 -0.25)
			(end 0.5 0.25)
			(stroke
				(width 0.15)
				(type solid)
			)
			(fill no)
			(layer "F.Fab")
		)
		(fp_text user "${REFERENCE}"
			(at -0.95 3.168 270)
			(layer "F.Fab")
			(effects
				(font
					(size 0.7 0.7)
					(thickness 0.15)
				)
				(justify left bottom)
			)
		)
		(fp_text user "Author: Antmicro"
			(at -0.95 4.169 270)
			(layer "F.Fab")
			(effects
				(font
					(size 0.7 0.7)
					(thickness 0.15)
				)
				(justify left bottom)
			)
		)
		(fp_text user "License: Apache-2.0"
			(at -0.95 5.169 270)
			(layer "F.Fab")
			(effects
				(font
					(size 0.7 0.7)
					(thickness 0.15)
				)
				(justify left bottom)
			)
		)
		(pad "1" smd roundrect
			(at -0.48 0 270)
			(size 0.59 0.64)
			(layers "F.Cu" "F.Mask" "F.Paste")
			(roundrect_rratio 0.25)
			(net 285 "Net-(U16-~{EQ_EN})")
			(pintype "passive")
		)
		(pad "2" smd roundrect
			(at 0.48 0 270)
			(size 0.59 0.64)
			(layers "F.Cu" "F.Mask" "F.Paste")
			(roundrect_rratio 0.25)
			(net 2 "+3V3")
			(pintype "passive")
		)
	)
	(footprint "antmicro-footprints:R_0603_1608Metric"
		(layer "F.Cu")
		(at 104.59 107.2 -90)
		(descr "Resistor SMD 0603")
		(tags "resistor SMD 0603")
		(property "Reference" "R65"
			(at 1.24 -0.44 90)
			(layer "F.SilkS")
			(effects
				(font
					(size 0.65 0.65)
					(thickness 0.15)
				)
				(justify right bottom)
			)
		)
		(property "Value" "R_0R_0603"
			(at 0 1.6 90)
			(layer "F.Fab")
			(hide yes)
			(effects
				(font
					(size 0.7 0.7)
					(thickness 0.15)
				)
				(justify right bottom)
			)
		)
		(property "Datasheet" "https://www.bourns.com/docs/product-datasheets/cr.pdf?sfvrsn=574d41f6_14"
			(at 0 0 270)
			(layer "F.Fab")
			(hide yes)
			(effects
				(font
					(size 1.27 1.27)
					(thickness 0.15)
				)
			)
		)
		(property "Description" "Zero Ohm Resistor, Jumper, 0603 [1608 Metric], Thick Film, 100 mW, 1 A, Surface Mount Device, CR"
			(at 0 0 270)
			(layer "F.Fab")
			(hide yes)
			(effects
				(font
					(size 1.27 1.27)
					(thickness 0.15)
				)
			)
		)
		(property "Author" "Antmicro"
			(at -2.61 211.79 0)
			(layer "F.Fab")
			(hide yes)
			(effects
				(font
					(size 1 1)
					(thickness 0.15)
				)
			)
		)
		(property "Current" "1A"
			(at -2.61 211.79 0)
			(layer "F.Fab")
			(hide yes)
			(effects
				(font
					(size 1 1)
					(thickness 0.15)
				)
			)
		)
		(property "License" "Apache-2.0"
			(at -2.61 211.79 0)
			(layer "F.Fab")
			(hide yes)
			(effects
				(font
					(size 1 1)
					(thickness 0.15)
				)
			)
		)
		(property "MPN" "CR0603-J/-000ELF"
			(at -2.61 211.79 0)
			(layer "F.Fab")
			(hide yes)
			(effects
				(font
					(size 1 1)
					(thickness 0.15)
				)
			)
		)
		(property "Manufacturer" "Bourns"
			(at -2.61 211.79 0)
			(layer "F.Fab")
			(hide yes)
			(effects
				(font
					(size 1 1)
					(thickness 0.15)
				)
			)
		)
		(property "Tolerance" "~"
			(at -2.61 211.79 0)
			(layer "F.Fab")
			(hide yes)
			(effects
				(font
					(size 1 1)
					(thickness 0.15)
				)
			)
		)
		(property "Val" "0R"
			(at -2.61 211.79 0)
			(layer "F.Fab")
			(hide yes)
			(effects
				(font
					(size 1 1)
					(thickness 0.15)
				)
			)
		)
		(sheetname "/FPGA/")
		(sheetfile "fpga.kicad_sch")
		(attr smd)
		(fp_line
			(start -0.15 0.4)
			(end 0.15 0.4)
			(stroke
				(width 0.15)
				(type solid)
			)
			(layer "F.SilkS")
		)
		(fp_line
			(start -0.15 -0.4)
			(end 0.15 -0.4)
			(stroke
				(width 0.15)
				(type solid)
			)
			(layer "F.SilkS")
		)
		(fp_rect
			(start -1.25 -0.65)
			(end 1.25 0.65)
			(stroke
				(width 0.05)
				(type solid)
			)
			(fill no)
			(layer "F.CrtYd")
		)
		(fp_rect
			(start -0.8 -0.4)
			(end 0.8 0.4)
			(stroke
				(width 0.15)
				(type solid)
			)
			(fill no)
			(layer "F.Fab")
		)
		(fp_text user "${REFERENCE}"
			(at -1.25 3.898 270)
			(layer "F.Fab")
			(effects
				(font
					(size 0.7 0.7)
					(thickness 0.15)
				)
				(justify left bottom)
			)
		)
		(fp_text user "License: Apache-2.0"
			(at -1.25 5.9 270)
			(layer "F.Fab")
			(effects
				(font
					(size 0.7 0.7)
					(thickness 0.15)
				)
				(justify left bottom)
			)
		)
		(fp_text user "Author: Antmicro"
			(at -1.25 4.9 270)
			(layer "F.Fab")
			(effects
				(font
					(size 0.7 0.7)
					(thickness 0.15)
				)
				(justify left bottom)
			)
		)
		(pad "1" smd roundrect
			(at -0.7 0 270)
			(size 0.8 1)
			(layers "F.Cu" "F.Mask" "F.Paste")
			(roundrect_rratio 0.2)
			(net 298 "Net-(U17-SCL)")
			(pintype "passive")
		)
		(pad "2" smd roundrect
			(at 0.7 0 270)
			(size 0.8 1)
			(layers "F.Cu" "F.Mask" "F.Paste")
			(roundrect_rratio 0.2)
			(net 100 "SCL")
			(pintype "passive")
		)
	)
	(footprint "antmicro-footprints:R_0402_1005Metric"
		(layer "F.Cu")
		(at 132.75 116.75 -90)
		(descr "Resistor SMD 0402")
		(tags "resistor SMD 0402")
		(property "Reference" "R126"
			(at -0.76 -0.28 270)
			(layer "F.SilkS")
			(effects
				(font
					(size 0.65 0.65)
					(thickness 0.15)
				)
				(justify left bottom)
			)
		)
		(property "Value" "R_0R_0402"
			(at 0 1.4 270)
			(layer "F.Fab")
			(hide yes)
			(effects
				(font
					(size 0.7 0.7)
					(thickness 0.15)
				)
				(justify left bottom)
			)
		)
		(property "Datasheet" "https://industrial.panasonic.com/cdbs/www-data/pdf/RDA0000/AOA0000C301.pdf"
			(at 0 0 270)
			(layer "F.Fab")
			(hide yes)
			(effects
				(font
					(size 1.27 1.27)
					(thickness 0.15)
				)
			)
		)
		(property "Description" "SMD Chip Resistor, Jumper, 0 ohm, 100 mW, 0402 [1005 Metric], Thick Film, General Purpose"
			(at 0 0 270)
			(layer "F.Fab")
			(hide yes)
			(effects
				(font
					(size 1.27 1.27)
					(thickness 0.15)
				)
			)
		)
		(property "Author" "Antmicro"
			(at 16 249.5 0)
			(layer "F.Fab")
			(hide yes)
			(effects
				(font
					(size 1 1)
					(thickness 0.15)
				)
			)
		)
		(property "Current" "1A"
			(at 16 249.5 0)
			(layer "F.Fab")
			(hide yes)
			(effects
				(font
					(size 1 1)
					(thickness 0.15)
				)
			)
		)
		(property "License" "Apache-2.0"
			(at 16 249.5 0)
			(layer "F.Fab")
			(hide yes)
			(effects
				(font
					(size 1 1)
					(thickness 0.15)
				)
			)
		)
		(property "MPN" "ERJ2GE0R00X"
			(at 16 249.5 0)
			(layer "F.Fab")
			(hide yes)
			(effects
				(font
					(size 1 1)
					(thickness 0.15)
				)
			)
		)
		(property "Manufacturer" "Panasonic"
			(at 16 249.5 0)
			(layer "F.Fab")
			(hide yes)
			(effects
				(font
					(size 1 1)
					(thickness 0.15)
				)
			)
		)
		(property "Tolerance" "~"
			(at 16 249.5 0)
			(layer "F.Fab")
			(hide yes)
			(effects
				(font
					(size 1 1)
					(thickness 0.15)
				)
			)
		)
		(property "Val" "0R"
			(at 16 249.5 0)
			(layer "F.Fab")
			(hide yes)
			(effects
				(font
					(size 1 1)
					(thickness 0.15)
				)
			)
		)
		(sheetname "/Peripherals/")
		(sheetfile "peripherals.kicad_sch")
		(attr smd)
		(fp_rect
			(start -0.925 -0.47)
			(end 0.925 0.47)
			(stroke
				(width 0.05)
				(type default)
			)
			(fill no)
			(layer "F.CrtYd")
		)
		(fp_rect
			(start -0.5 -0.25)
			(end 0.5 0.25)
			(stroke
				(width 0.15)
				(type solid)
			)
			(fill no)
			(layer "F.Fab")
		)
		(fp_text user "Author: Antmicro"
			(at -0.95 4.169 270)
			(layer "F.Fab")
			(effects
				(font
					(size 0.7 0.7)
					(thickness 0.15)
				)
				(justify left bottom)
			)
		)
		(fp_text user "License: Apache-2.0"
			(at -0.95 5.169 270)
			(layer "F.Fab")
			(effects
				(font
					(size 0.7 0.7)
					(thickness 0.15)
				)
				(justify left bottom)
			)
		)
		(fp_text user "${REFERENCE}"
			(at -0.95 3.168 270)
			(layer "F.Fab")
			(effects
				(font
					(size 0.7 0.7)
					(thickness 0.15)
				)
				(justify left bottom)
			)
		)
		(pad "1" smd roundrect
			(at -0.48 0 270)
			(size 0.59 0.64)
			(layers "F.Cu" "F.Mask" "F.Paste")
			(roundrect_rratio 0.25)
			(net 99 "/Peripherals/FCC2_SDA2")
			(pintype "passive")
		)
		(pad "2" smd roundrect
			(at 0.48 0 270)
			(size 0.59 0.64)
			(layers "F.Cu" "F.Mask" "F.Paste")
			(roundrect_rratio 0.25)
			(net 346 "Net-(J6-Pad41)")
			(pintype "passive")
		)
	)
	(footprint "antmicro-footprints:R_0402_1005Metric"
		(layer "F.Cu")
		(at 122.03 108.65 180)
		(descr "Resistor SMD 0402")
		(tags "resistor SMD 0402")
		(property "Reference" "R86"
			(at 0.95 -0.39 0)
			(layer "F.SilkS")
			(effects
				(font
					(size 0.65 0.65)
					(thickness 0.15)
				)
				(justify right bottom)
			)
		)
		(property "Value" "R_0R_0402"
			(at 0 1.4 0)
			(layer "F.Fab")
			(hide yes)
			(effects
				(font
					(size 0.7 0.7)
					(thickness 0.15)
				)
				(justify right bottom)
			)
		)
		(property "Datasheet" "https://industrial.panasonic.com/cdbs/www-data/pdf/RDA0000/AOA0000C301.pdf"
			(at 0 0 180)
			(layer "F.Fab")
			(hide yes)
			(effects
				(font
					(size 1.27 1.27)
					(thickness 0.15)
				)
			)
		)
		(property "Description" "SMD Chip Resistor, Jumper, 0 ohm, 100 mW, 0402 [1005 Metric], Thick Film, General Purpose"
			(at 0 0 180)
			(layer "F.Fab")
			(hide yes)
			(effects
				(font
					(size 1.27 1.27)
					(thickness 0.15)
				)
			)
		)
		(property "Author" "Antmicro"
			(at 244.06 217.3 0)
			(layer "F.Fab")
			(hide yes)
			(effects
				(font
					(size 1 1)
					(thickness 0.15)
				)
			)
		)
		(property "Current" "1A"
			(at 244.06 217.3 0)
			(layer "F.Fab")
			(hide yes)
			(effects
				(font
					(size 1 1)
					(thickness 0.15)
				)
			)
		)
		(property "License" "Apache-2.0"
			(at 244.06 217.3 0)
			(layer "F.Fab")
			(hide yes)
			(effects
				(font
					(size 1 1)
					(thickness 0.15)
				)
			)
		)
		(property "MPN" "ERJ2GE0R00X"
			(at 244.06 217.3 0)
			(layer "F.Fab")
			(hide yes)
			(effects
				(font
					(size 1 1)
					(thickness 0.15)
				)
			)
		)
		(property "Manufacturer" "Panasonic"
			(at 244.06 217.3 0)
			(layer "F.Fab")
			(hide yes)
			(effects
				(font
					(size 1 1)
					(thickness 0.15)
				)
			)
		)
		(property "Tolerance" "~"
			(at 244.06 217.3 0)
			(layer "F.Fab")
			(hide yes)
			(effects
				(font
					(size 1 1)
					(thickness 0.15)
				)
			)
		)
		(property "Val" "0R"
			(at 244.06 217.3 0)
			(layer "F.Fab")
			(hide yes)
			(effects
				(font
					(size 1 1)
					(thickness 0.15)
				)
			)
		)
		(sheetname "/FPGA/")
		(sheetfile "fpga.kicad_sch")
		(attr smd)
		(fp_rect
			(start -0.925 -0.47)
			(end 0.925 0.47)
			(stroke
				(width 0.05)
				(type default)
			)
			(fill no)
			(layer "F.CrtYd")
		)
		(fp_rect
			(start -0.5 -0.25)
			(end 0.5 0.25)
			(stroke
				(width 0.15)
				(type solid)
			)
			(fill no)
			(layer "F.Fab")
		)
		(fp_text user "${REFERENCE}"
			(at -0.95 3.168 180)
			(layer "F.Fab")
			(effects
				(font
					(size 0.7 0.7)
					(thickness 0.15)
				)
				(justify left bottom)
			)
		)
		(fp_text user "License: Apache-2.0"
			(at -0.95 5.169 180)
			(layer "F.Fab")
			(effects
				(font
					(size 0.7 0.7)
					(thickness 0.15)
				)
				(justify left bottom)
			)
		)
		(fp_text user "Author: Antmicro"
			(at -0.95 4.169 180)
			(layer "F.Fab")
			(effects
				(font
					(size 0.7 0.7)
					(thickness 0.15)
				)
				(justify left bottom)
			)
		)
		(pad "1" smd roundrect
			(at -0.48 0 180)
			(size 0.59 0.64)
			(layers "F.Cu" "F.Mask" "F.Paste")
			(roundrect_rratio 0.25)
			(net 15 "/FPGA/INITN")
			(pintype "passive")
		)
		(pad "2" smd roundrect
			(at 0.48 0 180)
			(size 0.59 0.64)
			(layers "F.Cu" "F.Mask" "F.Paste")
			(roundrect_rratio 0.25)
			(net 42 "/FPGA/INITN_SOFT")
			(pintype "passive")
		)
	)
	(footprint "antmicro-footprints:C_0603_1608Metric"
		(layer "F.Cu")
		(at 147.63 70.85 -90)
		(descr "Capacitor SMD 0603")
		(tags "capacitor 0603")
		(property "Reference" "C23"
			(at 0.59 0.9 90)
			(layer "F.SilkS")
			(effects
				(font
					(size 0.65 0.65)
					(thickness 0.15)
				)
				(justify right bottom)
			)
		)
		(property "Value" "C_22u_0603"
			(at 0 1.6 90)
			(layer "F.Fab")
			(hide yes)
			(effects
				(font
					(size 0.7 0.7)
					(thickness 0.15)
				)
				(justify right bottom)
			)
		)
		(property "Datasheet" "https://www.murata.com/products/productdetail?partno=GRM188R60J226MEA0%23"
			(at 0 0 270)
			(layer "F.Fab")
			(hide yes)
			(effects
				(font
					(size 1.27 1.27)
					(thickness 0.15)
				)
			)
		)
		(property "Description" "SMD Multilayer Ceramic Capacitor, 22 µF, 6.3 V, 0603 [1608 Metric], ± 20%, X5R, GRM Series"
			(at 0 0 270)
			(layer "F.Fab")
			(hide yes)
			(effects
				(font
					(size 1.27 1.27)
					(thickness 0.15)
				)
			)
		)
		(property "Author" "Antmicro"
			(at 76.78 218.48 0)
			(layer "F.Fab")
			(hide yes)
			(effects
				(font
					(size 1 1)
					(thickness 0.15)
				)
			)
		)
		(property "Dielectric" ""
			(at 76.78 218.48 0)
			(layer "F.Fab")
			(hide yes)
			(effects
				(font
					(size 1 1)
					(thickness 0.15)
				)
			)
		)
		(property "License" "Apache-2.0"
			(at 76.78 218.48 0)
			(layer "F.Fab")
			(hide yes)
			(effects
				(font
					(size 1 1)
					(thickness 0.15)
				)
			)
		)
		(property "MPN" "GRM188R60J226MEA0D"
			(at 76.78 218.48 0)
			(layer "F.Fab")
			(hide yes)
			(effects
				(font
					(size 1 1)
					(thickness 0.15)
				)
			)
		)
		(property "Manufacturer" "Murata"
			(at 76.78 218.48 0)
			(layer "F.Fab")
			(hide yes)
			(effects
				(font
					(size 1 1)
					(thickness 0.15)
				)
			)
		)
		(property "Val" "22u"
			(at 76.78 218.48 0)
			(layer "F.Fab")
			(hide yes)
			(effects
				(font
					(size 1 1)
					(thickness 0.15)
				)
			)
		)
		(property "Voltage" ""
			(at 76.78 218.48 0)
			(layer "F.Fab")
			(hide yes)
			(effects
				(font
					(size 1 1)
					(thickness 0.15)
				)
			)
		)
		(sheetname "/Power Supply/")
		(sheetfile "supply.kicad_sch")
		(attr smd)
		(fp_line
			(start -0.15 0.4)
			(end 0.15 0.4)
			(stroke
				(width 0.15)
				(type solid)
			)
			(layer "F.SilkS")
		)
		(fp_line
			(start -0.15 -0.4)
			(end 0.15 -0.4)
			(stroke
				(width 0.15)
				(type solid)
			)
			(layer "F.SilkS")
		)
		(fp_rect
			(start -1.25 -0.65)
			(end 1.25 0.65)
			(stroke
				(width 0.05)
				(type solid)
			)
			(fill no)
			(layer "F.CrtYd")
		)
		(fp_rect
			(start -0.8 -0.4)
			(end 0.8 0.4)
			(stroke
				(width 0.15)
				(type solid)
			)
			(fill no)
			(layer "F.Fab")
		)
		(fp_text user "License: Apache-2.0"
			(at -1.682 5.895 270)
			(layer "F.Fab")
			(effects
				(font
					(size 0.7 0.7)
					(thickness 0.15)
				)
				(justify left bottom)
			)
		)
		(fp_text user "${REFERENCE}"
			(at -1.682 3.895 270)
			(layer "F.Fab")
			(effects
				(font
					(size 0.7 0.7)
					(thickness 0.15)
				)
				(justify left bottom)
			)
		)
		(fp_text user "Author: Antmicro"
			(at -1.682 4.894 270)
			(layer "F.Fab")
			(effects
				(font
					(size 0.7 0.7)
					(thickness 0.15)
				)
				(justify left bottom)
			)
		)
		(pad "1" smd roundrect
			(at -0.7 0 270)
			(size 0.8 1)
			(layers "F.Cu" "F.Mask" "F.Paste")
			(roundrect_rratio 0.2)
			(net 1 "GND")
			(pintype "passive")
		)
		(pad "2" smd roundrect
			(at 0.7 0 270)
			(size 0.8 1)
			(layers "F.Cu" "F.Mask" "F.Paste")
			(roundrect_rratio 0.2)
			(net 273 "/Power Supply/1V0_OUT")
			(pintype "passive")
		)
	)
	(footprint "antmicro-footprints:C_0603_1608Metric"
		(layer "F.Cu")
		(at 167.03 86.15 90)
		(descr "Capacitor SMD 0603")
		(tags "capacitor 0603")
		(property "Reference" "C112"
			(at -1.49 1.5 90)
			(layer "F.SilkS")
			(effects
				(font
					(size 0.65 0.65)
					(thickness 0.15)
				)
				(justify left bottom)
			)
		)
		(property "Value" "C_1u_0603"
			(at 0 1.6 90)
			(layer "F.Fab")
			(hide yes)
			(effects
				(font
					(size 0.7 0.7)
					(thickness 0.15)
				)
				(justify left bottom)
			)
		)
		(property "Datasheet" "https://spicat.kyocera-avx.com/product/mlcc/chartview/0603YD105KAT2A/"
			(at 0 0 90)
			(layer "F.Fab")
			(hide yes)
			(effects
				(font
					(size 1.27 1.27)
					(thickness 0.15)
				)
			)
		)
		(property "Description" "SMD Multilayer Ceramic Capacitor, 1 µF, 16 V, 0603 [1608 Metric], ± 10%, X5R, AVX 0603 MLCC"
			(at 0 0 90)
			(layer "F.Fab")
			(hide yes)
			(effects
				(font
					(size 1.27 1.27)
					(thickness 0.15)
				)
			)
		)
		(property "Author" "Antmicro"
			(at 253.18 -80.88 0)
			(layer "F.Fab")
			(hide yes)
			(effects
				(font
					(size 1 1)
					(thickness 0.15)
				)
			)
		)
		(property "Dielectric" ""
			(at 253.18 -80.88 0)
			(layer "F.Fab")
			(hide yes)
			(effects
				(font
					(size 1 1)
					(thickness 0.15)
				)
			)
		)
		(property "License" "Apache-2.0"
			(at 253.18 -80.88 0)
			(layer "F.Fab")
			(hide yes)
			(effects
				(font
					(size 1 1)
					(thickness 0.15)
				)
			)
		)
		(property "MPN" "0603YD105KAT2A"
			(at 253.18 -80.88 0)
			(layer "F.Fab")
			(hide yes)
			(effects
				(font
					(size 1 1)
					(thickness 0.15)
				)
			)
		)
		(property "Manufacturer" "KYOCERA AVX"
			(at 253.18 -80.88 0)
			(layer "F.Fab")
			(hide yes)
			(effects
				(font
					(size 1 1)
					(thickness 0.15)
				)
			)
		)
		(property "Val" "1u"
			(at 253.18 -80.88 0)
			(layer "F.Fab")
			(hide yes)
			(effects
				(font
					(size 1 1)
					(thickness 0.15)
				)
			)
		)
		(property "Voltage" ""
			(at 253.18 -80.88 0)
			(layer "F.Fab")
			(hide yes)
			(effects
				(font
					(size 1 1)
					(thickness 0.15)
				)
			)
		)
		(sheetname "/Peripherals/")
		(sheetfile "peripherals.kicad_sch")
		(attr smd)
		(fp_line
			(start -0.15 -0.4)
			(end 0.15 -0.4)
			(stroke
				(width 0.15)
				(type solid)
			)
			(layer "F.SilkS")
		)
		(fp_line
			(start -0.15 0.4)
			(end 0.15 0.4)
			(stroke
				(width 0.15)
				(type solid)
			)
			(layer "F.SilkS")
		)
		(fp_rect
			(start -1.25 -0.65)
			(end 1.25 0.65)
			(stroke
				(width 0.05)
				(type solid)
			)
			(fill no)
			(layer "F.CrtYd")
		)
		(fp_rect
			(start -0.8 -0.4)
			(end 0.8 0.4)
			(stroke
				(width 0.15)
				(type solid)
			)
			(fill no)
			(layer "F.Fab")
		)
		(fp_text user "Author: Antmicro"
			(at -1.682 4.894 90)
			(layer "F.Fab")
			(effects
				(font
					(size 0.7 0.7)
					(thickness 0.15)
				)
				(justify left bottom)
			)
		)
		(fp_text user "${REFERENCE}"
			(at -1.682 3.895 90)
			(layer "F.Fab")
			(effects
				(font
					(size 0.7 0.7)
					(thickness 0.15)
				)
				(justify left bottom)
			)
		)
		(fp_text user "License: Apache-2.0"
			(at -1.682 5.895 90)
			(layer "F.Fab")
			(effects
				(font
					(size 0.7 0.7)
					(thickness 0.15)
				)
				(justify left bottom)
			)
		)
		(pad "1" smd roundrect
			(at -0.7 0 90)
			(size 0.8 1)
			(layers "F.Cu" "F.Mask" "F.Paste")
			(roundrect_rratio 0.2)
			(net 1 "GND")
			(pintype "passive")
		)
		(pad "2" smd roundrect
			(at 0.7 0 90)
			(size 0.8 1)
			(layers "F.Cu" "F.Mask" "F.Paste")
			(roundrect_rratio 0.2)
			(net 16 "/Peripherals/FFC1_5V")
			(pintype "passive")
		)
	)
	(footprint "antmicro-footprints:R_0402_1005Metric"
		(layer "F.Cu")
		(at 113.4 85.6)
		(descr "Resistor SMD 0402")
		(tags "resistor SMD 0402")
		(property "Reference" "R39"
			(at -1.17 -0.66 0)
			(layer "F.SilkS")
			(effects
				(font
					(size 0.65 0.65)
					(thickness 0.15)
				)
				(justify left bottom)
			)
		)
		(property "Value" "R_0R_0402"
			(at 0 1.4 0)
			(layer "F.Fab")
			(hide yes)
			(effects
				(font
					(size 0.7 0.7)
					(thickness 0.15)
				)
				(justify left bottom)
			)
		)
		(property "Datasheet" "https://industrial.panasonic.com/cdbs/www-data/pdf/RDA0000/AOA0000C301.pdf"
			(at 0 0 0)
			(layer "F.Fab")
			(hide yes)
			(effects
				(font
					(size 1.27 1.27)
					(thickness 0.15)
				)
			)
		)
		(property "Description" "SMD Chip Resistor, Jumper, 0 ohm, 100 mW, 0402 [1005 Metric], Thick Film, General Purpose"
			(at 0 0 0)
			(layer "F.Fab")
			(hide yes)
			(effects
				(font
					(size 1.27 1.27)
					(thickness 0.15)
				)
			)
		)
		(property "Author" "Antmicro"
			(at 0 0 0)
			(layer "F.Fab")
			(hide yes)
			(effects
				(font
					(size 1 1)
					(thickness 0.15)
				)
			)
		)
		(property "Current" "1A"
			(at 0 0 0)
			(layer "F.Fab")
			(hide yes)
			(effects
				(font
					(size 1 1)
					(thickness 0.15)
				)
			)
		)
		(property "License" "Apache-2.0"
			(at 0 0 0)
			(layer "F.Fab")
			(hide yes)
			(effects
				(font
					(size 1 1)
					(thickness 0.15)
				)
			)
		)
		(property "MPN" "ERJ2GE0R00X"
			(at 0 0 0)
			(layer "F.Fab")
			(hide yes)
			(effects
				(font
					(size 1 1)
					(thickness 0.15)
				)
			)
		)
		(property "Manufacturer" "Panasonic"
			(at 0 0 0)
			(layer "F.Fab")
			(hide yes)
			(effects
				(font
					(size 1 1)
					(thickness 0.15)
				)
			)
		)
		(property "Tolerance" "~"
			(at 0 0 0)
			(layer "F.Fab")
			(hide yes)
			(effects
				(font
					(size 1 1)
					(thickness 0.15)
				)
			)
		)
		(property "Val" "0R"
			(at 0 0 0)
			(layer "F.Fab")
			(hide yes)
			(effects
				(font
					(size 1 1)
					(thickness 0.15)
				)
			)
		)
		(sheetname "/FPGA/")
		(sheetfile "fpga.kicad_sch")
		(attr smd)
		(fp_rect
			(start -0.925 -0.47)
			(end 0.925 0.47)
			(stroke
				(width 0.05)
				(type default)
			)
			(fill no)
			(layer "F.CrtYd")
		)
		(fp_rect
			(start -0.5 -0.25)
			(end 0.5 0.25)
			(stroke
				(width 0.15)
				(type solid)
			)
			(fill no)
			(layer "F.Fab")
		)
		(fp_text user "${REFERENCE}"
			(at -0.95 3.168 0)
			(layer "F.Fab")
			(effects
				(font
					(size 0.7 0.7)
					(thickness 0.15)
				)
				(justify left bottom)
			)
		)
		(fp_text user "Author: Antmicro"
			(at -0.95 4.169 0)
			(layer "F.Fab")
			(effects
				(font
					(size 0.7 0.7)
					(thickness 0.15)
				)
				(justify left bottom)
			)
		)
		(fp_text user "License: Apache-2.0"
			(at -0.95 5.169 0)
			(layer "F.Fab")
			(effects
				(font
					(size 0.7 0.7)
					(thickness 0.15)
				)
				(justify left bottom)
			)
		)
		(pad "1" smd roundrect
			(at -0.48 0)
			(size 0.59 0.64)
			(layers "F.Cu" "F.Mask" "F.Paste")
			(roundrect_rratio 0.25)
			(net 286 "Net-(Y2-EN)")
			(pintype "passive")
		)
		(pad "2" smd roundrect
			(at 0.48 0)
			(size 0.59 0.64)
			(layers "F.Cu" "F.Mask" "F.Paste")
			(roundrect_rratio 0.25)
			(net 2 "+3V3")
			(pintype "passive")
		)
	)
	(footprint "antmicro-footprints:C_0402_1005Metric"
		(layer "F.Cu")
		(at 88.5 75.4 180)
		(descr "Capacitor SMD 0402")
		(tags "capacitor SMD 0402")
		(property "Reference" "C53"
			(at 0.42 6.26 0)
			(layer "F.SilkS")
			(effects
				(font
					(size 0.65 0.65)
					(thickness 0.15)
				)
				(justify right bottom)
			)
		)
		(property "Value" "C_1u_0402"
			(at 0 1.4 0)
			(layer "F.Fab")
			(hide yes)
			(effects
				(font
					(size 0.7 0.7)
					(thickness 0.15)
				)
				(justify right bottom)
			)
		)
		(property "Datasheet" "https://product.tdk.com/en/search/capacitor/ceramic/mlcc/info?part_no=C1005X6S1A105K050BC"
			(at 0 0 180)
			(layer "F.Fab")
			(hide yes)
			(effects
				(font
					(size 1.27 1.27)
					(thickness 0.15)
				)
			)
		)
		(property "Description" "SMD Multilayer Ceramic Capacitor, 1 µF, 10 V, 0402 [1005 Metric], ± 10%, X6S, C"
			(at 0 0 180)
			(layer "F.Fab")
			(hide yes)
			(effects
				(font
					(size 1.27 1.27)
					(thickness 0.15)
				)
			)
		)
		(property "Author" "Antmicro"
			(at 177 150.8 0)
			(layer "F.Fab")
			(hide yes)
			(effects
				(font
					(size 1 1)
					(thickness 0.15)
				)
			)
		)
		(property "Dielectric" ""
			(at 177 150.8 0)
			(layer "F.Fab")
			(hide yes)
			(effects
				(font
					(size 1 1)
					(thickness 0.15)
				)
			)
		)
		(property "License" "Apache-2.0"
			(at 177 150.8 0)
			(layer "F.Fab")
			(hide yes)
			(effects
				(font
					(size 1 1)
					(thickness 0.15)
				)
			)
		)
		(property "MPN" "C1005X6S1A105K050BC"
			(at 177 150.8 0)
			(layer "F.Fab")
			(hide yes)
			(effects
				(font
					(size 1 1)
					(thickness 0.15)
				)
			)
		)
		(property "Manufacturer" "TDK"
			(at 177 150.8 0)
			(layer "F.Fab")
			(hide yes)
			(effects
				(font
					(size 1 1)
					(thickness 0.15)
				)
			)
		)
		(property "Val" "1u"
			(at 177 150.8 0)
			(layer "F.Fab")
			(hide yes)
			(effects
				(font
					(size 1 1)
					(thickness 0.15)
				)
			)
		)
		(property "Voltage" ""
			(at 177 150.8 0)
			(layer "F.Fab")
			(hide yes)
			(effects
				(font
					(size 1 1)
					(thickness 0.15)
				)
			)
		)
		(sheetname "/SDI/")
		(sheetfile "sdi.kicad_sch")
		(attr smd)
		(fp_rect
			(start -0.925 -0.47)
			(end 0.925 0.47)
			(stroke
				(width 0.05)
				(type default)
			)
			(fill no)
			(layer "F.CrtYd")
		)
		(fp_line
			(start 0.504 0.248)
			(end -0.494 0.248)
			(stroke
				(width 0.15)
				(type solid)
			)
			(layer "F.Fab")
		)
		(fp_line
			(start 0.504 -0.25)
			(end 0.504 0.248)
			(stroke
				(width 0.15)
				(type solid)
			)
			(layer "F.Fab")
		)
		(fp_line
			(start -0.494 0.248)
			(end -0.494 -0.25)
			(stroke
				(width 0.15)
				(type solid)
			)
			(layer "F.Fab")
		)
		(fp_line
			(start -0.494 -0.25)
			(end 0.504 -0.25)
			(stroke
				(width 0.15)
				(type solid)
			)
			(layer "F.Fab")
		)
		(fp_text user "Author: Antmicro"
			(at -0.939 3.399 180)
			(layer "F.Fab")
			(effects
				(font
					(size 0.7 0.7)
					(thickness 0.15)
				)
				(justify left bottom)
			)
		)
		(fp_text user "License: Apache-2.0"
			(at -0.939 5.799 180)
			(layer "F.Fab")
			(effects
				(font
					(size 0.7 0.7)
					(thickness 0.15)
				)
				(justify left bottom)
			)
		)
		(fp_text user "${REFERENCE}"
			(at -0.939 4.599 180)
			(layer "F.Fab")
			(effects
				(font
					(size 0.7 0.7)
					(thickness 0.15)
				)
				(justify left bottom)
			)
		)
		(pad "1" smd roundrect
			(at -0.48 0 180)
			(size 0.59 0.64)
			(layers "F.Cu" "F.Mask" "F.Paste")
			(roundrect_rratio 0.25)
			(net 7 "/SDI/SDI_P")
			(pintype "passive")
		)
		(pad "2" smd roundrect
			(at 0.48 0 180)
			(size 0.59 0.64)
			(layers "F.Cu" "F.Mask" "F.Paste")
			(roundrect_rratio 0.25)
			(net 243 "/SDI/SDI_IN_F")
			(pintype "passive")
		)
	)
	(footprint "antmicro-footprints:TP_SMD_0.75mm"
		(layer "F.Cu")
		(at 126.89 106.45)
		(property "Reference" "TP22"
			(at 0 -0.6 0)
			(layer "F.SilkS")
			(effects
				(font
					(size 0.65 0.65)
					(thickness 0.15)
				)
				(justify left bottom)
			)
		)
		(property "Value" "TP_0.75mm_SMD"
			(at 0 1.2 0)
			(layer "F.Fab")
			(hide yes)
			(effects
				(font
					(size 0.7 0.7)
					(thickness 0.15)
				)
				(justify left bottom)
			)
		)
		(property "Description" "SMT test point"
			(at 0 0 0)
			(layer "F.Fab")
			(hide yes)
			(effects
				(font
					(size 1.27 1.27)
					(thickness 0.15)
				)
			)
		)
		(property "Author" "Antmicro"
			(at 0 0 0)
			(layer "F.Fab")
			(hide yes)
			(effects
				(font
					(size 1 1)
					(thickness 0.15)
				)
			)
		)
		(property "License" "Apache-2.0"
			(at 0 0 0)
			(layer "F.Fab")
			(hide yes)
			(effects
				(font
					(size 1 1)
					(thickness 0.15)
				)
			)
		)
		(property "MPN" ""
			(at 0 0 0)
			(layer "F.Fab")
			(hide yes)
			(effects
				(font
					(size 1 1)
					(thickness 0.15)
				)
			)
		)
		(property "Manufacturer" ""
			(at 0 0 0)
			(layer "F.Fab")
			(hide yes)
			(effects
				(font
					(size 1 1)
					(thickness 0.15)
				)
			)
		)
		(sheetname "/FPGA/")
		(sheetfile "fpga.kicad_sch")
		(attr exclude_from_pos_files)
		(fp_circle
			(center 0 0)
			(end 0.475 0)
			(stroke
				(width 0.05)
				(type default)
			)
			(fill no)
			(layer "F.CrtYd")
		)
		(fp_text user "Author: Antmicro"
			(at -0.4 3.901 0)
			(layer "F.Fab")
			(effects
				(font
					(size 0.7 0.7)
					(thickness 0.15)
				)
				(justify left bottom)
			)
		)
		(fp_text user "License: Apache-2.0"
			(at -0.4 5.101 0)
			(layer "F.Fab")
			(effects
				(font
					(size 0.7 0.7)
					(thickness 0.15)
				)
				(justify left bottom)
			)
		)
		(fp_text user "${REFERENCE}"
			(at -0.4 2.7 0)
			(layer "F.Fab")
			(effects
				(font
					(size 0.7 0.7)
					(thickness 0.15)
				)
				(justify left bottom)
			)
		)
		(pad "1" smd circle
			(at 0 0)
			(size 0.75 0.75)
			(layers "F.Cu" "F.Mask")
			(net 15 "/FPGA/INITN")
			(pinfunction "1")
			(pintype "passive")
		)
	)
	(footprint "antmicro-footprints:C_0603_1608Metric"
		(layer "F.Cu")
		(at 138.79 115.9 90)
		(descr "Capacitor SMD 0603")
		(tags "capacitor 0603")
		(property "Reference" "C30"
			(at -3.44 0.44 90)
			(layer "F.SilkS")
			(effects
				(font
					(size 0.65 0.65)
					(thickness 0.15)
				)
				(justify left bottom)
			)
		)
		(property "Value" "C_1u_0603"
			(at 0 1.6 90)
			(layer "F.Fab")
			(hide yes)
			(effects
				(font
					(size 0.7 0.7)
					(thickness 0.15)
				)
				(justify left bottom)
			)
		)
		(property "Datasheet" "https://spicat.kyocera-avx.com/product/mlcc/chartview/0603YD105KAT2A/"
			(at 0 0 90)
			(layer "F.Fab")
			(hide yes)
			(effects
				(font
					(size 1.27 1.27)
					(thickness 0.15)
				)
			)
		)
		(property "Description" "SMD Multilayer Ceramic Capacitor, 1 µF, 16 V, 0603 [1608 Metric], ± 10%, X5R, AVX 0603 MLCC"
			(at 0 0 90)
			(layer "F.Fab")
			(hide yes)
			(effects
				(font
					(size 1.27 1.27)
					(thickness 0.15)
				)
			)
		)
		(property "Author" "Antmicro"
			(at 254.69 -22.89 0)
			(layer "F.Fab")
			(hide yes)
			(effects
				(font
					(size 1 1)
					(thickness 0.15)
				)
			)
		)
		(property "Dielectric" ""
			(at 254.69 -22.89 0)
			(layer "F.Fab")
			(hide yes)
			(effects
				(font
					(size 1 1)
					(thickness 0.15)
				)
			)
		)
		(property "License" "Apache-2.0"
			(at 254.69 -22.89 0)
			(layer "F.Fab")
			(hide yes)
			(effects
				(font
					(size 1 1)
					(thickness 0.15)
				)
			)
		)
		(property "MPN" "0603YD105KAT2A"
			(at 254.69 -22.89 0)
			(layer "F.Fab")
			(hide yes)
			(effects
				(font
					(size 1 1)
					(thickness 0.15)
				)
			)
		)
		(property "Manufacturer" "KYOCERA AVX"
			(at 254.69 -22.89 0)
			(layer "F.Fab")
			(hide yes)
			(effects
				(font
					(size 1 1)
					(thickness 0.15)
				)
			)
		)
		(property "Val" "1u"
			(at 254.69 -22.89 0)
			(layer "F.Fab")
			(hide yes)
			(effects
				(font
					(size 1 1)
					(thickness 0.15)
				)
			)
		)
		(property "Voltage" ""
			(at 254.69 -22.89 0)
			(layer "F.Fab")
			(hide yes)
			(effects
				(font
					(size 1 1)
					(thickness 0.15)
				)
			)
		)
		(sheetname "/Power Supply/")
		(sheetfile "supply.kicad_sch")
		(attr smd)
		(fp_line
			(start -0.15 -0.4)
			(end 0.15 -0.4)
			(stroke
				(width 0.15)
				(type solid)
			)
			(layer "F.SilkS")
		)
		(fp_line
			(start -0.15 0.4)
			(end 0.15 0.4)
			(stroke
				(width 0.15)
				(type solid)
			)
			(layer "F.SilkS")
		)
		(fp_rect
			(start -1.25 -0.65)
			(end 1.25 0.65)
			(stroke
				(width 0.05)
				(type solid)
			)
			(fill no)
			(layer "F.CrtYd")
		)
		(fp_rect
			(start -0.8 -0.4)
			(end 0.8 0.4)
			(stroke
				(width 0.15)
				(type solid)
			)
			(fill no)
			(layer "F.Fab")
		)
		(fp_text user "License: Apache-2.0"
			(at -1.682 5.895 90)
			(layer "F.Fab")
			(effects
				(font
					(size 0.7 0.7)
					(thickness 0.15)
				)
				(justify left bottom)
			)
		)
		(fp_text user "Author: Antmicro"
			(at -1.682 4.894 90)
			(layer "F.Fab")
			(effects
				(font
					(size 0.7 0.7)
					(thickness 0.15)
				)
				(justify left bottom)
			)
		)
		(fp_text user "${REFERENCE}"
			(at -1.682 3.895 90)
			(layer "F.Fab")
			(effects
				(font
					(size 0.7 0.7)
					(thickness 0.15)
				)
				(justify left bottom)
			)
		)
		(pad "1" smd roundrect
			(at -0.7 0 90)
			(size 0.8 1)
			(layers "F.Cu" "F.Mask" "F.Paste")
			(roundrect_rratio 0.2)
			(net 1 "GND")
			(pintype "passive")
		)
		(pad "2" smd roundrect
			(at 0.7 0 90)
			(size 0.8 1)
			(layers "F.Cu" "F.Mask" "F.Paste")
			(roundrect_rratio 0.2)
			(net 3 "+1V2")
			(pintype "passive")
		)
	)
	(footprint "antmicro-footprints:R_0402_1005Metric"
		(layer "F.Cu")
		(at 163.19 59.04 180)
		(descr "Resistor SMD 0402")
		(tags "resistor SMD 0402")
		(property "Reference" "R26"
			(at 1.06 0.7 180)
			(layer "F.SilkS")
			(effects
				(font
					(size 0.65 0.65)
					(thickness 0.15)
				)
				(justify left bottom)
			)
		)
		(property "Value" "R_33k_0402"
			(at 0 1.4 180)
			(layer "F.Fab")
			(hide yes)
			(effects
				(font
					(size 0.7 0.7)
					(thickness 0.15)
				)
				(justify left bottom)
			)
		)
		(property "Datasheet" "https://www.bourns.com/docs/product-datasheets/cr.pdf"
			(at 0 0 180)
			(layer "F.Fab")
			(hide yes)
			(effects
				(font
					(size 1.27 1.27)
					(thickness 0.15)
				)
			)
		)
		(property "Description" "SMD Chip Resistor, 33 kohm, ± 1%, 62.5 mW, 0402 [1005 Metric], Thick Film, General Purpose"
			(at 0 0 180)
			(layer "F.Fab")
			(hide yes)
			(effects
				(font
					(size 1.27 1.27)
					(thickness 0.15)
				)
			)
		)
		(property "Author" "Antmicro"
			(at 326.38 118.08 0)
			(layer "F.Fab")
			(hide yes)
			(effects
				(font
					(size 1 1)
					(thickness 0.15)
				)
			)
		)
		(property "License" "Apache-2.0"
			(at 326.38 118.08 0)
			(layer "F.Fab")
			(hide yes)
			(effects
				(font
					(size 1 1)
					(thickness 0.15)
				)
			)
		)
		(property "MPN" "CR0402-FX-3302GLF"
			(at 326.38 118.08 0)
			(layer "F.Fab")
			(hide yes)
			(effects
				(font
					(size 1 1)
					(thickness 0.15)
				)
			)
		)
		(property "Manufacturer" "Bourns"
			(at 326.38 118.08 0)
			(layer "F.Fab")
			(hide yes)
			(effects
				(font
					(size 1 1)
					(thickness 0.15)
				)
			)
		)
		(property "Tolerance" "1%"
			(at 326.38 118.08 0)
			(layer "F.Fab")
			(hide yes)
			(effects
				(font
					(size 1 1)
					(thickness 0.15)
				)
			)
		)
		(property "Val" "33k"
			(at 326.38 118.08 0)
			(layer "F.Fab")
			(hide yes)
			(effects
				(font
					(size 1 1)
					(thickness 0.15)
				)
			)
		)
		(sheetname "/Power Supply/")
		(sheetfile "supply.kicad_sch")
		(attr smd)
		(fp_rect
			(start -0.925 -0.47)
			(end 0.925 0.47)
			(stroke
				(width 0.05)
				(type default)
			)
			(fill no)
			(layer "F.CrtYd")
		)
		(fp_rect
			(start -0.5 -0.25)
			(end 0.5 0.25)
			(stroke
				(width 0.15)
				(type solid)
			)
			(fill no)
			(layer "F.Fab")
		)
		(fp_text user "${REFERENCE}"
			(at -0.95 3.168 180)
			(layer "F.Fab")
			(effects
				(font
					(size 0.7 0.7)
					(thickness 0.15)
				)
				(justify left bottom)
			)
		)
		(fp_text user "License: Apache-2.0"
			(at -0.95 5.169 180)
			(layer "F.Fab")
			(effects
				(font
					(size 0.7 0.7)
					(thickness 0.15)
				)
				(justify left bottom)
			)
		)
		(fp_text user "Author: Antmicro"
			(at -0.95 4.169 180)
			(layer "F.Fab")
			(effects
				(font
					(size 0.7 0.7)
					(thickness 0.15)
				)
				(justify left bottom)
			)
		)
		(pad "1" smd roundrect
			(at -0.48 0 180)
			(size 0.59 0.64)
			(layers "F.Cu" "F.Mask" "F.Paste")
			(roundrect_rratio 0.25)
			(net 270 "Net-(U7-FB)")
			(pintype "passive")
		)
		(pad "2" smd roundrect
			(at 0.48 0 180)
			(size 0.59 0.64)
			(layers "F.Cu" "F.Mask" "F.Paste")
			(roundrect_rratio 0.25)
			(net 275 "/Power Supply/3V3_OUT")
			(pintype "passive")
		)
	)
	(footprint "antmicro-footprints:R_0402_1005Metric"
		(layer "F.Cu")
		(at 167.2 91.6)
		(descr "Resistor SMD 0402")
		(tags "resistor SMD 0402")
		(property "Reference" "R124"
			(at -3.67 0.34 0)
			(layer "F.SilkS")
			(effects
				(font
					(size 0.65 0.65)
					(thickness 0.15)
				)
				(justify left bottom)
			)
		)
		(property "Value" "R_0R_0402"
			(at 0 1.4 0)
			(layer "F.Fab")
			(hide yes)
			(effects
				(font
					(size 0.7 0.7)
					(thickness 0.15)
				)
				(justify left bottom)
			)
		)
		(property "Datasheet" "https://industrial.panasonic.com/cdbs/www-data/pdf/RDA0000/AOA0000C301.pdf"
			(at 0 0 0)
			(layer "F.Fab")
			(hide yes)
			(effects
				(font
					(size 1.27 1.27)
					(thickness 0.15)
				)
			)
		)
		(property "Description" "SMD Chip Resistor, Jumper, 0 ohm, 100 mW, 0402 [1005 Metric], Thick Film, General Purpose"
			(at 0 0 0)
			(layer "F.Fab")
			(hide yes)
			(effects
				(font
					(size 1.27 1.27)
					(thickness 0.15)
				)
			)
		)
		(property "Author" "Antmicro"
			(at 0 0 0)
			(layer "F.Fab")
			(hide yes)
			(effects
				(font
					(size 1 1)
					(thickness 0.15)
				)
			)
		)
		(property "Current" "1A"
			(at 0 0 0)
			(layer "F.Fab")
			(hide yes)
			(effects
				(font
					(size 1 1)
					(thickness 0.15)
				)
			)
		)
		(property "License" "Apache-2.0"
			(at 0 0 0)
			(layer "F.Fab")
			(hide yes)
			(effects
				(font
					(size 1 1)
					(thickness 0.15)
				)
			)
		)
		(property "MPN" "ERJ2GE0R00X"
			(at 0 0 0)
			(layer "F.Fab")
			(hide yes)
			(effects
				(font
					(size 1 1)
					(thickness 0.15)
				)
			)
		)
		(property "Manufacturer" "Panasonic"
			(at 0 0 0)
			(layer "F.Fab")
			(hide yes)
			(effects
				(font
					(size 1 1)
					(thickness 0.15)
				)
			)
		)
		(property "Tolerance" "~"
			(at 0 0 0)
			(layer "F.Fab")
			(hide yes)
			(effects
				(font
					(size 1 1)
					(thickness 0.15)
				)
			)
		)
		(property "Val" "0R"
			(at 0 0 0)
			(layer "F.Fab")
			(hide yes)
			(effects
				(font
					(size 1 1)
					(thickness 0.15)
				)
			)
		)
		(sheetname "/Peripherals/")
		(sheetfile "peripherals.kicad_sch")
		(attr smd)
		(fp_rect
			(start -0.925 -0.47)
			(end 0.925 0.47)
			(stroke
				(width 0.05)
				(type default)
			)
			(fill no)
			(layer "F.CrtYd")
		)
		(fp_rect
			(start -0.5 -0.25)
			(end 0.5 0.25)
			(stroke
				(width 0.15)
				(type solid)
			)
			(fill no)
			(layer "F.Fab")
		)
		(fp_text user "License: Apache-2.0"
			(at -0.95 5.169 0)
			(layer "F.Fab")
			(effects
				(font
					(size 0.7 0.7)
					(thickness 0.15)
				)
				(justify left bottom)
			)
		)
		(fp_text user "Author: Antmicro"
			(at -0.95 4.169 0)
			(layer "F.Fab")
			(effects
				(font
					(size 0.7 0.7)
					(thickness 0.15)
				)
				(justify left bottom)
			)
		)
		(fp_text user "${REFERENCE}"
			(at -0.95 3.168 0)
			(layer "F.Fab")
			(effects
				(font
					(size 0.7 0.7)
					(thickness 0.15)
				)
				(justify left bottom)
			)
		)
		(pad "1" smd roundrect
			(at -0.48 0)
			(size 0.59 0.64)
			(layers "F.Cu" "F.Mask" "F.Paste")
			(roundrect_rratio 0.25)
			(net 93 "/Peripherals/FCC1_SDA2")
			(pintype "passive")
		)
		(pad "2" smd roundrect
			(at 0.48 0)
			(size 0.59 0.64)
			(layers "F.Cu" "F.Mask" "F.Paste")
			(roundrect_rratio 0.25)
			(net 365 "Net-(J4-Pad41)")
			(pintype "passive")
		)
	)
	(footprint "antmicro-footprints:L_Coilcraft-XEL4030"
		(layer "F.Cu")
		(at 142.48 59.29 -90)
		(property "Reference" "L2"
			(at -2.65 2.15 0)
			(layer "F.SilkS")
			(effects
				(font
					(size 0.65 0.65)
					(thickness 0.15)
				)
				(justify left bottom)
			)
		)
		(property "Value" "L_3u3_5.9A_XEL4030"
			(at 0 3.35 270)
			(layer "F.Fab")
			(hide yes)
			(effects
				(font
					(size 0.7 0.7)
					(thickness 0.15)
				)
				(justify left bottom)
			)
		)
		(property "Datasheet" "https://www.coilcraft.com/getmedia/8245f050-f190-4295-8c41-7c03d662ee3d/xel4030.pdf"
			(at 0 0 270)
			(layer "F.Fab")
			(hide yes)
			(effects
				(font
					(size 1.27 1.27)
					(thickness 0.15)
				)
			)
		)
		(property "Description" "Power Inductor (SMT), AEC-Q200, 3.3 µH, 6.6 A, Shielded, 5.9 A, XEL4030"
			(at 0 0 270)
			(layer "F.Fab")
			(hide yes)
			(effects
				(font
					(size 1.27 1.27)
					(thickness 0.15)
				)
			)
		)
		(property "Author" "Antmicro"
			(at 83.19 201.77 0)
			(layer "F.Fab")
			(hide yes)
			(effects
				(font
					(size 1 1)
					(thickness 0.15)
				)
			)
		)
		(property "IMax" "6.6 A"
			(at 83.19 201.77 0)
			(layer "F.Fab")
			(hide yes)
			(effects
				(font
					(size 1 1)
					(thickness 0.15)
				)
			)
		)
		(property "ISat" "5.9 A"
			(at 83.19 201.77 0)
			(layer "F.Fab")
			(hide yes)
			(effects
				(font
					(size 1 1)
					(thickness 0.15)
				)
			)
		)
		(property "License" "Apache-2.0"
			(at 83.19 201.77 0)
			(layer "F.Fab")
			(hide yes)
			(effects
				(font
					(size 1 1)
					(thickness 0.15)
				)
			)
		)
		(property "MPN" "XEL4030-332MEC"
			(at 83.19 201.77 0)
			(layer "F.Fab")
			(hide yes)
			(effects
				(font
					(size 1 1)
					(thickness 0.15)
				)
			)
		)
		(property "Manufacturer" "Coilcraft"
			(at 83.19 201.77 0)
			(layer "F.Fab")
			(hide yes)
			(effects
				(font
					(size 1 1)
					(thickness 0.15)
				)
			)
		)
		(property "Size" "4.0x4.0"
			(at 83.19 201.77 0)
			(layer "F.Fab")
			(hide yes)
			(effects
				(font
					(size 1 1)
					(thickness 0.15)
				)
			)
		)
		(property "Val" "3u3/6.6A"
			(at 83.19 201.77 0)
			(layer "F.Fab")
			(hide yes)
			(effects
				(font
					(size 1 1)
					(thickness 0.15)
				)
			)
		)
		(sheetname "/Power Supply/")
		(sheetfile "supply.kicad_sch")
		(attr smd)
		(fp_line
			(start -2.2 2.2)
			(end 2.2 2.2)
			(stroke
				(width 0.15)
				(type solid)
			)
			(layer "F.SilkS")
		)
		(fp_line
			(start -2.2 2.2)
			(end -2.2 -2.2)
			(stroke
				(width 0.15)
				(type solid)
			)
			(layer "F.SilkS")
		)
		(fp_line
			(start 2.2 2.2)
			(end 2.2 -2.2)
			(stroke
				(width 0.15)
				(type solid)
			)
			(layer "F.SilkS")
		)
		(fp_line
			(start -2.2 -2.2)
			(end 2.2 -2.2)
			(stroke
				(width 0.15)
				(type solid)
			)
			(layer "F.SilkS")
		)
		(fp_rect
			(start -2.4 -2.4)
			(end 2.4 2.4)
			(stroke
				(width 0.05)
				(type solid)
			)
			(fill no)
			(layer "F.CrtYd")
		)
		(fp_rect
			(start -2.15 -2.15)
			(end 2.15 2.15)
			(stroke
				(width 0.15)
				(type solid)
			)
			(fill no)
			(layer "F.Fab")
		)
		(fp_text user "${REFERENCE}"
			(at -2.4 6.55 270)
			(layer "F.Fab")
			(effects
				(font
					(size 0.7 0.7)
					(thickness 0.15)
				)
				(justify left bottom)
			)
		)
		(fp_text user "Author: Antmicro"
			(at -2.4 5.35 270)
			(layer "F.Fab")
			(effects
				(font
					(size 0.7 0.7)
					(thickness 0.15)
				)
				(justify left bottom)
			)
		)
		(fp_text user "License: Apache-2.0"
			(at -2.4 7.75 270)
			(layer "F.Fab")
			(effects
				(font
					(size 0.7 0.7)
					(thickness 0.15)
				)
				(justify left bottom)
			)
		)
		(pad "1" smd roundrect
			(at -1.185 0 270)
			(size 0.98 3.4)
			(layers "F.Cu" "F.Mask" "F.Paste")
			(roundrect_rratio 0.1)
			(net 277 "/Power Supply/1V5_SW")
			(pintype "passive")
		)
		(pad "2" smd roundrect
			(at 1.185 0 270)
			(size 0.98 3.4)
			(layers "F.Cu" "F.Mask" "F.Paste")
			(roundrect_rratio 0.1)
			(net 274 "/Power Supply/1V5_OUT")
			(pintype "passive")
		)
	)
	(footprint "antmicro-footprints:LED_0603_1608Metric_G"
		(layer "F.Cu")
		(at 127 109.65 -90)
		(descr "LED SMD 0603 Green")
		(tags "LED SMD 0603 Green")
		(property "Reference" "D5"
			(at -2.71 0.37 90)
			(layer "F.SilkS")
			(effects
				(font
					(size 0.65 0.65)
					(thickness 0.15)
				)
				(justify right top)
			)
		)
		(property "Value" "LED_G_0603_LTST-C190GKT"
			(at 0 1.6 90)
			(layer "F.Fab")
			(hide yes)
			(effects
				(font
					(size 0.7 0.7)
					(thickness 0.15)
				)
				(justify right top)
			)
		)
		(property "Datasheet" "https://media.digikey.com/pdf/Data%20Sheets/Lite-On%20PDFs/LTST-C190GKT.pdf"
			(at 0 0 90)
			(layer "F.Fab")
			(hide yes)
			(effects
				(font
					(size 1.27 1.27)
					(thickness 0.15)
				)
			)
		)
		(property "Description" "LED, Green, SMD, 0603, 20 mA, 2.1 V, 569 nm"
			(at 0 0 90)
			(layer "F.Fab")
			(hide yes)
			(effects
				(font
					(size 1.27 1.27)
					(thickness 0.15)
				)
			)
		)
		(property "Author" "Antmicro"
			(at 236.65 -17.35 0)
			(layer "F.Fab")
			(hide yes)
			(effects
				(font
					(size 1 1)
					(thickness 0.15)
				)
			)
		)
		(property "License" "Apache-2.0"
			(at 236.65 -17.35 0)
			(layer "F.Fab")
			(hide yes)
			(effects
				(font
					(size 1 1)
					(thickness 0.15)
				)
			)
		)
		(property "MPN" "LTST-C190GKT"
			(at 236.65 -17.35 0)
			(layer "F.Fab")
			(hide yes)
			(effects
				(font
					(size 1 1)
					(thickness 0.15)
				)
			)
		)
		(property "Manufacturer" "Lite-On"
			(at 236.65 -17.35 0)
			(layer "F.Fab")
			(hide yes)
			(effects
				(font
					(size 1 1)
					(thickness 0.15)
				)
			)
		)
		(property "Color" "Green"
			(at 0 0 270)
			(unlocked yes)
			(layer "F.Fab")
			(hide yes)
			(effects
				(font
					(size 1 1)
					(thickness 0.15)
				)
			)
		)
		(sheetname "/FPGA/")
		(sheetfile "fpga.kicad_sch")
		(attr smd)
		(fp_line
			(start 0.22 0.35)
			(end -0.22 0.35)
			(stroke
				(width 0.15)
				(type solid)
			)
			(layer "F.SilkS")
		)
		(fp_line
			(start -0.094672 0.201008)
			(end -0.094672 -0.198992)
			(stroke
				(width 0.1)
				(type solid)
			)
			(layer "F.SilkS")
		)
		(fp_line
			(start 0.105328 0.201008)
			(end -0.094672 0.001008)
			(stroke
				(width 0.1)
				(type solid)
			)
			(layer "F.SilkS")
		)
		(fp_line
			(start 0.105328 0.201008)
			(end 0.105328 -0.198992)
			(stroke
				(width 0.1)
				(type solid)
			)
			(layer "F.SilkS")
		)
		(fp_line
			(start -0.094672 0.001008)
			(end -0.24 0.001008)
			(stroke
				(width 0.1)
				(type solid)
			)
			(layer "F.SilkS")
		)
		(fp_line
			(start -0.094672 0.001008)
			(end 0.105328 -0.198992)
			(stroke
				(width 0.1)
				(type solid)
			)
			(layer "F.SilkS")
		)
		(fp_line
			(start 0.105328 0.001008)
			(end 0.24 0.001)
			(stroke
				(width 0.1)
				(type solid)
			)
			(layer "F.SilkS")
		)
		(fp_line
			(start -1.18 -0.319)
			(end -1.18 0.321)
			(stroke
				(width 0.15)
				(type solid)
			)
			(layer "F.SilkS")
		)
		(fp_line
			(start 0.22 -0.35)
			(end -0.22 -0.35)
			(stroke
				(width 0.15)
				(type solid)
			)
			(layer "F.SilkS")
		)
		(fp_rect
			(start 1.25 0.65)
			(end -1.25 -0.65)
			(stroke
				(width 0.05)
				(type solid)
			)
			(fill no)
			(layer "F.CrtYd")
		)
		(fp_line
			(start -0.199 0.2)
			(end -0.199 0.1)
			(stroke
				(width 0.15)
				(type solid)
			)
			(layer "F.Fab")
		)
		(fp_line
			(start 0.201 0.2)
			(end 0.201 0)
			(stroke
				(width 0.15)
				(type solid)
			)
			(layer "F.Fab")
		)
		(fp_line
			(start -0.199 0)
			(end -0.597 0)
			(stroke
				(width 0.15)
				(type solid)
			)
			(layer "F.Fab")
		)
		(fp_line
			(start -0.101 0)
			(end 0.201 0.2)
			(stroke
				(width 0.15)
				(type solid)
			)
			(layer "F.Fab")
		)
		(fp_line
			(start 0.201 0)
			(end 0.201 -0.202)
			(stroke
				(width 0.15)
				(type solid)
			)
			(layer "F.Fab")
		)
		(fp_line
			(start 0.599 0)
			(end 0.201 0)
			(stroke
				(width 0.15)
				(type solid)
			)
			(layer "F.Fab")
		)
		(fp_line
			(start -0.199 -0.202)
			(end -0.199 0.1)
			(stroke
				(width 0.15)
				(type solid)
			)
			(layer "F.Fab")
		)
		(fp_line
			(start 0.201 -0.202)
			(end -0.101 0)
			(stroke
				(width 0.15)
				(type solid)
			)
			(layer "F.Fab")
		)
		(fp_rect
			(start 0.848 0.4)
			(end -0.85 -0.402)
			(stroke
				(width 0.15)
				(type solid)
			)
			(fill no)
			(layer "F.Fab")
		)
		(fp_text user "Author: Antmicro"
			(at -1.4224 4.799 90)
			(layer "F.Fab")
			(effects
				(font
					(size 0.7 0.7)
					(thickness 0.15)
				)
				(justify right top)
			)
		)
		(fp_text user "${REFERENCE}"
			(at -1.4224 5.999 90)
			(layer "F.Fab")
			(effects
				(font
					(size 0.7 0.7)
					(thickness 0.15)
				)
				(justify right top)
			)
		)
		(fp_text user "License: Apache-2.0"
			(at -1.4224 3.599 90)
			(layer "F.Fab")
			(effects
				(font
					(size 0.7 0.7)
					(thickness 0.15)
				)
				(justify right top)
			)
		)
		(pad "1" smd roundrect
			(at -0.7 0 90)
			(size 0.8 1)
			(layers "F.Cu" "F.Mask" "F.Paste")
			(roundrect_rratio 0.2)
			(net 66 "Net-(D5-C)")
			(pinfunction "C")
			(pintype "passive")
		)
		(pad "2" smd roundrect
			(at 0.7 0 90)
			(size 0.8 1)
			(layers "F.Cu" "F.Mask" "F.Paste")
			(roundrect_rratio 0.2)
			(net 67 "Net-(D5-A)")
			(pinfunction "A")
			(pintype "passive")
		)
	)
	(footprint "antmicro-footprints:R_0603_1608Metric"
		(layer "F.Cu")
		(at 158.53 88.65 90)
		(descr "Resistor SMD 0603")
		(tags "resistor SMD 0603")
		(property "Reference" "R105"
			(at 1.21 -1.1 90)
			(layer "F.SilkS")
			(effects
				(font
					(size 0.65 0.65)
					(thickness 0.15)
				)
				(justify left bottom)
			)
		)
		(property "Value" "R_10k_0603"
			(at 0 1.6 90)
			(layer "F.Fab")
			(hide yes)
			(effects
				(font
					(size 0.7 0.7)
					(thickness 0.15)
				)
				(justify left bottom)
			)
		)
		(property "Datasheet" "https://www.bourns.com/docs/product-datasheets/cr.pdf"
			(at 0 0 90)
			(layer "F.Fab")
			(hide yes)
			(effects
				(font
					(size 1.27 1.27)
					(thickness 0.15)
				)
			)
		)
		(property "Description" "SMD Chip Resistor, 10 kohm, ± 1%, 100 mW, 0603 [1608 Metric], Thick Film, General Purpose"
			(at 0 0 90)
			(layer "F.Fab")
			(hide yes)
			(effects
				(font
					(size 1.27 1.27)
					(thickness 0.15)
				)
			)
		)
		(property "Author" "Antmicro"
			(at 247.18 -69.88 0)
			(layer "F.Fab")
			(hide yes)
			(effects
				(font
					(size 1 1)
					(thickness 0.15)
				)
			)
		)
		(property "License" "Apache-2.0"
			(at 247.18 -69.88 0)
			(layer "F.Fab")
			(hide yes)
			(effects
				(font
					(size 1 1)
					(thickness 0.15)
				)
			)
		)
		(property "MPN" "CR0603-FX-1002ELF"
			(at 247.18 -69.88 0)
			(layer "F.Fab")
			(hide yes)
			(effects
				(font
					(size 1 1)
					(thickness 0.15)
				)
			)
		)
		(property "Manufacturer" "Bourns"
			(at 247.18 -69.88 0)
			(layer "F.Fab")
			(hide yes)
			(effects
				(font
					(size 1 1)
					(thickness 0.15)
				)
			)
		)
		(property "Tolerance" "1%"
			(at 247.18 -69.88 0)
			(layer "F.Fab")
			(hide yes)
			(effects
				(font
					(size 1 1)
					(thickness 0.15)
				)
			)
		)
		(property "Val" "10k"
			(at 247.18 -69.88 0)
			(layer "F.Fab")
			(hide yes)
			(effects
				(font
					(size 1 1)
					(thickness 0.15)
				)
			)
		)
		(sheetname "/Peripherals/")
		(sheetfile "peripherals.kicad_sch")
		(attr smd)
		(fp_line
			(start -0.15 -0.4)
			(end 0.15 -0.4)
			(stroke
				(width 0.15)
				(type solid)
			)
			(layer "F.SilkS")
		)
		(fp_line
			(start -0.15 0.4)
			(end 0.15 0.4)
			(stroke
				(width 0.15)
				(type solid)
			)
			(layer "F.SilkS")
		)
		(fp_rect
			(start -1.25 -0.65)
			(end 1.25 0.65)
			(stroke
				(width 0.05)
				(type solid)
			)
			(fill no)
			(layer "F.CrtYd")
		)
		(fp_rect
			(start -0.8 -0.4)
			(end 0.8 0.4)
			(stroke
				(width 0.15)
				(type solid)
			)
			(fill no)
			(layer "F.Fab")
		)
		(fp_text user "${REFERENCE}"
			(at -1.25 3.898 90)
			(layer "F.Fab")
			(effects
				(font
					(size 0.7 0.7)
					(thickness 0.15)
				)
				(justify left bottom)
			)
		)
		(fp_text user "Author: Antmicro"
			(at -1.25 4.9 90)
			(layer "F.Fab")
			(effects
				(font
					(size 0.7 0.7)
					(thickness 0.15)
				)
				(justify left bottom)
			)
		)
		(fp_text user "License: Apache-2.0"
			(at -1.25 5.9 90)
			(layer "F.Fab")
			(effects
				(font
					(size 0.7 0.7)
					(thickness 0.15)
				)
				(justify left bottom)
			)
		)
		(pad "1" smd roundrect
			(at -0.7 0 90)
			(size 0.8 1)
			(layers "F.Cu" "F.Mask" "F.Paste")
			(roundrect_rratio 0.2)
			(net 2 "+3V3")
			(pintype "passive")
		)
		(pad "2" smd roundrect
			(at 0.7 0 90)
			(size 0.8 1)
			(layers "F.Cu" "F.Mask" "F.Paste")
			(roundrect_rratio 0.2)
			(net 307 "/Peripherals/FFC1_PEN")
			(pintype "passive")
		)
	)
	(footprint "antmicro-footprints:R_0603_1608Metric"
		(layer "F.Cu")
		(at 162.83 116.35 90)
		(descr "Resistor SMD 0603")
		(tags "resistor SMD 0603")
		(property "Reference" "R112"
			(at 1.21 0.4 90)
			(layer "F.SilkS")
			(effects
				(font
					(size 0.65 0.65)
					(thickness 0.15)
				)
				(justify left bottom)
			)
		)
		(property "Value" "R_200R_0603"
			(at 0 1.6 90)
			(layer "F.Fab")
			(hide yes)
			(effects
				(font
					(size 0.7 0.7)
					(thickness 0.15)
				)
				(justify left bottom)
			)
		)
		(property "Datasheet" "https://www.bourns.com/docs/product-datasheets/cr.pdf"
			(at 0 0 90)
			(layer "F.Fab")
			(hide yes)
			(effects
				(font
					(size 1.27 1.27)
					(thickness 0.15)
				)
			)
		)
		(property "Description" "SMD Chip Resistor, 200 ohm, ± 1%, 100 mW, 0603 [1608 Metric], Thick Film, General Purpose"
			(at 0 0 90)
			(layer "F.Fab")
			(hide yes)
			(effects
				(font
					(size 1.27 1.27)
					(thickness 0.15)
				)
			)
		)
		(property "Author" "Antmicro"
			(at 279.18 -46.48 0)
			(layer "F.Fab")
			(hide yes)
			(effects
				(font
					(size 1 1)
					(thickness 0.15)
				)
			)
		)
		(property "License" "Apache-2.0"
			(at 279.18 -46.48 0)
			(layer "F.Fab")
			(hide yes)
			(effects
				(font
					(size 1 1)
					(thickness 0.15)
				)
			)
		)
		(property "MPN" "CR0603-FX-2000ELF"
			(at 279.18 -46.48 0)
			(layer "F.Fab")
			(hide yes)
			(effects
				(font
					(size 1 1)
					(thickness 0.15)
				)
			)
		)
		(property "Manufacturer" "Bourns"
			(at 279.18 -46.48 0)
			(layer "F.Fab")
			(hide yes)
			(effects
				(font
					(size 1 1)
					(thickness 0.15)
				)
			)
		)
		(property "Tolerance" "1%"
			(at 279.18 -46.48 0)
			(layer "F.Fab")
			(hide yes)
			(effects
				(font
					(size 1 1)
					(thickness 0.15)
				)
			)
		)
		(property "Val" "200R"
			(at 279.18 -46.48 0)
			(layer "F.Fab")
			(hide yes)
			(effects
				(font
					(size 1 1)
					(thickness 0.15)
				)
			)
		)
		(sheetname "/Peripherals/")
		(sheetfile "peripherals.kicad_sch")
		(attr smd)
		(fp_line
			(start -0.15 -0.4)
			(end 0.15 -0.4)
			(stroke
				(width 0.15)
				(type solid)
			)
			(layer "F.SilkS")
		)
		(fp_line
			(start -0.15 0.4)
			(end 0.15 0.4)
			(stroke
				(width 0.15)
				(type solid)
			)
			(layer "F.SilkS")
		)
		(fp_rect
			(start -1.25 -0.65)
			(end 1.25 0.65)
			(stroke
				(width 0.05)
				(type solid)
			)
			(fill no)
			(layer "F.CrtYd")
		)
		(fp_rect
			(start -0.8 -0.4)
			(end 0.8 0.4)
			(stroke
				(width 0.15)
				(type solid)
			)
			(fill no)
			(layer "F.Fab")
		)
		(fp_text user "${REFERENCE}"
			(at -1.25 3.898 90)
			(layer "F.Fab")
			(effects
				(font
					(size 0.7 0.7)
					(thickness 0.15)
				)
				(justify left bottom)
			)
		)
		(fp_text user "Author: Antmicro"
			(at -1.25 4.9 90)
			(layer "F.Fab")
			(effects
				(font
					(size 0.7 0.7)
					(thickness 0.15)
				)
				(justify left bottom)
			)
		)
		(fp_text user "License: Apache-2.0"
			(at -1.25 5.9 90)
			(layer "F.Fab")
			(effects
				(font
					(size 0.7 0.7)
					(thickness 0.15)
				)
				(justify left bottom)
			)
		)
		(pad "1" smd roundrect
			(at -0.7 0 90)
			(size 0.8 1)
			(layers "F.Cu" "F.Mask" "F.Paste")
			(roundrect_rratio 0.2)
			(net 64 "Net-(D4-A)")
			(pintype "passive")
		)
		(pad "2" smd roundrect
			(at 0.7 0 90)
			(size 0.8 1)
			(layers "F.Cu" "F.Mask" "F.Paste")
			(roundrect_rratio 0.2)
			(net 35 "LED0")
			(pintype "passive")
		)
	)
	(footprint "antmicro-footprints:C_0402_1005Metric"
		(layer "F.Cu")
		(at 129.48 63.26 -90)
		(descr "Capacitor SMD 0402")
		(tags "capacitor SMD 0402")
		(property "Reference" "C120"
			(at -1.385 -1.4 90)
			(layer "F.SilkS")
			(effects
				(font
					(size 0.65 0.65)
					(thickness 0.15)
				)
				(justify right bottom)
			)
		)
		(property "Value" "C_100n_0402"
			(at 0 1.4 90)
			(layer "F.Fab")
			(hide yes)
			(effects
				(font
					(size 0.7 0.7)
					(thickness 0.15)
				)
				(justify right bottom)
			)
		)
		(property "Datasheet" "https://www.murata.com/products/productdetail?partno=GRM155R61H104KE14%23"
			(at 0 0 270)
			(layer "F.Fab")
			(hide yes)
			(effects
				(font
					(size 1.27 1.27)
					(thickness 0.15)
				)
			)
		)
		(property "Description" "SMD Multilayer Ceramic Capacitor, 0.1 µF, 50 V, 0402 [1005 Metric], ± 10%, X5R, GRM Series"
			(at 0 0 270)
			(layer "F.Fab")
			(hide yes)
			(effects
				(font
					(size 1.27 1.27)
					(thickness 0.15)
				)
			)
		)
		(property "Author" "Antmicro"
			(at 66.22 192.74 0)
			(layer "F.Fab")
			(hide yes)
			(effects
				(font
					(size 1 1)
					(thickness 0.15)
				)
			)
		)
		(property "Dielectric" "X5R"
			(at 66.22 192.74 0)
			(layer "F.Fab")
			(hide yes)
			(effects
				(font
					(size 1 1)
					(thickness 0.15)
				)
			)
		)
		(property "License" "Apache-2.0"
			(at 66.22 192.74 0)
			(layer "F.Fab")
			(hide yes)
			(effects
				(font
					(size 1 1)
					(thickness 0.15)
				)
			)
		)
		(property "MPN" "GRM155R61H104KE14D"
			(at 66.22 192.74 0)
			(layer "F.Fab")
			(hide yes)
			(effects
				(font
					(size 1 1)
					(thickness 0.15)
				)
			)
		)
		(property "Manufacturer" "Murata"
			(at 66.22 192.74 0)
			(layer "F.Fab")
			(hide yes)
			(effects
				(font
					(size 1 1)
					(thickness 0.15)
				)
			)
		)
		(property "Val" "100n"
			(at 66.22 192.74 0)
			(layer "F.Fab")
			(hide yes)
			(effects
				(font
					(size 1 1)
					(thickness 0.15)
				)
			)
		)
		(property "Voltage" "50V"
			(at 66.22 192.74 0)
			(layer "F.Fab")
			(hide yes)
			(effects
				(font
					(size 1 1)
					(thickness 0.15)
				)
			)
		)
		(sheetname "/DDR3/")
		(sheetfile "ddr3.kicad_sch")
		(attr smd)
		(fp_rect
			(start -0.925 -0.47)
			(end 0.925 0.47)
			(stroke
				(width 0.05)
				(type default)
			)
			(fill no)
			(layer "F.CrtYd")
		)
		(fp_line
			(start -0.494 0.248)
			(end -0.494 -0.25)
			(stroke
				(width 0.15)
				(type solid)
			)
			(layer "F.Fab")
		)
		(fp_line
			(start 0.504 0.248)
			(end -0.494 0.248)
			(stroke
				(width 0.15)
				(type solid)
			)
			(layer "F.Fab")
		)
		(fp_line
			(start -0.494 -0.25)
			(end 0.504 -0.25)
			(stroke
				(width 0.15)
				(type solid)
			)
			(layer "F.Fab")
		)
		(fp_line
			(start 0.504 -0.25)
			(end 0.504 0.248)
			(stroke
				(width 0.15)
				(type solid)
			)
			(layer "F.Fab")
		)
		(fp_text user "Author: Antmicro"
			(at -0.939 3.399 270)
			(layer "F.Fab")
			(effects
				(font
					(size 0.7 0.7)
					(thickness 0.15)
				)
				(justify left bottom)
			)
		)
		(fp_text user "License: Apache-2.0"
			(at -0.939 5.799 270)
			(layer "F.Fab")
			(effects
				(font
					(size 0.7 0.7)
					(thickness 0.15)
				)
				(justify left bottom)
			)
		)
		(fp_text user "${REFERENCE}"
			(at -0.939 4.599 270)
			(layer "F.Fab")
			(effects
				(font
					(size 0.7 0.7)
					(thickness 0.15)
				)
				(justify left bottom)
			)
		)
		(pad "1" smd roundrect
			(at -0.48 0 270)
			(size 0.59 0.64)
			(layers "F.Cu" "F.Mask" "F.Paste")
			(roundrect_rratio 0.25)
			(net 1 "GND")
			(pintype "passive")
		)
		(pad "2" smd roundrect
			(at 0.48 0 270)
			(size 0.59 0.64)
			(layers "F.Cu" "F.Mask" "F.Paste")
			(roundrect_rratio 0.25)
			(net 5 "Vref")
			(pintype "passive")
		)
	)
	(footprint "antmicro-footprints:LED_0603_1608Metric_G"
		(layer "F.Cu")
		(at 162.83 119.15 90)
		(descr "LED SMD 0603 Green")
		(tags "LED SMD 0603 Green")
		(property "Reference" "D4"
			(at -0.09 0.8 90)
			(layer "F.SilkS")
			(effects
				(font
					(size 0.65 0.65)
					(thickness 0.15)
				)
				(justify left top)
			)
		)
		(property "Value" "LED_G_0603_LTST-C190GKT"
			(at 0 1.6 90)
			(layer "F.Fab")
			(hide yes)
			(effects
				(font
					(size 0.7 0.7)
					(thickness 0.15)
				)
				(justify left top)
			)
		)
		(property "Datasheet" "https://media.digikey.com/pdf/Data%20Sheets/Lite-On%20PDFs/LTST-C190GKT.pdf"
			(at 0 0 90)
			(layer "F.Fab")
			(hide yes)
			(effects
				(font
					(size 1.27 1.27)
					(thickness 0.15)
				)
			)
		)
		(property "Description" "LED, Green, SMD, 0603, 20 mA, 2.1 V, 569 nm"
			(at 0 0 90)
			(layer "F.Fab")
			(hide yes)
			(effects
				(font
					(size 1.27 1.27)
					(thickness 0.15)
				)
			)
		)
		(property "Author" "Antmicro"
			(at 43.68 281.98 0)
			(layer "F.Fab")
			(hide yes)
			(effects
				(font
					(size 1 1)
					(thickness 0.15)
				)
			)
		)
		(property "License" "Apache-2.0"
			(at 43.68 281.98 0)
			(layer "F.Fab")
			(hide yes)
			(effects
				(font
					(size 1 1)
					(thickness 0.15)
				)
			)
		)
		(property "MPN" "LTST-C190GKT"
			(at 43.68 281.98 0)
			(layer "F.Fab")
			(hide yes)
			(effects
				(font
					(size 1 1)
					(thickness 0.15)
				)
			)
		)
		(property "Manufacturer" "Lite-On"
			(at 43.68 281.98 0)
			(layer "F.Fab")
			(hide yes)
			(effects
				(font
					(size 1 1)
					(thickness 0.15)
				)
			)
		)
		(property "Color" "Green"
			(at 0 0 90)
			(unlocked yes)
			(layer "F.Fab")
			(hide yes)
			(effects
				(font
					(size 1 1)
					(thickness 0.15)
				)
			)
		)
		(sheetname "/Peripherals/")
		(sheetfile "peripherals.kicad_sch")
		(attr smd)
		(fp_line
			(start 0.22 -0.35)
			(end -0.22 -0.35)
			(stroke
				(width 0.15)
				(type solid)
			)
			(layer "F.SilkS")
		)
		(fp_line
			(start -1.18 -0.319)
			(end -1.18 0.321)
			(stroke
				(width 0.15)
				(type solid)
			)
			(layer "F.SilkS")
		)
		(fp_line
			(start 0.105328 0.001008)
			(end 0.24 0.001)
			(stroke
				(width 0.1)
				(type solid)
			)
			(layer "F.SilkS")
		)
		(fp_line
			(start -0.094672 0.001008)
			(end 0.105328 -0.198992)
			(stroke
				(width 0.1)
				(type solid)
			)
			(layer "F.SilkS")
		)
		(fp_line
			(start -0.094672 0.001008)
			(end -0.24 0.001008)
			(stroke
				(width 0.1)
				(type solid)
			)
			(layer "F.SilkS")
		)
		(fp_line
			(start 0.105328 0.201008)
			(end 0.105328 -0.198992)
			(stroke
				(width 0.1)
				(type solid)
			)
			(layer "F.SilkS")
		)
		(fp_line
			(start 0.105328 0.201008)
			(end -0.094672 0.001008)
			(stroke
				(width 0.1)
				(type solid)
			)
			(layer "F.SilkS")
		)
		(fp_line
			(start -0.094672 0.201008)
			(end -0.094672 -0.198992)
			(stroke
				(width 0.1)
				(type solid)
			)
			(layer "F.SilkS")
		)
		(fp_line
			(start 0.22 0.35)
			(end -0.22 0.35)
			(stroke
				(width 0.15)
				(type solid)
			)
			(layer "F.SilkS")
		)
		(fp_rect
			(start 1.25 0.65)
			(end -1.25 -0.65)
			(stroke
				(width 0.05)
				(type solid)
			)
			(fill no)
			(layer "F.CrtYd")
		)
		(fp_line
			(start 0.201 -0.202)
			(end -0.101 0)
			(stroke
				(width 0.15)
				(type solid)
			)
			(layer "F.Fab")
		)
		(fp_line
			(start -0.199 -0.202)
			(end -0.199 0.1)
			(stroke
				(width 0.15)
				(type solid)
			)
			(layer "F.Fab")
		)
		(fp_line
			(start 0.599 0)
			(end 0.201 0)
			(stroke
				(width 0.15)
				(type solid)
			)
			(layer "F.Fab")
		)
		(fp_line
			(start 0.201 0)
			(end 0.201 -0.202)
			(stroke
				(width 0.15)
				(type solid)
			)
			(layer "F.Fab")
		)
		(fp_line
			(start -0.101 0)
			(end 0.201 0.2)
			(stroke
				(width 0.15)
				(type solid)
			)
			(layer "F.Fab")
		)
		(fp_line
			(start -0.199 0)
			(end -0.597 0)
			(stroke
				(width 0.15)
				(type solid)
			)
			(layer "F.Fab")
		)
		(fp_line
			(start 0.201 0.2)
			(end 0.201 0)
			(stroke
				(width 0.15)
				(type solid)
			)
			(layer "F.Fab")
		)
		(fp_line
			(start -0.199 0.2)
			(end -0.199 0.1)
			(stroke
				(width 0.15)
				(type solid)
			)
			(layer "F.Fab")
		)
		(fp_rect
			(start 0.848 0.4)
			(end -0.85 -0.402)
			(stroke
				(width 0.15)
				(type solid)
			)
			(fill no)
			(layer "F.Fab")
		)
		(fp_text user "${REFERENCE}"
			(at -1.4224 5.999 90)
			(layer "F.Fab")
			(effects
				(font
					(size 0.7 0.7)
					(thickness 0.15)
				)
				(justify left bottom)
			)
		)
		(fp_text user "Author: Antmicro"
			(at -1.4224 4.799 90)
			(layer "F.Fab")
			(effects
				(font
					(size 0.7 0.7)
					(thickness 0.15)
				)
				(justify left bottom)
			)
		)
		(fp_text user "License: Apache-2.0"
			(at -1.4224 3.599 90)
			(layer "F.Fab")
			(effects
				(font
					(size 0.7 0.7)
					(thickness 0.15)
				)
				(justify left bottom)
			)
		)
		(pad "1" smd roundrect
			(at -0.7 0 270)
			(size 0.8 1)
			(layers "F.Cu" "F.Mask" "F.Paste")
			(roundrect_rratio 0.2)
			(net 1 "GND")
			(pinfunction "C")
			(pintype "passive")
		)
		(pad "2" smd roundrect
			(at 0.7 0 270)
			(size 0.8 1)
			(layers "F.Cu" "F.Mask" "F.Paste")
			(roundrect_rratio 0.2)
			(net 64 "Net-(D4-A)")
			(pinfunction "A")
			(pintype "passive")
		)
	)
	(footprint "antmicro-footprints:C_0603_1608Metric"
		(layer "F.Cu")
		(at 146.18 75.29 90)
		(descr "Capacitor SMD 0603")
		(tags "capacitor 0603")
		(property "Reference" "C26"
			(at -3.44 0.3 90)
			(layer "F.SilkS")
			(effects
				(font
					(size 0.65 0.65)
					(thickness 0.15)
				)
				(justify left bottom)
			)
		)
		(property "Value" "C_22u_0603"
			(at 0 1.6 90)
			(layer "F.Fab")
			(hide yes)
			(effects
				(font
					(size 0.7 0.7)
					(thickness 0.15)
				)
				(justify left bottom)
			)
		)
		(property "Datasheet" "https://www.murata.com/products/productdetail?partno=GRM188R60J226MEA0%23"
			(at 0 0 90)
			(layer "F.Fab")
			(hide yes)
			(effects
				(font
					(size 1.27 1.27)
					(thickness 0.15)
				)
			)
		)
		(property "Description" "SMD Multilayer Ceramic Capacitor, 22 µF, 6.3 V, 0603 [1608 Metric], ± 20%, X5R, GRM Series"
			(at 0 0 90)
			(layer "F.Fab")
			(hide yes)
			(effects
				(font
					(size 1.27 1.27)
					(thickness 0.15)
				)
			)
		)
		(property "Author" "Antmicro"
			(at 221.43 -71.03 0)
			(layer "F.Fab")
			(hide yes)
			(effects
				(font
					(size 1 1)
					(thickness 0.15)
				)
			)
		)
		(property "Dielectric" ""
			(at 221.43 -71.03 0)
			(layer "F.Fab")
			(hide yes)
			(effects
				(font
					(size 1 1)
					(thickness 0.15)
				)
			)
		)
		(property "License" "Apache-2.0"
			(at 221.43 -71.03 0)
			(layer "F.Fab")
			(hide yes)
			(effects
				(font
					(size 1 1)
					(thickness 0.15)
				)
			)
		)
		(property "MPN" "GRM188R60J226MEA0D"
			(at 221.43 -71.03 0)
			(layer "F.Fab")
			(hide yes)
			(effects
				(font
					(size 1 1)
					(thickness 0.15)
				)
			)
		)
		(property "Manufacturer" "Murata"
			(at 221.43 -71.03 0)
			(layer "F.Fab")
			(hide yes)
			(effects
				(font
					(size 1 1)
					(thickness 0.15)
				)
			)
		)
		(property "Val" "22u"
			(at 221.43 -71.03 0)
			(layer "F.Fab")
			(hide yes)
			(effects
				(font
					(size 1 1)
					(thickness 0.15)
				)
			)
		)
		(property "Voltage" ""
			(at 221.43 -71.03 0)
			(layer "F.Fab")
			(hide yes)
			(effects
				(font
					(size 1 1)
					(thickness 0.15)
				)
			)
		)
		(sheetname "/Power Supply/")
		(sheetfile "supply.kicad_sch")
		(attr smd)
		(fp_line
			(start -0.15 -0.4)
			(end 0.15 -0.4)
			(stroke
				(width 0.15)
				(type solid)
			)
			(layer "F.SilkS")
		)
		(fp_line
			(start -0.15 0.4)
			(end 0.15 0.4)
			(stroke
				(width 0.15)
				(type solid)
			)
			(layer "F.SilkS")
		)
		(fp_rect
			(start -1.25 -0.65)
			(end 1.25 0.65)
			(stroke
				(width 0.05)
				(type solid)
			)
			(fill no)
			(layer "F.CrtYd")
		)
		(fp_rect
			(start -0.8 -0.4)
			(end 0.8 0.4)
			(stroke
				(width 0.15)
				(type solid)
			)
			(fill no)
			(layer "F.Fab")
		)
		(fp_text user "Author: Antmicro"
			(at -1.682 4.894 90)
			(layer "F.Fab")
			(effects
				(font
					(size 0.7 0.7)
					(thickness 0.15)
				)
				(justify left bottom)
			)
		)
		(fp_text user "${REFERENCE}"
			(at -1.682 3.895 90)
			(layer "F.Fab")
			(effects
				(font
					(size 0.7 0.7)
					(thickness 0.15)
				)
				(justify left bottom)
			)
		)
		(fp_text user "License: Apache-2.0"
			(at -1.682 5.895 90)
			(layer "F.Fab")
			(effects
				(font
					(size 0.7 0.7)
					(thickness 0.15)
				)
				(justify left bottom)
			)
		)
		(pad "1" smd roundrect
			(at -0.7 0 90)
			(size 0.8 1)
			(layers "F.Cu" "F.Mask" "F.Paste")
			(roundrect_rratio 0.2)
			(net 1 "GND")
			(pintype "passive")
		)
		(pad "2" smd roundrect
			(at 0.7 0 90)
			(size 0.8 1)
			(layers "F.Cu" "F.Mask" "F.Paste")
			(roundrect_rratio 0.2)
			(net 273 "/Power Supply/1V0_OUT")
			(pintype "passive")
		)
	)
	(footprint "antmicro-footprints:R_0805_2012Metric"
		(layer "F.Cu")
		(at 141.13 62.64 180)
		(property "Reference" "R42"
			(at 3.9 -0.3 180)
			(layer "F.SilkS")
			(effects
				(font
					(size 0.65 0.65)
					(thickness 0.15)
				)
				(justify left bottom)
			)
		)
		(property "Value" "R_0R_0805"
			(at 0 1.8 180)
			(layer "F.Fab")
			(hide yes)
			(effects
				(font
					(size 0.7 0.7)
					(thickness 0.15)
				)
				(justify left bottom)
			)
		)
		(property "Datasheet" "https://www.vishay.com/docs/20035/dcrcwe3.pdf"
			(at 0 0 180)
			(layer "F.Fab")
			(hide yes)
			(effects
				(font
					(size 1.27 1.27)
					(thickness 0.15)
				)
			)
		)
		(property "Description" "Zero Ohm Resistor, Jumper, 0805 [2012 Metric], Thick Film, 125 mW, 2.5 A, Surface Mount Device"
			(at 0 0 180)
			(layer "F.Fab")
			(hide yes)
			(effects
				(font
					(size 1.27 1.27)
					(thickness 0.15)
				)
			)
		)
		(property "Author" "Antmicro"
			(at 282.26 125.28 0)
			(layer "F.Fab")
			(hide yes)
			(effects
				(font
					(size 1 1)
					(thickness 0.15)
				)
			)
		)
		(property "Current" "2.5A"
			(at 282.26 125.28 0)
			(layer "F.Fab")
			(hide yes)
			(effects
				(font
					(size 1 1)
					(thickness 0.15)
				)
			)
		)
		(property "License" "Apache-2.0"
			(at 282.26 125.28 0)
			(layer "F.Fab")
			(hide yes)
			(effects
				(font
					(size 1 1)
					(thickness 0.15)
				)
			)
		)
		(property "MPN" "CRCW08050000Z0EA"
			(at 282.26 125.28 0)
			(layer "F.Fab")
			(hide yes)
			(effects
				(font
					(size 1 1)
					(thickness 0.15)
				)
			)
		)
		(property "Manufacturer" "Vishay"
			(at 282.26 125.28 0)
			(layer "F.Fab")
			(hide yes)
			(effects
				(font
					(size 1 1)
					(thickness 0.15)
				)
			)
		)
		(property "Tolerance" "~"
			(at 282.26 125.28 0)
			(layer "F.Fab")
			(hide yes)
			(effects
				(font
					(size 1 1)
					(thickness 0.15)
				)
			)
		)
		(property "Val" "0R"
			(at 282.26 125.28 0)
			(layer "F.Fab")
			(hide yes)
			(effects
				(font
					(size 1 1)
					(thickness 0.15)
				)
			)
		)
		(sheetname "/Power Supply/")
		(sheetfile "supply.kicad_sch")
		(attr smd)
		(fp_line
			(start -0.3 -0.701)
			(end 0.298 -0.701)
			(stroke
				(width 0.15)
				(type solid)
			)
			(layer "F.SilkS")
		)
		(fp_line
			(start -0.32 0.699)
			(end 0.28 0.699)
			(stroke
				(width 0.15)
				(type solid)
			)
			(layer "F.SilkS")
		)
		(fp_rect
			(start 1.95 -0.9)
			(end -1.95 0.9)
			(stroke
				(width 0.05)
				(type default)
			)
			(fill no)
			(layer "F.CrtYd")
		)
		(fp_line
			(start 0.949 -0.677)
			(end 0.949 0.675)
			(stroke
				(width 0.15)
				(type solid)
			)
			(layer "F.Fab")
		)
		(fp_line
			(start -0.951 0.68)
			(end 0.949 0.68)
			(stroke
				(width 0.15)
				(type solid)
			)
			(layer "F.Fab")
		)
		(fp_line
			(start -0.951 -0.677)
			(end -0.951 0.675)
			(stroke
				(width 0.15)
				(type solid)
			)
			(layer "F.Fab")
		)
		(fp_line
			(start -0.951 -0.682)
			(end 0.949 -0.682)
			(stroke
				(width 0.15)
				(type solid)
			)
			(layer "F.Fab")
		)
		(fp_text user "${REFERENCE}"
			(at -1.9 3.1 180)
			(layer "F.Fab")
			(effects
				(font
					(size 0.7 0.7)
					(thickness 0.15)
				)
				(justify left bottom)
			)
		)
		(fp_text user "License: Apache-2.0"
			(at -1.9 5.75 180)
			(layer "F.Fab")
			(effects
				(font
					(size 0.7 0.7)
					(thickness 0.15)
				)
				(justify left bottom)
			)
		)
		(fp_text user "Author: Antmicro"
			(at -1.9 4.4 180)
			(layer "F.Fab")
			(effects
				(font
					(size 0.7 0.7)
					(thickness 0.15)
				)
				(justify left bottom)
			)
		)
		(pad "1" smd roundrect
			(at -1.1 0 180)
			(size 1.2 1.3)
			(layers "F.Cu" "F.Mask" "F.Paste")
			(roundrect_rratio 0.25)
			(net 274 "/Power Supply/1V5_OUT")
			(pintype "passive")
		)
		(pad "2" smd roundrect
			(at 1.1 0 180)
			(size 1.2 1.3)
			(layers "F.Cu" "F.Mask" "F.Paste")
			(roundrect_rratio 0.25)
			(net 248 "+1V5")
			(pintype "passive")
		)
	)
	(footprint "antmicro-footprints:R_0402_1005Metric"
		(layer "F.Cu")
		(at 122.03 109.65 180)
		(descr "Resistor SMD 0402")
		(tags "resistor SMD 0402")
		(property "Reference" "R91"
			(at 0.95 -0.39 0)
			(layer "F.SilkS")
			(effects
				(font
					(size 0.65 0.65)
					(thickness 0.15)
				)
				(justify right bottom)
			)
		)
		(property "Value" "R_10k_0402"
			(at 0 1.4 0)
			(layer "F.Fab")
			(hide yes)
			(effects
				(font
					(size 0.7 0.7)
					(thickness 0.15)
				)
				(justify right bottom)
			)
		)
		(property "Datasheet" "https://www.bourns.com/docs/product-datasheets/cr.pdf"
			(at 0 0 180)
			(layer "F.Fab")
			(hide yes)
			(effects
				(font
					(size 1.27 1.27)
					(thickness 0.15)
				)
			)
		)
		(property "Description" "SMD Chip Resistor, 10 kohm, ± 1%, 62.5 mW, 0402 [1005 Metric], Thick Film, General Purpose"
			(at 0 0 180)
			(layer "F.Fab")
			(hide yes)
			(effects
				(font
					(size 1.27 1.27)
					(thickness 0.15)
				)
			)
		)
		(property "Author" "Antmicro"
			(at 244.06 219.3 0)
			(layer "F.Fab")
			(hide yes)
			(effects
				(font
					(size 1 1)
					(thickness 0.15)
				)
			)
		)
		(property "License" "Apache-2.0"
			(at 244.06 219.3 0)
			(layer "F.Fab")
			(hide yes)
			(effects
				(font
					(size 1 1)
					(thickness 0.15)
				)
			)
		)
		(property "MPN" "CR0402-FX-1002GLF"
			(at 244.06 219.3 0)
			(layer "F.Fab")
			(hide yes)
			(effects
				(font
					(size 1 1)
					(thickness 0.15)
				)
			)
		)
		(property "Manufacturer" "Bourns"
			(at 244.06 219.3 0)
			(layer "F.Fab")
			(hide yes)
			(effects
				(font
					(size 1 1)
					(thickness 0.15)
				)
			)
		)
		(property "Tolerance" "1%"
			(at 244.06 219.3 0)
			(layer "F.Fab")
			(hide yes)
			(effects
				(font
					(size 1 1)
					(thickness 0.15)
				)
			)
		)
		(property "Val" "10k"
			(at 244.06 219.3 0)
			(layer "F.Fab")
			(hide yes)
			(effects
				(font
					(size 1 1)
					(thickness 0.15)
				)
			)
		)
		(sheetname "/FPGA/")
		(sheetfile "fpga.kicad_sch")
		(attr smd)
		(fp_rect
			(start -0.925 -0.47)
			(end 0.925 0.47)
			(stroke
				(width 0.05)
				(type default)
			)
			(fill no)
			(layer "F.CrtYd")
		)
		(fp_rect
			(start -0.5 -0.25)
			(end 0.5 0.25)
			(stroke
				(width 0.15)
				(type solid)
			)
			(fill no)
			(layer "F.Fab")
		)
		(fp_text user "${REFERENCE}"
			(at -0.95 3.168 180)
			(layer "F.Fab")
			(effects
				(font
					(size 0.7 0.7)
					(thickness 0.15)
				)
				(justify left bottom)
			)
		)
		(fp_text user "License: Apache-2.0"
			(at -0.95 5.169 180)
			(layer "F.Fab")
			(effects
				(font
					(size 0.7 0.7)
					(thickness 0.15)
				)
				(justify left bottom)
			)
		)
		(fp_text user "Author: Antmicro"
			(at -0.95 4.169 180)
			(layer "F.Fab")
			(effects
				(font
					(size 0.7 0.7)
					(thickness 0.15)
				)
				(justify left bottom)
			)
		)
		(pad "1" smd roundrect
			(at -0.48 0 180)
			(size 0.59 0.64)
			(layers "F.Cu" "F.Mask" "F.Paste")
			(roundrect_rratio 0.25)
			(net 15 "/FPGA/INITN")
			(pintype "passive")
		)
		(pad "2" smd roundrect
			(at 0.48 0 180)
			(size 0.59 0.64)
			(layers "F.Cu" "F.Mask" "F.Paste")
			(roundrect_rratio 0.25)
			(net 2 "+3V3")
			(pintype "passive")
		)
	)
	(footprint "antmicro-footprints:TP_SMD_0.75mm"
		(layer "F.Cu")
		(at 145 92.41)
		(property "Reference" "TP46"
			(at -3.07 0.3792 0)
			(layer "F.SilkS")
			(effects
				(font
					(size 0.65 0.65)
					(thickness 0.15)
				)
				(justify left bottom)
			)
		)
		(property "Value" "TP_0.75mm_SMD"
			(at 0 1.2 0)
			(layer "F.Fab")
			(hide yes)
			(effects
				(font
					(size 0.7 0.7)
					(thickness 0.15)
				)
				(justify left bottom)
			)
		)
		(property "Description" "SMT test point"
			(at 0 0 0)
			(layer "F.Fab")
			(hide yes)
			(effects
				(font
					(size 1.27 1.27)
					(thickness 0.15)
				)
			)
		)
		(property "Author" "Antmicro"
			(at 0 0 0)
			(layer "F.Fab")
			(hide yes)
			(effects
				(font
					(size 1 1)
					(thickness 0.15)
				)
			)
		)
		(property "License" "Apache-2.0"
			(at 0 0 0)
			(layer "F.Fab")
			(hide yes)
			(effects
				(font
					(size 1 1)
					(thickness 0.15)
				)
			)
		)
		(property "MPN" ""
			(at 0 0 0)
			(layer "F.Fab")
			(hide yes)
			(effects
				(font
					(size 1 1)
					(thickness 0.15)
				)
			)
		)
		(property "Manufacturer" ""
			(at 0 0 0)
			(layer "F.Fab")
			(hide yes)
			(effects
				(font
					(size 1 1)
					(thickness 0.15)
				)
			)
		)
		(sheetname "/Peripherals/")
		(sheetfile "peripherals.kicad_sch")
		(attr exclude_from_pos_files)
		(fp_circle
			(center 0 0)
			(end 0.475 0)
			(stroke
				(width 0.05)
				(type default)
			)
			(fill no)
			(layer "F.CrtYd")
		)
		(fp_text user "${REFERENCE}"
			(at -0.4 2.7 0)
			(layer "F.Fab")
			(effects
				(font
					(size 0.7 0.7)
					(thickness 0.15)
				)
				(justify left bottom)
			)
		)
		(fp_text user "Author: Antmicro"
			(at -0.4 3.901 0)
			(layer "F.Fab")
			(effects
				(font
					(size 0.7 0.7)
					(thickness 0.15)
				)
				(justify left bottom)
			)
		)
		(fp_text user "License: Apache-2.0"
			(at -0.4 5.101 0)
			(layer "F.Fab")
			(effects
				(font
					(size 0.7 0.7)
					(thickness 0.15)
				)
				(justify left bottom)
			)
		)
		(pad "1" smd circle
			(at 0 0)
			(size 0.75 0.75)
			(layers "F.Cu" "F.Mask")
			(net 379 "Net-(U20-CBUS0)")
			(pinfunction "1")
			(pintype "passive")
		)
	)
	(footprint "antmicro-footprints:C_0402_1005Metric"
		(layer "F.Cu")
		(at 144.78 56.34)
		(descr "Capacitor SMD 0402")
		(tags "capacitor SMD 0402")
		(property "Reference" "C14"
			(at -3.15 0.3 0)
			(layer "F.SilkS")
			(effects
				(font
					(size 0.65 0.65)
					(thickness 0.15)
				)
				(justify left bottom)
			)
		)
		(property "Value" "C_100n_0402"
			(at 0 1.4 0)
			(layer "F.Fab")
			(hide yes)
			(effects
				(font
					(size 0.7 0.7)
					(thickness 0.15)
				)
				(justify left bottom)
			)
		)
		(property "Datasheet" "https://www.murata.com/products/productdetail?partno=GRM155R61H104KE14%23"
			(at 0 0 0)
			(layer "F.Fab")
			(hide yes)
			(effects
				(font
					(size 1.27 1.27)
					(thickness 0.15)
				)
			)
		)
		(property "Description" "SMD Multilayer Ceramic Capacitor, 0.1 µF, 50 V, 0402 [1005 Metric], ± 10%, X5R, GRM Series"
			(at 0 0 0)
			(layer "F.Fab")
			(hide yes)
			(effects
				(font
					(size 1.27 1.27)
					(thickness 0.15)
				)
			)
		)
		(property "Author" "Antmicro"
			(at 0 0 0)
			(layer "F.Fab")
			(hide yes)
			(effects
				(font
					(size 1 1)
					(thickness 0.15)
				)
			)
		)
		(property "Dielectric" "X5R"
			(at 0 0 0)
			(layer "F.Fab")
			(hide yes)
			(effects
				(font
					(size 1 1)
					(thickness 0.15)
				)
			)
		)
		(property "License" "Apache-2.0"
			(at 0 0 0)
			(layer "F.Fab")
			(hide yes)
			(effects
				(font
					(size 1 1)
					(thickness 0.15)
				)
			)
		)
		(property "MPN" "GRM155R61H104KE14D"
			(at 0 0 0)
			(layer "F.Fab")
			(hide yes)
			(effects
				(font
					(size 1 1)
					(thickness 0.15)
				)
			)
		)
		(property "Manufacturer" "Murata"
			(at 0 0 0)
			(layer "F.Fab")
			(hide yes)
			(effects
				(font
					(size 1 1)
					(thickness 0.15)
				)
			)
		)
		(property "Val" "100n"
			(at 0 0 0)
			(layer "F.Fab")
			(hide yes)
			(effects
				(font
					(size 1 1)
					(thickness 0.15)
				)
			)
		)
		(property "Voltage" "50V"
			(at 0 0 0)
			(layer "F.Fab")
			(hide yes)
			(effects
				(font
					(size 1 1)
					(thickness 0.15)
				)
			)
		)
		(sheetname "/Power Supply/")
		(sheetfile "supply.kicad_sch")
		(attr smd)
		(fp_rect
			(start -0.925 -0.47)
			(end 0.925 0.47)
			(stroke
				(width 0.05)
				(type default)
			)
			(fill no)
			(layer "F.CrtYd")
		)
		(fp_line
			(start -0.494 -0.25)
			(end 0.504 -0.25)
			(stroke
				(width 0.15)
				(type solid)
			)
			(layer "F.Fab")
		)
		(fp_line
			(start -0.494 0.248)
			(end -0.494 -0.25)
			(stroke
				(width 0.15)
				(type solid)
			)
			(layer "F.Fab")
		)
		(fp_line
			(start 0.504 -0.25)
			(end 0.504 0.248)
			(stroke
				(width 0.15)
				(type solid)
			)
			(layer "F.Fab")
		)
		(fp_line
			(start 0.504 0.248)
			(end -0.494 0.248)
			(stroke
				(width 0.15)
				(type solid)
			)
			(layer "F.Fab")
		)
		(fp_text user "Author: Antmicro"
			(at -0.939 3.399 0)
			(layer "F.Fab")
			(effects
				(font
					(size 0.7 0.7)
					(thickness 0.15)
				)
				(justify left bottom)
			)
		)
		(fp_text user "License: Apache-2.0"
			(at -0.939 5.799 0)
			(layer "F.Fab")
			(effects
				(font
					(size 0.7 0.7)
					(thickness 0.15)
				)
				(justify left bottom)
			)
		)
		(fp_text user "${REFERENCE}"
			(at -0.939 4.599 0)
			(layer "F.Fab")
			(effects
				(font
					(size 0.7 0.7)
					(thickness 0.15)
				)
				(justify left bottom)
			)
		)
		(pad "1" smd roundrect
			(at -0.48 0)
			(size 0.59 0.64)
			(layers "F.Cu" "F.Mask" "F.Paste")
			(roundrect_rratio 0.25)
			(net 277 "/Power Supply/1V5_SW")
			(pintype "passive")
		)
		(pad "2" smd roundrect
			(at 0.48 0)
			(size 0.59 0.64)
			(layers "F.Cu" "F.Mask" "F.Paste")
			(roundrect_rratio 0.25)
			(net 65 "Net-(U6-BST)")
			(pintype "passive")
		)
	)
	(footprint "antmicro-footprints:R_0603_1608Metric"
		(layer "F.Cu")
		(at 140.29 115.9 90)
		(descr "Resistor SMD 0603")
		(tags "resistor SMD 0603")
		(property "Reference" "R30"
			(at -3.44 0.54 90)
			(layer "F.SilkS")
			(effects
				(font
					(size 0.65 0.65)
					(thickness 0.15)
				)
				(justify left bottom)
			)
		)
		(property "Value" "R_0R_0603"
			(at 0 1.6 90)
			(layer "F.Fab")
			(hide yes)
			(effects
				(font
					(size 0.7 0.7)
					(thickness 0.15)
				)
				(justify left bottom)
			)
		)
		(property "Datasheet" "https://www.bourns.com/docs/product-datasheets/cr.pdf?sfvrsn=574d41f6_14"
			(at 0 0 90)
			(layer "F.Fab")
			(hide yes)
			(effects
				(font
					(size 1.27 1.27)
					(thickness 0.15)
				)
			)
		)
		(property "Description" "Zero Ohm Resistor, Jumper, 0603 [1608 Metric], Thick Film, 100 mW, 1 A, Surface Mount Device, CR"
			(at 0 0 90)
			(layer "F.Fab")
			(hide yes)
			(effects
				(font
					(size 1.27 1.27)
					(thickness 0.15)
				)
			)
		)
		(property "Author" "Antmicro"
			(at 256.19 -24.39 0)
			(layer "F.Fab")
			(hide yes)
			(effects
				(font
					(size 1 1)
					(thickness 0.15)
				)
			)
		)
		(property "Current" "1A"
			(at 256.19 -24.39 0)
			(layer "F.Fab")
			(hide yes)
			(effects
				(font
					(size 1 1)
					(thickness 0.15)
				)
			)
		)
		(property "License" "Apache-2.0"
			(at 256.19 -24.39 0)
			(layer "F.Fab")
			(hide yes)
			(effects
				(font
					(size 1 1)
					(thickness 0.15)
				)
			)
		)
		(property "MPN" "CR0603-J/-000ELF"
			(at 256.19 -24.39 0)
			(layer "F.Fab")
			(hide yes)
			(effects
				(font
					(size 1 1)
					(thickness 0.15)
				)
			)
		)
		(property "Manufacturer" "Bourns"
			(at 256.19 -24.39 0)
			(layer "F.Fab")
			(hide yes)
			(effects
				(font
					(size 1 1)
					(thickness 0.15)
				)
			)
		)
		(property "Tolerance" "~"
			(at 256.19 -24.39 0)
			(layer "F.Fab")
			(hide yes)
			(effects
				(font
					(size 1 1)
					(thickness 0.15)
				)
			)
		)
		(property "Val" "0R"
			(at 256.19 -24.39 0)
			(layer "F.Fab")
			(hide yes)
			(effects
				(font
					(size 1 1)
					(thickness 0.15)
				)
			)
		)
		(sheetname "/Power Supply/")
		(sheetfile "supply.kicad_sch")
		(attr smd)
		(fp_line
			(start -0.15 -0.4)
			(end 0.15 -0.4)
			(stroke
				(width 0.15)
				(type solid)
			)
			(layer "F.SilkS")
		)
		(fp_line
			(start -0.15 0.4)
			(end 0.15 0.4)
			(stroke
				(width 0.15)
				(type solid)
			)
			(layer "F.SilkS")
		)
		(fp_rect
			(start -1.25 -0.65)
			(end 1.25 0.65)
			(stroke
				(width 0.05)
				(type solid)
			)
			(fill no)
			(layer "F.CrtYd")
		)
		(fp_rect
			(start -0.8 -0.4)
			(end 0.8 0.4)
			(stroke
				(width 0.15)
				(type solid)
			)
			(fill no)
			(layer "F.Fab")
		)
		(fp_text user "Author: Antmicro"
			(at -1.25 4.9 90)
			(layer "F.Fab")
			(effects
				(font
					(size 0.7 0.7)
					(thickness 0.15)
				)
				(justify left bottom)
			)
		)
		(fp_text user "License: Apache-2.0"
			(at -1.25 5.9 90)
			(layer "F.Fab")
			(effects
				(font
					(size 0.7 0.7)
					(thickness 0.15)
				)
				(justify left bottom)
			)
		)
		(fp_text user "${REFERENCE}"
			(at -1.25 3.898 90)
			(layer "F.Fab")
			(effects
				(font
					(size 0.7 0.7)
					(thickness 0.15)
				)
				(justify left bottom)
			)
		)
		(pad "1" smd roundrect
			(at -0.7 0 90)
			(size 0.8 1)
			(layers "F.Cu" "F.Mask" "F.Paste")
			(roundrect_rratio 0.2)
			(net 279 "Net-(U9-V_{OUT})")
			(pintype "passive")
		)
		(pad "2" smd roundrect
			(at 0.7 0 90)
			(size 0.8 1)
			(layers "F.Cu" "F.Mask" "F.Paste")
			(roundrect_rratio 0.2)
			(net 3 "+1V2")
			(pintype "passive")
		)
	)
	(footprint "antmicro-footprints:R_0805_2012Metric"
		(layer "F.Cu")
		(at 134.41 57.73 90)
		(property "Reference" "R5"
			(at -0.61 1.82 90)
			(layer "F.SilkS")
			(effects
				(font
					(size 0.65 0.65)
					(thickness 0.15)
				)
				(justify left bottom)
			)
		)
		(property "Value" "R_0R_0805"
			(at 0 1.8 90)
			(layer "F.Fab")
			(hide yes)
			(effects
				(font
					(size 0.7 0.7)
					(thickness 0.15)
				)
				(justify left bottom)
			)
		)
		(property "Datasheet" "https://www.vishay.com/docs/20035/dcrcwe3.pdf"
			(at 0 0 90)
			(layer "F.Fab")
			(hide yes)
			(effects
				(font
					(size 1.27 1.27)
					(thickness 0.15)
				)
			)
		)
		(property "Description" "Zero Ohm Resistor, Jumper, 0805 [2012 Metric], Thick Film, 125 mW, 2.5 A, Surface Mount Device"
			(at 0 0 90)
			(layer "F.Fab")
			(hide yes)
			(effects
				(font
					(size 1.27 1.27)
					(thickness 0.15)
				)
			)
		)
		(property "Author" "Antmicro"
			(at 192.14 -76.68 0)
			(layer "F.Fab")
			(hide yes)
			(effects
				(font
					(size 1 1)
					(thickness 0.15)
				)
			)
		)
		(property "Current" "2.5A"
			(at 192.14 -76.68 0)
			(layer "F.Fab")
			(hide yes)
			(effects
				(font
					(size 1 1)
					(thickness 0.15)
				)
			)
		)
		(property "License" "Apache-2.0"
			(at 192.14 -76.68 0)
			(layer "F.Fab")
			(hide yes)
			(effects
				(font
					(size 1 1)
					(thickness 0.15)
				)
			)
		)
		(property "MPN" "CRCW08050000Z0EA"
			(at 192.14 -76.68 0)
			(layer "F.Fab")
			(hide yes)
			(effects
				(font
					(size 1 1)
					(thickness 0.15)
				)
			)
		)
		(property "Manufacturer" "Vishay"
			(at 192.14 -76.68 0)
			(layer "F.Fab")
			(hide yes)
			(effects
				(font
					(size 1 1)
					(thickness 0.15)
				)
			)
		)
		(property "Tolerance" "~"
			(at 192.14 -76.68 0)
			(layer "F.Fab")
			(hide yes)
			(effects
				(font
					(size 1 1)
					(thickness 0.15)
				)
			)
		)
		(property "Val" "0R"
			(at 192.14 -76.68 0)
			(layer "F.Fab")
			(hide yes)
			(effects
				(font
					(size 1 1)
					(thickness 0.15)
				)
			)
		)
		(sheetname "/Power Supply/")
		(sheetfile "supply.kicad_sch")
		(attr smd)
		(fp_line
			(start -0.3 -0.701)
			(end 0.298 -0.701)
			(stroke
				(width 0.15)
				(type solid)
			)
			(layer "F.SilkS")
		)
		(fp_line
			(start -0.32 0.699)
			(end 0.28 0.699)
			(stroke
				(width 0.15)
				(type solid)
			)
			(layer "F.SilkS")
		)
		(fp_rect
			(start 1.95 -0.9)
			(end -1.95 0.9)
			(stroke
				(width 0.05)
				(type default)
			)
			(fill no)
			(layer "F.CrtYd")
		)
		(fp_line
			(start -0.951 -0.682)
			(end 0.949 -0.682)
			(stroke
				(width 0.15)
				(type solid)
			)
			(layer "F.Fab")
		)
		(fp_line
			(start 0.949 -0.677)
			(end 0.949 0.675)
			(stroke
				(width 0.15)
				(type solid)
			)
			(layer "F.Fab")
		)
		(fp_line
			(start -0.951 -0.677)
			(end -0.951 0.675)
			(stroke
				(width 0.15)
				(type solid)
			)
			(layer "F.Fab")
		)
		(fp_line
			(start -0.951 0.68)
			(end 0.949 0.68)
			(stroke
				(width 0.15)
				(type solid)
			)
			(layer "F.Fab")
		)
		(fp_text user "${REFERENCE}"
			(at -1.9 3.1 90)
			(layer "F.Fab")
			(effects
				(font
					(size 0.7 0.7)
					(thickness 0.15)
				)
				(justify left bottom)
			)
		)
		(fp_text user "License: Apache-2.0"
			(at -1.9 5.75 90)
			(layer "F.Fab")
			(effects
				(font
					(size 0.7 0.7)
					(thickness 0.15)
				)
				(justify left bottom)
			)
		)
		(fp_text user "Author: Antmicro"
			(at -1.9 4.4 90)
			(layer "F.Fab")
			(effects
				(font
					(size 0.7 0.7)
					(thickness 0.15)
				)
				(justify left bottom)
			)
		)
		(pad "1" smd roundrect
			(at -1.1 0 90)
			(size 1.2 1.3)
			(layers "F.Cu" "F.Mask" "F.Paste")
			(roundrect_rratio 0.25)
			(net 248 "+1V5")
			(pintype "passive")
		)
		(pad "2" smd roundrect
			(at 1.1 0 90)
			(size 1.2 1.3)
			(layers "F.Cu" "F.Mask" "F.Paste")
			(roundrect_rratio 0.25)
			(net 60 "Net-(U1-DDQ)")
			(pintype "passive")
		)
	)
	(footprint "antmicro-footprints:R_0402_1005Metric"
		(layer "F.Cu")
		(at 99.94 115.185 90)
		(descr "Resistor SMD 0402")
		(tags "resistor SMD 0402")
		(property "Reference" "R92"
			(at 0.895 0.39 90)
			(layer "F.SilkS")
			(effects
				(font
					(size 0.65 0.65)
					(thickness 0.15)
				)
				(justify left bottom)
			)
		)
		(property "Value" "R_0R_0402"
			(at 0 1.4 90)
			(layer "F.Fab")
			(hide yes)
			(effects
				(font
					(size 0.7 0.7)
					(thickness 0.15)
				)
				(justify left bottom)
			)
		)
		(property "Datasheet" "https://industrial.panasonic.com/cdbs/www-data/pdf/RDA0000/AOA0000C301.pdf"
			(at 0 0 90)
			(layer "F.Fab")
			(hide yes)
			(effects
				(font
					(size 1.27 1.27)
					(thickness 0.15)
				)
			)
		)
		(property "Description" "SMD Chip Resistor, Jumper, 0 ohm, 100 mW, 0402 [1005 Metric], Thick Film, General Purpose"
			(at 0 0 90)
			(layer "F.Fab")
			(hide yes)
			(effects
				(font
					(size 1.27 1.27)
					(thickness 0.15)
				)
			)
		)
		(property "Author" "Antmicro"
			(at 215.125 15.245 0)
			(layer "F.Fab")
			(hide yes)
			(effects
				(font
					(size 1 1)
					(thickness 0.15)
				)
			)
		)
		(property "Current" "1A"
			(at 215.125 15.245 0)
			(layer "F.Fab")
			(hide yes)
			(effects
				(font
					(size 1 1)
					(thickness 0.15)
				)
			)
		)
		(property "License" "Apache-2.0"
			(at 215.125 15.245 0)
			(layer "F.Fab")
			(hide yes)
			(effects
				(font
					(size 1 1)
					(thickness 0.15)
				)
			)
		)
		(property "MPN" "ERJ2GE0R00X"
			(at 215.125 15.245 0)
			(layer "F.Fab")
			(hide yes)
			(effects
				(font
					(size 1 1)
					(thickness 0.15)
				)
			)
		)
		(property "Manufacturer" "Panasonic"
			(at 215.125 15.245 0)
			(layer "F.Fab")
			(hide yes)
			(effects
				(font
					(size 1 1)
					(thickness 0.15)
				)
			)
		)
		(property "Tolerance" "~"
			(at 215.125 15.245 0)
			(layer "F.Fab")
			(hide yes)
			(effects
				(font
					(size 1 1)
					(thickness 0.15)
				)
			)
		)
		(property "Val" "0R"
			(at 215.125 15.245 0)
			(layer "F.Fab")
			(hide yes)
			(effects
				(font
					(size 1 1)
					(thickness 0.15)
				)
			)
		)
		(sheetname "/FPGA/")
		(sheetfile "fpga.kicad_sch")
		(attr smd)
		(fp_rect
			(start -0.925 -0.47)
			(end 0.925 0.47)
			(stroke
				(width 0.05)
				(type default)
			)
			(fill no)
			(layer "F.CrtYd")
		)
		(fp_rect
			(start -0.5 -0.25)
			(end 0.5 0.25)
			(stroke
				(width 0.15)
				(type solid)
			)
			(fill no)
			(layer "F.Fab")
		)
		(fp_text user "Author: Antmicro"
			(at -0.95 4.169 90)
			(layer "F.Fab")
			(effects
				(font
					(size 0.7 0.7)
					(thickness 0.15)
				)
				(justify left bottom)
			)
		)
		(fp_text user "${REFERENCE}"
			(at -0.95 3.168 90)
			(layer "F.Fab")
			(effects
				(font
					(size 0.7 0.7)
					(thickness 0.15)
				)
				(justify left bottom)
			)
		)
		(fp_text user "License: Apache-2.0"
			(at -0.95 5.169 90)
			(layer "F.Fab")
			(effects
				(font
					(size 0.7 0.7)
					(thickness 0.15)
				)
				(justify left bottom)
			)
		)
		(pad "1" smd roundrect
			(at -0.48 0 90)
			(size 0.59 0.64)
			(layers "F.Cu" "F.Mask" "F.Paste")
			(roundrect_rratio 0.25)
			(net 135 "Net-(J7-Pad4)")
			(pintype "passive")
		)
		(pad "2" smd roundrect
			(at 0.48 0 90)
			(size 0.59 0.64)
			(layers "F.Cu" "F.Mask" "F.Paste")
			(roundrect_rratio 0.25)
			(net 170 "TCK")
			(pintype "passive")
		)
	)
	(footprint "antmicro-footprints:R_0805_2012Metric"
		(layer "F.Cu")
		(at 147.49 63.35 -90)
		(property "Reference" "R16"
			(at 0.19 -1.74 90)
			(layer "F.SilkS")
			(effects
				(font
					(size 0.65 0.65)
					(thickness 0.15)
				)
				(justify right bottom)
			)
		)
		(property "Value" "R_0R_0805"
			(at 0 1.8 90)
			(layer "F.Fab")
			(hide yes)
			(effects
				(font
					(size 0.7 0.7)
					(thickness 0.15)
				)
				(justify right bottom)
			)
		)
		(property "Datasheet" "https://www.vishay.com/docs/20035/dcrcwe3.pdf"
			(at 0 0 270)
			(layer "F.Fab")
			(hide yes)
			(effects
				(font
					(size 1.27 1.27)
					(thickness 0.15)
				)
			)
		)
		(property "Description" "Zero Ohm Resistor, Jumper, 0805 [2012 Metric], Thick Film, 125 mW, 2.5 A, Surface Mount Device"
			(at 0 0 270)
			(layer "F.Fab")
			(hide yes)
			(effects
				(font
					(size 1.27 1.27)
					(thickness 0.15)
				)
			)
		)
		(property "Author" "Antmicro"
			(at 84.14 210.84 0)
			(layer "F.Fab")
			(hide yes)
			(effects
				(font
					(size 1 1)
					(thickness 0.15)
				)
			)
		)
		(property "Current" "2.5A"
			(at 84.14 210.84 0)
			(layer "F.Fab")
			(hide yes)
			(effects
				(font
					(size 1 1)
					(thickness 0.15)
				)
			)
		)
		(property "License" "Apache-2.0"
			(at 84.14 210.84 0)
			(layer "F.Fab")
			(hide yes)
			(effects
				(font
					(size 1 1)
					(thickness 0.15)
				)
			)
		)
		(property "MPN" "CRCW08050000Z0EA"
			(at 84.14 210.84 0)
			(layer "F.Fab")
			(hide yes)
			(effects
				(font
					(size 1 1)
					(thickness 0.15)
				)
			)
		)
		(property "Manufacturer" "Vishay"
			(at 84.14 210.84 0)
			(layer "F.Fab")
			(hide yes)
			(effects
				(font
					(size 1 1)
					(thickness 0.15)
				)
			)
		)
		(property "Tolerance" "~"
			(at 84.14 210.84 0)
			(layer "F.Fab")
			(hide yes)
			(effects
				(font
					(size 1 1)
					(thickness 0.15)
				)
			)
		)
		(property "Val" "0R"
			(at 84.14 210.84 0)
			(layer "F.Fab")
			(hide yes)
			(effects
				(font
					(size 1 1)
					(thickness 0.15)
				)
			)
		)
		(sheetname "/Power Supply/")
		(sheetfile "supply.kicad_sch")
		(attr smd)
		(fp_line
			(start -0.32 0.699)
			(end 0.28 0.699)
			(stroke
				(width 0.15)
				(type solid)
			)
			(layer "F.SilkS")
		)
		(fp_line
			(start -0.3 -0.701)
			(end 0.298 -0.701)
			(stroke
				(width 0.15)
				(type solid)
			)
			(layer "F.SilkS")
		)
		(fp_rect
			(start 1.95 -0.9)
			(end -1.95 0.9)
			(stroke
				(width 0.05)
				(type default)
			)
			(fill no)
			(layer "F.CrtYd")
		)
		(fp_line
			(start -0.951 0.68)
			(end 0.949 0.68)
			(stroke
				(width 0.15)
				(type solid)
			)
			(layer "F.Fab")
		)
		(fp_line
			(start -0.951 -0.677)
			(end -0.951 0.675)
			(stroke
				(width 0.15)
				(type solid)
			)
			(layer "F.Fab")
		)
		(fp_line
			(start 0.949 -0.677)
			(end 0.949 0.675)
			(stroke
				(width 0.15)
				(type solid)
			)
			(layer "F.Fab")
		)
		(fp_line
			(start -0.951 -0.682)
			(end 0.949 -0.682)
			(stroke
				(width 0.15)
				(type solid)
			)
			(layer "F.Fab")
		)
		(fp_text user "Author: Antmicro"
			(at -1.9 4.4 270)
			(layer "F.Fab")
			(effects
				(font
					(size 0.7 0.7)
					(thickness 0.15)
				)
				(justify left bottom)
			)
		)
		(fp_text user "License: Apache-2.0"
			(at -1.9 5.75 270)
			(layer "F.Fab")
			(effects
				(font
					(size 0.7 0.7)
					(thickness 0.15)
				)
				(justify left bottom)
			)
		)
		(fp_text user "${REFERENCE}"
			(at -1.9 3.1 270)
			(layer "F.Fab")
			(effects
				(font
					(size 0.7 0.7)
					(thickness 0.15)
				)
				(justify left bottom)
			)
		)
		(pad "1" smd roundrect
			(at -1.1 0 270)
			(size 1.2 1.3)
			(layers "F.Cu" "F.Mask" "F.Paste")
			(roundrect_rratio 0.25)
			(net 327 "/Power Supply/5V_1V5_IN")
			(pintype "passive")
		)
		(pad "2" smd roundrect
			(at 1.1 0 270)
			(size 1.2 1.3)
			(layers "F.Cu" "F.Mask" "F.Paste")
			(roundrect_rratio 0.25)
			(net 14 "+5V")
			(pintype "passive")
		)
	)
	(footprint "antmicro-footprints:TP_SMD_0.75mm"
		(layer "F.Cu")
		(at 152.7908 72.64 90)
		(property "Reference" "TP2"
			(at 0.5 0.3392 90)
			(layer "F.SilkS")
			(effects
				(font
					(size 0.65 0.65)
					(thickness 0.15)
				)
				(justify left bottom)
			)
		)
		(property "Value" "TP_0.75mm_SMD"
			(at 0 1.2 90)
			(layer "F.Fab")
			(hide yes)
			(effects
				(font
					(size 0.7 0.7)
					(thickness 0.15)
				)
				(justify left bottom)
			)
		)
		(property "Description" "SMT test point"
			(at 0 0 90)
			(layer "F.Fab")
			(hide yes)
			(effects
				(font
					(size 1.27 1.27)
					(thickness 0.15)
				)
			)
		)
		(property "Author" "Antmicro"
			(at 225.4308 -80.1508 0)
			(layer "F.Fab")
			(hide yes)
			(effects
				(font
					(size 1 1)
					(thickness 0.15)
				)
			)
		)
		(property "License" "Apache-2.0"
			(at 225.4308 -80.1508 0)
			(layer "F.Fab")
			(hide yes)
			(effects
				(font
					(size 1 1)
					(thickness 0.15)
				)
			)
		)
		(property "MPN" ""
			(at 225.4308 -80.1508 0)
			(layer "F.Fab")
			(hide yes)
			(effects
				(font
					(size 1 1)
					(thickness 0.15)
				)
			)
		)
		(property "Manufacturer" ""
			(at 225.4308 -80.1508 0)
			(layer "F.Fab")
			(hide yes)
			(effects
				(font
					(size 1 1)
					(thickness 0.15)
				)
			)
		)
		(sheetname "/Power Supply/")
		(sheetfile "supply.kicad_sch")
		(attr exclude_from_pos_files)
		(fp_circle
			(center 0 0)
			(end 0.475 0)
			(stroke
				(width 0.05)
				(type default)
			)
			(fill no)
			(layer "F.CrtYd")
		)
		(fp_text user "${REFERENCE}"
			(at -0.4 2.7 90)
			(layer "F.Fab")
			(effects
				(font
					(size 0.7 0.7)
					(thickness 0.15)
				)
				(justify left bottom)
			)
		)
		(fp_text user "Author: Antmicro"
			(at -0.4 3.901 90)
			(layer "F.Fab")
			(effects
				(font
					(size 0.7 0.7)
					(thickness 0.15)
				)
				(justify left bottom)
			)
		)
		(fp_text user "License: Apache-2.0"
			(at -0.4 5.101 90)
			(layer "F.Fab")
			(effects
				(font
					(size 0.7 0.7)
					(thickness 0.15)
				)
				(justify left bottom)
			)
		)
		(pad "1" smd circle
			(at 0 0 90)
			(size 0.75 0.75)
			(layers "F.Cu" "F.Mask")
			(net 14 "+5V")
			(pinfunction "1")
			(pintype "passive")
		)
	)
	(footprint "antmicro-footprints:TP_SMD_0.75mm"
		(layer "F.Cu")
		(at 100.25 68.25)
		(property "Reference" "TP27"
			(at 0.53 0.39 0)
			(layer "F.SilkS")
			(effects
				(font
					(size 0.65 0.65)
					(thickness 0.15)
				)
				(justify left bottom)
			)
		)
		(property "Value" "TP_0.75mm_SMD"
			(at 0 1.2 0)
			(layer "F.Fab")
			(hide yes)
			(effects
				(font
					(size 0.7 0.7)
					(thickness 0.15)
				)
				(justify left bottom)
			)
		)
		(property "Description" "SMT test point"
			(at 0 0 0)
			(layer "F.Fab")
			(hide yes)
			(effects
				(font
					(size 1.27 1.27)
					(thickness 0.15)
				)
			)
		)
		(property "Author" "Antmicro"
			(at 0 0 0)
			(layer "F.Fab")
			(hide yes)
			(effects
				(font
					(size 1 1)
					(thickness 0.15)
				)
			)
		)
		(property "License" "Apache-2.0"
			(at 0 0 0)
			(layer "F.Fab")
			(hide yes)
			(effects
				(font
					(size 1 1)
					(thickness 0.15)
				)
			)
		)
		(property "MPN" ""
			(at 0 0 0)
			(layer "F.Fab")
			(hide yes)
			(effects
				(font
					(size 1 1)
					(thickness 0.15)
				)
			)
		)
		(property "Manufacturer" ""
			(at 0 0 0)
			(layer "F.Fab")
			(hide yes)
			(effects
				(font
					(size 1 1)
					(thickness 0.15)
				)
			)
		)
		(sheetname "/SDI/")
		(sheetfile "sdi.kicad_sch")
		(attr exclude_from_pos_files)
		(fp_circle
			(center 0 0)
			(end 0.475 0)
			(stroke
				(width 0.05)
				(type default)
			)
			(fill no)
			(layer "F.CrtYd")
		)
		(fp_text user "License: Apache-2.0"
			(at -0.4 5.101 0)
			(layer "F.Fab")
			(effects
				(font
					(size 0.7 0.7)
					(thickness 0.15)
				)
				(justify left bottom)
			)
		)
		(fp_text user "Author: Antmicro"
			(at -0.4 3.901 0)
			(layer "F.Fab")
			(effects
				(font
					(size 0.7 0.7)
					(thickness 0.15)
				)
				(justify left bottom)
			)
		)
		(fp_text user "${REFERENCE}"
			(at -0.4 2.7 0)
			(layer "F.Fab")
			(effects
				(font
					(size 0.7 0.7)
					(thickness 0.15)
				)
				(justify left bottom)
			)
		)
		(pad "1" smd circle
			(at 0 0)
			(size 0.75 0.75)
			(layers "F.Cu" "F.Mask")
			(net 218 "/SDI/SDI_STAT4")
			(pinfunction "1")
			(pintype "passive")
		)
	)
	(footprint "antmicro-footprints:Conn_FFC_WE_68715014x22"
		(layer "F.Cu")
		(at 124.93 122.27)
		(property "Reference" "J6"
			(at 0 -3.4 0)
			(layer "F.SilkS")
			(effects
				(font
					(size 0.65 0.65)
					(thickness 0.15)
				)
				(justify left bottom)
			)
		)
		(property "Value" "Conn_FFC_WE_68715014522_ONE-SIDE"
			(at 0 4.5 0)
			(layer "F.Fab")
			(hide yes)
			(effects
				(font
					(size 0.7 0.7)
					(thickness 0.15)
				)
				(justify left bottom)
			)
		)
		(property "Datasheet" "https://www.we-online.com/components/products/datasheet/68715014522.pdf"
			(at 0 0 0)
			(layer "F.Fab")
			(hide yes)
			(effects
				(font
					(size 1.27 1.27)
					(thickness 0.15)
				)
			)
		)
		(property "Description" "FFC connector"
			(at 0 0 0)
			(layer "F.Fab")
			(hide yes)
			(effects
				(font
					(size 1.27 1.27)
					(thickness 0.15)
				)
			)
		)
		(property "Author" "Antmicro"
			(at 0 0 0)
			(layer "F.Fab")
			(hide yes)
			(effects
				(font
					(size 1 1)
					(thickness 0.15)
				)
			)
		)
		(property "License" "Apache-2.0"
			(at 0 0 0)
			(layer "F.Fab")
			(hide yes)
			(effects
				(font
					(size 1 1)
					(thickness 0.15)
				)
			)
		)
		(property "MPN" "68715014522"
			(at 0 0 0)
			(layer "F.Fab")
			(hide yes)
			(effects
				(font
					(size 1 1)
					(thickness 0.15)
				)
			)
		)
		(property "Manufacturer" "Würth Elektronik"
			(at 0 0 0)
			(layer "F.Fab")
			(hide yes)
			(effects
				(font
					(size 1 1)
					(thickness 0.15)
				)
			)
		)
		(sheetname "/Peripherals/")
		(sheetfile "peripherals.kicad_sch")
		(attr smd)
		(fp_line
			(start -15.85 -2.15)
			(end -12.5 -2.15)
			(stroke
				(width 0.15)
				(type solid)
			)
			(layer "F.SilkS")
		)
		(fp_line
			(start -15.85 2.7)
			(end -15.85 -2.15)
			(stroke
				(width 0.15)
				(type solid)
			)
			(layer "F.SilkS")
		)
		(fp_line
			(start -12.5 -2.976)
			(end 12.499 -2.976)
			(stroke
				(width 0.15)
				(type solid)
			)
			(layer "F.SilkS")
		)
		(fp_line
			(start -12.5 -2.15)
			(end -12.5 -2.976)
			(stroke
				(width 0.15)
				(type solid)
			)
			(layer "F.SilkS")
		)
		(fp_line
			(start 12.499 -2.15)
			(end 12.499 -2.976)
			(stroke
				(width 0.15)
				(type solid)
			)
			(layer "F.SilkS")
		)
		(fp_line
			(start 15.85 -2.15)
			(end 12.499 -2.15)
			(stroke
				(width 0.15)
				(type solid)
			)
			(layer "F.SilkS")
		)
		(fp_line
			(start 15.85 2.7)
			(end -15.85 2.7)
			(stroke
				(width 0.15)
				(type solid)
			)
			(layer "F.SilkS")
		)
		(fp_line
			(start 15.85 2.7)
			(end 15.85 -2.15)
			(stroke
				(width 0.15)
				(type solid)
			)
			(layer "F.SilkS")
		)
		(fp_circle
			(center -12.9 -2.9)
			(end -12.85 -2.85)
			(stroke
				(width 0.15)
				(type solid)
			)
			(fill yes)
			(layer "F.SilkS")
		)
		(fp_rect
			(start -16.2 -3.25)
			(end 16.2 3.55)
			(stroke
				(width 0.05)
				(type solid)
			)
			(fill no)
			(layer "F.CrtYd")
		)
		(fp_text user "Author: Antmicro"
			(at -16.2 6.9 0)
			(layer "F.Fab")
			(effects
				(font
					(size 0.7 0.7)
					(thickness 0.15)
				)
				(justify left bottom)
			)
		)
		(fp_text user "${REFERENCE}"
			(at -16.2 5.9 0)
			(layer "F.Fab")
			(effects
				(font
					(size 0.7 0.7)
					(thickness 0.15)
				)
				(justify left bottom)
			)
		)
		(fp_text user "License: Apache-2.0"
			(at -16.2 7.9 0)
			(layer "F.Fab")
			(effects
				(font
					(size 0.7 0.7)
					(thickness 0.15)
				)
				(justify left bottom)
			)
		)
		(pad "1" smd roundrect
			(at -12.25 -2.15)
			(size 0.3 1.2)
			(layers "F.Cu" "F.Mask" "F.Paste")
			(roundrect_rratio 0.25)
			(net 133 "unconnected-(J6-Pad1)")
			(pintype "passive+no_connect")
		)
		(pad "2" smd roundrect
			(at -11.75 -2.15)
			(size 0.3 1.2)
			(layers "F.Cu" "F.Mask" "F.Paste")
			(roundrect_rratio 0.25)
			(net 132 "unconnected-(J6-Pad2)")
			(pintype "passive+no_connect")
		)
		(pad "3" smd roundrect
			(at -11.25 -2.15)
			(size 0.3 1.2)
			(layers "F.Cu" "F.Mask" "F.Paste")
			(roundrect_rratio 0.25)
			(net 131 "unconnected-(J6-Pad3)")
			(pintype "passive+no_connect")
		)
		(pad "4" smd roundrect
			(at -10.75 -2.15)
			(size 0.3 1.2)
			(layers "F.Cu" "F.Mask" "F.Paste")
			(roundrect_rratio 0.25)
			(net 130 "unconnected-(J6-Pad4)")
			(pintype "passive+no_connect")
		)
		(pad "5" smd roundrect
			(at -10.25 -2.15)
			(size 0.3 1.2)
			(layers "F.Cu" "F.Mask" "F.Paste")
			(roundrect_rratio 0.25)
			(net 129 "unconnected-(J6-Pad5)")
			(pintype "passive+no_connect")
		)
		(pad "6" smd roundrect
			(at -9.75 -2.15)
			(size 0.3 1.2)
			(layers "F.Cu" "F.Mask" "F.Paste")
			(roundrect_rratio 0.25)
			(net 128 "unconnected-(J6-Pad6)")
			(pintype "passive+no_connect")
		)
		(pad "7" smd roundrect
			(at -9.25 -2.15)
			(size 0.3 1.2)
			(layers "F.Cu" "F.Mask" "F.Paste")
			(roundrect_rratio 0.25)
			(net 127 "unconnected-(J6-Pad7)")
			(pintype "passive+no_connect")
		)
		(pad "8" smd roundrect
			(at -8.75 -2.15)
			(size 0.3 1.2)
			(layers "F.Cu" "F.Mask" "F.Paste")
			(roundrect_rratio 0.25)
			(net 126 "unconnected-(J6-Pad8)")
			(pintype "passive+no_connect")
		)
		(pad "9" smd roundrect
			(at -8.25 -2.15)
			(size 0.3 1.2)
			(layers "F.Cu" "F.Mask" "F.Paste")
			(roundrect_rratio 0.25)
			(net 1 "GND")
			(pintype "passive")
		)
		(pad "10" smd roundrect
			(at -7.75 -2.15)
			(size 0.3 1.2)
			(layers "F.Cu" "F.Mask" "F.Paste")
			(roundrect_rratio 0.25)
			(net 125 "unconnected-(J6-Pad10)")
			(pintype "passive+no_connect")
		)
		(pad "11" smd roundrect
			(at -7.25 -2.15)
			(size 0.3 1.2)
			(layers "F.Cu" "F.Mask" "F.Paste")
			(roundrect_rratio 0.25)
			(net 124 "unconnected-(J6-Pad11)")
			(pintype "passive+no_connect")
		)
		(pad "12" smd roundrect
			(at -6.75 -2.15)
			(size 0.3 1.2)
			(layers "F.Cu" "F.Mask" "F.Paste")
			(roundrect_rratio 0.25)
			(net 1 "GND")
			(pintype "passive")
		)
		(pad "13" smd roundrect
			(at -6.25 -2.15)
			(size 0.3 1.2)
			(layers "F.Cu" "F.Mask" "F.Paste")
			(roundrect_rratio 0.25)
			(net 123 "unconnected-(J6-Pad13)")
			(pintype "passive+no_connect")
		)
		(pad "14" smd roundrect
			(at -5.75 -2.15)
			(size 0.3 1.2)
			(layers "F.Cu" "F.Mask" "F.Paste")
			(roundrect_rratio 0.25)
			(net 122 "unconnected-(J6-Pad14)")
			(pintype "passive+no_connect")
		)
		(pad "15" smd roundrect
			(at -5.25 -2.15)
			(size 0.3 1.2)
			(layers "F.Cu" "F.Mask" "F.Paste")
			(roundrect_rratio 0.25)
			(net 1 "GND")
			(pintype "passive")
		)
		(pad "16" smd roundrect
			(at -4.75 -2.15)
			(size 0.3 1.2)
			(layers "F.Cu" "F.Mask" "F.Paste")
			(roundrect_rratio 0.25)
			(net 121 "unconnected-(J6-Pad16)")
			(pintype "passive+no_connect")
		)
		(pad "17" smd roundrect
			(at -4.25 -2.15)
			(size 0.3 1.2)
			(layers "F.Cu" "F.Mask" "F.Paste")
			(roundrect_rratio 0.25)
			(net 120 "unconnected-(J6-Pad17)")
			(pintype "passive+no_connect")
		)
		(pad "18" smd roundrect
			(at -3.75 -2.15)
			(size 0.3 1.2)
			(layers "F.Cu" "F.Mask" "F.Paste")
			(roundrect_rratio 0.25)
			(net 1 "GND")
			(pintype "passive")
		)
		(pad "19" smd roundrect
			(at -3.25 -2.15)
			(size 0.3 1.2)
			(layers "F.Cu" "F.Mask" "F.Paste")
			(roundrect_rratio 0.25)
			(net 119 "/Peripherals/MIPI1_D3_N")
			(pintype "passive")
		)
		(pad "20" smd roundrect
			(at -2.75 -2.15)
			(size 0.3 1.2)
			(layers "F.Cu" "F.Mask" "F.Paste")
			(roundrect_rratio 0.25)
			(net 118 "/Peripherals/MIPI1_D3_P")
			(pintype "passive")
		)
		(pad "21" smd roundrect
			(at -2.25 -2.15)
			(size 0.3 1.2)
			(layers "F.Cu" "F.Mask" "F.Paste")
			(roundrect_rratio 0.25)
			(net 117 "/Peripherals/MIPI1_D2_N")
			(pintype "passive")
		)
		(pad "22" smd roundrect
			(at -1.75 -2.15)
			(size 0.3 1.2)
			(layers "F.Cu" "F.Mask" "F.Paste")
			(roundrect_rratio 0.25)
			(net 116 "/Peripherals/MIPI1_D2_P")
			(pintype "passive")
		)
		(pad "23" smd roundrect
			(at -1.25 -2.15)
			(size 0.3 1.2)
			(layers "F.Cu" "F.Mask" "F.Paste")
			(roundrect_rratio 0.25)
			(net 115 "/Peripherals/MIPI1_D1_N")
			(pintype "passive")
		)
		(pad "24" smd roundrect
			(at -0.75 -2.15)
			(size 0.3 1.2)
			(layers "F.Cu" "F.Mask" "F.Paste")
			(roundrect_rratio 0.25)
			(net 114 "/Peripherals/MIPI1_D1_P")
			(pintype "passive")
		)
		(pad "25" smd roundrect
			(at -0.25 -2.15)
			(size 0.3 1.2)
			(layers "F.Cu" "F.Mask" "F.Paste")
			(roundrect_rratio 0.25)
			(net 113 "/Peripherals/MIPI1_D0_N")
			(pintype "passive")
		)
		(pad "26" smd roundrect
			(at 0.248 -2.15)
			(size 0.3 1.2)
			(layers "F.Cu" "F.Mask" "F.Paste")
			(roundrect_rratio 0.25)
			(net 112 "/Peripherals/MIPI1_D0_P")
			(pintype "passive")
		)
		(pad "27" smd roundrect
			(at 0.748 -2.15)
			(size 0.3 1.2)
			(layers "F.Cu" "F.Mask" "F.Paste")
			(roundrect_rratio 0.25)
			(net 1 "GND")
			(pintype "passive")
		)
		(pad "28" smd roundrect
			(at 1.249 -2.15)
			(size 0.3 1.2)
			(layers "F.Cu" "F.Mask" "F.Paste")
			(roundrect_rratio 0.25)
			(net 111 "/Peripherals/MIPI1_CLK_N")
			(pintype "passive")
		)
		(pad "29" smd roundrect
			(at 1.749 -2.15)
			(size 0.3 1.2)
			(layers "F.Cu" "F.Mask" "F.Paste")
			(roundrect_rratio 0.25)
			(net 110 "/Peripherals/MIPI1_CLK_P")
			(pintype "passive")
		)
		(pad "30" smd roundrect
			(at 2.249 -2.15)
			(size 0.3 1.2)
			(layers "F.Cu" "F.Mask" "F.Paste")
			(roundrect_rratio 0.25)
			(net 1 "GND")
			(pintype "passive")
		)
		(pad "31" smd roundrect
			(at 2.749 -2.15)
			(size 0.3 1.2)
			(layers "F.Cu" "F.Mask" "F.Paste")
			(roundrect_rratio 0.25)
			(net 109 "unconnected-(J6-Pad31)")
			(pintype "passive+no_connect")
		)
		(pad "32" smd roundrect
			(at 3.249 -2.15)
			(size 0.3 1.2)
			(layers "F.Cu" "F.Mask" "F.Paste")
			(roundrect_rratio 0.25)
			(net 343 "Net-(J6-Pad32)")
			(pintype "passive")
		)
		(pad "33" smd roundrect
			(at 3.749 -2.15)
			(size 0.3 1.2)
			(layers "F.Cu" "F.Mask" "F.Paste")
			(roundrect_rratio 0.25)
			(net 344 "Net-(J6-Pad33)")
			(pintype "passive")
		)
		(pad "34" smd roundrect
			(at 4.248 -2.15)
			(size 0.3 1.2)
			(layers "F.Cu" "F.Mask" "F.Paste")
			(roundrect_rratio 0.25)
			(net 345 "Net-(J6-Pad34)")
			(pintype "passive")
		)
		(pad "35" smd roundrect
			(at 4.748 -2.15)
			(size 0.3 1.2)
			(layers "F.Cu" "F.Mask" "F.Paste")
			(roundrect_rratio 0.25)
			(net 105 "unconnected-(J6-Pad35)")
			(pintype "passive+no_connect")
		)
		(pad "36" smd roundrect
			(at 5.248 -2.15)
			(size 0.3 1.2)
			(layers "F.Cu" "F.Mask" "F.Paste")
			(roundrect_rratio 0.25)
			(net 104 "unconnected-(J6-Pad36)")
			(pintype "passive+no_connect")
		)
		(pad "37" smd roundrect
			(at 5.749 -2.15)
			(size 0.3 1.2)
			(layers "F.Cu" "F.Mask" "F.Paste")
			(roundrect_rratio 0.25)
			(net 103 "unconnected-(J6-Pad37)")
			(pintype "passive+no_connect")
		)
		(pad "38" smd roundrect
			(at 6.249 -2.15)
			(size 0.3 1.2)
			(layers "F.Cu" "F.Mask" "F.Paste")
			(roundrect_rratio 0.25)
			(net 102 "unconnected-(J6-Pad38)")
			(pintype "passive+no_connect")
		)
		(pad "39" smd roundrect
			(at 6.749 -2.15)
			(size 0.3 1.2)
			(layers "F.Cu" "F.Mask" "F.Paste")
			(roundrect_rratio 0.25)
			(net 323 "Net-(J6-Pad39)")
			(pintype "passive")
		)
		(pad "40" smd roundrect
			(at 7.249 -2.15)
			(size 0.3 1.2)
			(layers "F.Cu" "F.Mask" "F.Paste")
			(roundrect_rratio 0.25)
			(net 302 "Net-(J6-Pad40)")
			(pintype "passive")
		)
		(pad "41" smd roundrect
			(at 7.749 -2.15)
			(size 0.3 1.2)
			(layers "F.Cu" "F.Mask" "F.Paste")
			(roundrect_rratio 0.25)
			(net 346 "Net-(J6-Pad41)")
			(pintype "passive")
		)
		(pad "42" smd roundrect
			(at 8.249 -2.15)
			(size 0.3 1.2)
			(layers "F.Cu" "F.Mask" "F.Paste")
			(roundrect_rratio 0.25)
			(net 347 "Net-(J6-Pad42)")
			(pintype "passive")
		)
		(pad "43" smd roundrect
			(at 8.749 -2.15)
			(size 0.3 1.2)
			(layers "F.Cu" "F.Mask" "F.Paste")
			(roundrect_rratio 0.25)
			(net 98 "unconnected-(J6-Pad43)")
			(pintype "passive+no_connect")
		)
		(pad "44" smd roundrect
			(at 9.249 -2.15)
			(size 0.3 1.2)
			(layers "F.Cu" "F.Mask" "F.Paste")
			(roundrect_rratio 0.25)
			(net 97 "unconnected-(J6-Pad44)")
			(pintype "passive+no_connect")
		)
		(pad "45" smd roundrect
			(at 9.749 -2.15)
			(size 0.3 1.2)
			(layers "F.Cu" "F.Mask" "F.Paste")
			(roundrect_rratio 0.25)
			(net 96 "unconnected-(J6-Pad45)")
			(pintype "passive+no_connect")
		)
		(pad "46" smd roundrect
			(at 10.249 -2.15)
			(size 0.3 1.2)
			(layers "F.Cu" "F.Mask" "F.Paste")
			(roundrect_rratio 0.25)
			(net 95 "unconnected-(J6-Pad46)")
			(pintype "passive+no_connect")
		)
		(pad "47" smd roundrect
			(at 10.749 -2.15)
			(size 0.3 1.2)
			(layers "F.Cu" "F.Mask" "F.Paste")
			(roundrect_rratio 0.25)
			(net 18 "/Peripherals/FFC2_3V3")
			(pintype "passive")
		)
		(pad "48" smd roundrect
			(at 11.249 -2.15)
			(size 0.3 1.2)
			(layers "F.Cu" "F.Mask" "F.Paste")
			(roundrect_rratio 0.25)
			(net 18 "/Peripherals/FFC2_3V3")
			(pintype "passive")
		)
		(pad "49" smd roundrect
			(at 11.749 -2.15)
			(size 0.3 1.2)
			(layers "F.Cu" "F.Mask" "F.Paste")
			(roundrect_rratio 0.25)
			(net 19 "FFC2_5V")
			(pintype "passive")
		)
		(pad "50" smd roundrect
			(at 12.249 -2.15)
			(size 0.3 1.2)
			(layers "F.Cu" "F.Mask" "F.Paste")
			(roundrect_rratio 0.25)
			(net 19 "FFC2_5V")
			(pintype "passive")
		)
		(pad "MP1" smd roundrect
			(at -14.198 -0.3)
			(size 2.7 3)
			(layers "F.Cu" "F.Mask" "F.Paste")
			(roundrect_rratio 0.05)
			(net 1 "GND")
			(pinfunction "MP")
			(pintype "passive")
		)
		(pad "MP2" smd roundrect
			(at 14.198 -0.3)
			(size 2.7 3)
			(layers "F.Cu" "F.Mask" "F.Paste")
			(roundrect_rratio 0.05)
			(net 1 "GND")
			(pinfunction "MP")
			(pintype "passive")
		)
	)
	(footprint "antmicro-footprints:TP_SMD_0.75mm"
		(layer "F.Cu")
		(at 88.7 109.25)
		(property "Reference" "TP14"
			(at -2.07 1.39 0)
			(layer "F.SilkS")
			(effects
				(font
					(size 0.65 0.65)
					(thickness 0.15)
				)
				(justify left bottom)
			)
		)
		(property "Value" "TP_0.75mm_SMD"
			(at 0 1.2 0)
			(layer "F.Fab")
			(hide yes)
			(effects
				(font
					(size 0.7 0.7)
					(thickness 0.15)
				)
				(justify left bottom)
			)
		)
		(property "Description" "SMT test point"
			(at 0 0 0)
			(layer "F.Fab")
			(hide yes)
			(effects
				(font
					(size 1.27 1.27)
					(thickness 0.15)
				)
			)
		)
		(property "Author" "Antmicro"
			(at 0 0 0)
			(layer "F.Fab")
			(hide yes)
			(effects
				(font
					(size 1 1)
					(thickness 0.15)
				)
			)
		)
		(property "License" "Apache-2.0"
			(at 0 0 0)
			(layer "F.Fab")
			(hide yes)
			(effects
				(font
					(size 1 1)
					(thickness 0.15)
				)
			)
		)
		(property "MPN" ""
			(at 0 0 0)
			(layer "F.Fab")
			(hide yes)
			(effects
				(font
					(size 1 1)
					(thickness 0.15)
				)
			)
		)
		(property "Manufacturer" ""
			(at 0 0 0)
			(layer "F.Fab")
			(hide yes)
			(effects
				(font
					(size 1 1)
					(thickness 0.15)
				)
			)
		)
		(sheetname "/SDI/")
		(sheetfile "sdi.kicad_sch")
		(attr exclude_from_pos_files)
		(fp_circle
			(center 0 0)
			(end 0.475 0)
			(stroke
				(width 0.05)
				(type default)
			)
			(fill no)
			(layer "F.CrtYd")
		)
		(fp_text user "License: Apache-2.0"
			(at -0.4 5.101 0)
			(layer "F.Fab")
			(effects
				(font
					(size 0.7 0.7)
					(thickness 0.15)
				)
				(justify left bottom)
			)
		)
		(fp_text user "Author: Antmicro"
			(at -0.4 3.901 0)
			(layer "F.Fab")
			(effects
				(font
					(size 0.7 0.7)
					(thickness 0.15)
				)
				(justify left bottom)
			)
		)
		(fp_text user "${REFERENCE}"
			(at -0.4 2.7 0)
			(layer "F.Fab")
			(effects
				(font
					(size 0.7 0.7)
					(thickness 0.15)
				)
				(justify left bottom)
			)
		)
		(pad "1" smd circle
			(at 0 0)
			(size 0.75 0.75)
			(layers "F.Cu" "F.Mask")
			(net 378 "Net-(U16-~{OSP})")
			(pinfunction "1")
			(pintype "passive")
		)
	)
	(footprint "antmicro-footprints:R_0402_1005Metric"
		(layer "F.Cu")
		(at 167.2 90.6 180)
		(descr "Resistor SMD 0402")
		(tags "resistor SMD 0402")
		(property "Reference" "R125"
			(at 3.67 -0.34 180)
			(layer "F.SilkS")
			(effects
				(font
					(size 0.65 0.65)
					(thickness 0.15)
				)
				(justify left bottom)
			)
		)
		(property "Value" "R_0R_0402"
			(at 0 1.4 180)
			(layer "F.Fab")
			(hide yes)
			(effects
				(font
					(size 0.7 0.7)
					(thickness 0.15)
				)
				(justify left bottom)
			)
		)
		(property "Datasheet" "https://industrial.panasonic.com/cdbs/www-data/pdf/RDA0000/AOA0000C301.pdf"
			(at 0 0 180)
			(layer "F.Fab")
			(hide yes)
			(effects
				(font
					(size 1.27 1.27)
					(thickness 0.15)
				)
			)
		)
		(property "Description" "SMD Chip Resistor, Jumper, 0 ohm, 100 mW, 0402 [1005 Metric], Thick Film, General Purpose"
			(at 0 0 180)
			(layer "F.Fab")
			(hide yes)
			(effects
				(font
					(size 1.27 1.27)
					(thickness 0.15)
				)
			)
		)
		(property "Author" "Antmicro"
			(at 334.4 181.2 0)
			(layer "F.Fab")
			(hide yes)
			(effects
				(font
					(size 1 1)
					(thickness 0.15)
				)
			)
		)
		(property "Current" "1A"
			(at 334.4 181.2 0)
			(layer "F.Fab")
			(hide yes)
			(effects
				(font
					(size 1 1)
					(thickness 0.15)
				)
			)
		)
		(property "License" "Apache-2.0"
			(at 334.4 181.2 0)
			(layer "F.Fab")
			(hide yes)
			(effects
				(font
					(size 1 1)
					(thickness 0.15)
				)
			)
		)
		(property "MPN" "ERJ2GE0R00X"
			(at 334.4 181.2 0)
			(layer "F.Fab")
			(hide yes)
			(effects
				(font
					(size 1 1)
					(thickness 0.15)
				)
			)
		)
		(property "Manufacturer" "Panasonic"
			(at 334.4 181.2 0)
			(layer "F.Fab")
			(hide yes)
			(effects
				(font
					(size 1 1)
					(thickness 0.15)
				)
			)
		)
		(property "Tolerance" "~"
			(at 334.4 181.2 0)
			(layer "F.Fab")
			(hide yes)
			(effects
				(font
					(size 1 1)
					(thickness 0.15)
				)
			)
		)
		(property "Val" "0R"
			(at 334.4 181.2 0)
			(layer "F.Fab")
			(hide yes)
			(effects
				(font
					(size 1 1)
					(thickness 0.15)
				)
			)
		)
		(sheetname "/Peripherals/")
		(sheetfile "peripherals.kicad_sch")
		(attr smd)
		(fp_rect
			(start -0.925 -0.47)
			(end 0.925 0.47)
			(stroke
				(width 0.05)
				(type default)
			)
			(fill no)
			(layer "F.CrtYd")
		)
		(fp_rect
			(start -0.5 -0.25)
			(end 0.5 0.25)
			(stroke
				(width 0.15)
				(type solid)
			)
			(fill no)
			(layer "F.Fab")
		)
		(fp_text user "${REFERENCE}"
			(at -0.95 3.168 180)
			(layer "F.Fab")
			(effects
				(font
					(size 0.7 0.7)
					(thickness 0.15)
				)
				(justify left bottom)
			)
		)
		(fp_text user "Author: Antmicro"
			(at -0.95 4.169 180)
			(layer "F.Fab")
			(effects
				(font
					(size 0.7 0.7)
					(thickness 0.15)
				)
				(justify left bottom)
			)
		)
		(fp_text user "License: Apache-2.0"
			(at -0.95 5.169 180)
			(layer "F.Fab")
			(effects
				(font
					(size 0.7 0.7)
					(thickness 0.15)
				)
				(justify left bottom)
			)
		)
		(pad "1" smd roundrect
			(at -0.48 0 180)
			(size 0.59 0.64)
			(layers "F.Cu" "F.Mask" "F.Paste")
			(roundrect_rratio 0.25)
			(net 366 "Net-(J4-Pad42)")
			(pintype "passive")
		)
		(pad "2" smd roundrect
			(at 0.48 0 180)
			(size 0.59 0.64)
			(layers "F.Cu" "F.Mask" "F.Paste")
			(roundrect_rratio 0.25)
			(net 94 "/Peripherals/FCC1_SCL2")
			(pintype "passive")
		)
	)
	(footprint "antmicro-footprints:R_0805_2012Metric"
		(layer "F.Cu")
		(at 159.805 68.55 90)
		(property "Reference" "R17"
			(at -3.99 0.325 90)
			(layer "F.SilkS")
			(effects
				(font
					(size 0.65 0.65)
					(thickness 0.15)
				)
				(justify left bottom)
			)
		)
		(property "Value" "R_0R_0805"
			(at 0 1.8 90)
			(layer "F.Fab")
			(hide yes)
			(effects
				(font
					(size 0.7 0.7)
					(thickness 0.15)
				)
				(justify left bottom)
			)
		)
		(property "Datasheet" "https://www.vishay.com/docs/20035/dcrcwe3.pdf"
			(at 0 0 90)
			(layer "F.Fab")
			(hide yes)
			(effects
				(font
					(size 1.27 1.27)
					(thickness 0.15)
				)
			)
		)
		(property "Description" "Zero Ohm Resistor, Jumper, 0805 [2012 Metric], Thick Film, 125 mW, 2.5 A, Surface Mount Device"
			(at 0 0 90)
			(layer "F.Fab")
			(hide yes)
			(effects
				(font
					(size 1.27 1.27)
					(thickness 0.15)
				)
			)
		)
		(property "Author" "Antmicro"
			(at 228.355 -91.255 0)
			(layer "F.Fab")
			(hide yes)
			(effects
				(font
					(size 1 1)
					(thickness 0.15)
				)
			)
		)
		(property "Current" "2.5A"
			(at 228.355 -91.255 0)
			(layer "F.Fab")
			(hide yes)
			(effects
				(font
					(size 1 1)
					(thickness 0.15)
				)
			)
		)
		(property "License" "Apache-2.0"
			(at 228.355 -91.255 0)
			(layer "F.Fab")
			(hide yes)
			(effects
				(font
					(size 1 1)
					(thickness 0.15)
				)
			)
		)
		(property "MPN" "CRCW08050000Z0EA"
			(at 228.355 -91.255 0)
			(layer "F.Fab")
			(hide yes)
			(effects
				(font
					(size 1 1)
					(thickness 0.15)
				)
			)
		)
		(property "Manufacturer" "Vishay"
			(at 228.355 -91.255 0)
			(layer "F.Fab")
			(hide yes)
			(effects
				(font
					(size 1 1)
					(thickness 0.15)
				)
			)
		)
		(property "Tolerance" "~"
			(at 228.355 -91.255 0)
			(layer "F.Fab")
			(hide yes)
			(effects
				(font
					(size 1 1)
					(thickness 0.15)
				)
			)
		)
		(property "Val" "0R"
			(at 228.355 -91.255 0)
			(layer "F.Fab")
			(hide yes)
			(effects
				(font
					(size 1 1)
					(thickness 0.15)
				)
			)
		)
		(sheetname "/Power Supply/")
		(sheetfile "supply.kicad_sch")
		(attr smd)
		(fp_line
			(start -0.3 -0.701)
			(end 0.298 -0.701)
			(stroke
				(width 0.15)
				(type solid)
			)
			(layer "F.SilkS")
		)
		(fp_line
			(start -0.32 0.699)
			(end 0.28 0.699)
			(stroke
				(width 0.15)
				(type solid)
			)
			(layer "F.SilkS")
		)
		(fp_rect
			(start 1.95 -0.9)
			(end -1.95 0.9)
			(stroke
				(width 0.05)
				(type default)
			)
			(fill no)
			(layer "F.CrtYd")
		)
		(fp_line
			(start -0.951 -0.682)
			(end 0.949 -0.682)
			(stroke
				(width 0.15)
				(type solid)
			)
			(layer "F.Fab")
		)
		(fp_line
			(start 0.949 -0.677)
			(end 0.949 0.675)
			(stroke
				(width 0.15)
				(type solid)
			)
			(layer "F.Fab")
		)
		(fp_line
			(start -0.951 -0.677)
			(end -0.951 0.675)
			(stroke
				(width 0.15)
				(type solid)
			)
			(layer "F.Fab")
		)
		(fp_line
			(start -0.951 0.68)
			(end 0.949 0.68)
			(stroke
				(width 0.15)
				(type solid)
			)
			(layer "F.Fab")
		)
		(fp_text user "License: Apache-2.0"
			(at -1.9 5.75 90)
			(layer "F.Fab")
			(effects
				(font
					(size 0.7 0.7)
					(thickness 0.15)
				)
				(justify left bottom)
			)
		)
		(fp_text user "Author: Antmicro"
			(at -1.9 4.4 90)
			(layer "F.Fab")
			(effects
				(font
					(size 0.7 0.7)
					(thickness 0.15)
				)
				(justify left bottom)
			)
		)
		(fp_text user "${REFERENCE}"
			(at -1.9 3.1 90)
			(layer "F.Fab")
			(effects
				(font
					(size 0.7 0.7)
					(thickness 0.15)
				)
				(justify left bottom)
			)
		)
		(pad "1" smd roundrect
			(at -1.1 0 90)
			(size 1.2 1.3)
			(layers "F.Cu" "F.Mask" "F.Paste")
			(roundrect_rratio 0.25)
			(net 14 "+5V")
			(pintype "passive")
		)
		(pad "2" smd roundrect
			(at 1.1 0 90)
			(size 1.2 1.3)
			(layers "F.Cu" "F.Mask" "F.Paste")
			(roundrect_rratio 0.25)
			(net 328 "/Power Supply/5V_3V3_IN")
			(pintype "passive")
		)
	)
	(footprint "antmicro-footprints:PinHeader_2x5_P1.27mm_SMD_Shrouded"
		(layer "F.Cu")
		(at 101 119.7)
		(property "Reference" "J7"
			(at -6.601 -3.801 0)
			(layer "F.SilkS")
			(effects
				(font
					(size 0.65 0.65)
					(thickness 0.15)
				)
				(justify left bottom)
			)
		)
		(property "Value" "PinHeader_2x5_P2mm_Drill0.71mm_Shrouded"
			(at -6.75 4.75 0)
			(layer "F.Fab")
			(hide yes)
			(effects
				(font
					(size 0.7 0.7)
					(thickness 0.15)
				)
				(justify left bottom)
			)
		)
		(property "Datasheet" "https://eu.mouser.com/datasheet/2/527/shf-1370134.pdf"
			(at 0 0 0)
			(layer "F.Fab")
			(hide yes)
			(effects
				(font
					(size 1.27 1.27)
					(thickness 0.15)
				)
			)
		)
		(property "Description" "Headers & Wire Housings Shrouded Terminal Strip, 0.050\" pitch"
			(at 0 0 0)
			(layer "F.Fab")
			(hide yes)
			(effects
				(font
					(size 1.27 1.27)
					(thickness 0.15)
				)
			)
		)
		(property "Author" "Antmicro"
			(at 0 0 0)
			(layer "F.Fab")
			(hide yes)
			(effects
				(font
					(size 1 1)
					(thickness 0.15)
				)
			)
		)
		(property "License" "Apache-2.0"
			(at 0 0 0)
			(layer "F.Fab")
			(hide yes)
			(effects
				(font
					(size 1 1)
					(thickness 0.15)
				)
			)
		)
		(property "MPN" "SHF-105-01-L-D-SM"
			(at 0 0 0)
			(layer "F.Fab")
			(hide yes)
			(effects
				(font
					(size 1 1)
					(thickness 0.15)
				)
			)
		)
		(property "Manufacturer" "Samtec"
			(at 0 0 0)
			(layer "F.Fab")
			(hide yes)
			(effects
				(font
					(size 1 1)
					(thickness 0.15)
				)
			)
		)
		(sheetname "/FPGA/")
		(sheetfile "fpga.kicad_sch")
		(attr smd)
		(fp_line
			(start -6.415 -2.86)
			(end -3.286 -2.86)
			(stroke
				(width 0.15)
				(type solid)
			)
			(layer "F.SilkS")
		)
		(fp_line
			(start -6.415 2.858)
			(end -6.415 -2.86)
			(stroke
				(width 0.15)
				(type solid)
			)
			(layer "F.SilkS")
		)
		(fp_line
			(start -6.415 2.858)
			(end -3.286 2.858)
			(stroke
				(width 0.15)
				(type solid)
			)
			(layer "F.SilkS")
		)
		(fp_line
			(start 3.285 -2.86)
			(end 6.413 -2.86)
			(stroke
				(width 0.15)
				(type solid)
			)
			(layer "F.SilkS")
		)
		(fp_line
			(start 3.285 2.858)
			(end 6.413 2.858)
			(stroke
				(width 0.15)
				(type solid)
			)
			(layer "F.SilkS")
		)
		(fp_line
			(start 6.413 2.858)
			(end 6.413 -2.86)
			(stroke
				(width 0.15)
				(type solid)
			)
			(layer "F.SilkS")
		)
		(fp_rect
			(start -6.601 -3.498)
			(end 6.599 3.547)
			(stroke
				(width 0.05)
				(type solid)
			)
			(fill no)
			(layer "F.CrtYd")
		)
		(fp_line
			(start -6.415 -2.86)
			(end 6.413 -2.86)
			(stroke
				(width 0.15)
				(type solid)
			)
			(layer "F.Fab")
		)
		(fp_line
			(start -6.415 2.858)
			(end -6.415 -2.86)
			(stroke
				(width 0.15)
				(type solid)
			)
			(layer "F.Fab")
		)
		(fp_line
			(start 6.413 -2.86)
			(end 6.413 2.858)
			(stroke
				(width 0.15)
				(type solid)
			)
			(layer "F.Fab")
		)
		(fp_line
			(start 6.413 2.858)
			(end -6.415 2.858)
			(stroke
				(width 0.15)
				(type solid)
			)
			(layer "F.Fab")
		)
		(pad "1" smd rect
			(at -2.54 2.055)
			(size 0.74 2.795)
			(layers "F.Cu" "F.Mask" "F.Paste")
			(net 2 "+3V3")
			(pinfunction "1")
			(pintype "passive")
		)
		(pad "2" smd rect
			(at -2.54 -2.009)
			(size 0.74 2.795)
			(layers "F.Cu" "F.Mask" "F.Paste")
			(net 134 "Net-(J7-Pad2)")
			(pinfunction "2")
			(pintype "passive")
		)
		(pad "3" smd rect
			(at -1.27 2.055)
			(size 0.74 2.795)
			(layers "F.Cu" "F.Mask" "F.Paste")
			(net 1 "GND")
			(pinfunction "3")
			(pintype "passive")
		)
		(pad "4" smd rect
			(at -1.27 -2.009)
			(size 0.74 2.795)
			(layers "F.Cu" "F.Mask" "F.Paste")
			(net 135 "Net-(J7-Pad4)")
			(pinfunction "4")
			(pintype "passive")
		)
		(pad "5" smd rect
			(at 0 2.055)
			(size 0.74 2.795)
			(layers "F.Cu" "F.Mask" "F.Paste")
			(net 1 "GND")
			(pinfunction "5")
			(pintype "passive")
		)
		(pad "6" smd rect
			(at 0 -2.009)
			(size 0.74 2.795)
			(layers "F.Cu" "F.Mask" "F.Paste")
			(net 136 "Net-(J7-Pad6)")
			(pinfunction "6")
			(pintype "passive")
		)
		(pad "7" smd rect
			(at 1.269 2.055)
			(size 0.74 2.795)
			(layers "F.Cu" "F.Mask" "F.Paste")
			(net 137 "unconnected-(J7-Pad7)")
			(pinfunction "7")
			(pintype "passive+no_connect")
		)
		(pad "8" smd rect
			(at 1.269 -2.009)
			(size 0.74 2.795)
			(layers "F.Cu" "F.Mask" "F.Paste")
			(net 138 "Net-(J7-Pad8)")
			(pinfunction "8")
			(pintype "passive")
		)
		(pad "9" smd rect
			(at 2.539 2.055)
			(size 0.74 2.795)
			(layers "F.Cu" "F.Mask" "F.Paste")
			(net 1 "GND")
			(pinfunction "9")
			(pintype "passive")
		)
		(pad "10" smd rect
			(at 2.539 -2.009)
			(size 0.74 2.795)
			(layers "F.Cu" "F.Mask" "F.Paste")
			(net 139 "Net-(J7-Pad10)")
			(pinfunction "10")
			(pintype "passive")
		)
	)
	(footprint "antmicro-footprints:R_0402_1005Metric"
		(layer "F.Cu")
		(at 101.2 102.7 -90)
		(descr "Resistor SMD 0402")
		(tags "resistor SMD 0402")
		(property "Reference" "R66"
			(at 1.04 -0.33 90)
			(layer "F.SilkS")
			(effects
				(font
					(size 0.65 0.65)
					(thickness 0.15)
				)
				(justify right bottom)
			)
		)
		(property "Value" "R_0R_0402"
			(at 0 1.4 90)
			(layer "F.Fab")
			(hide yes)
			(effects
				(font
					(size 0.7 0.7)
					(thickness 0.15)
				)
				(justify right bottom)
			)
		)
		(property "Datasheet" "https://industrial.panasonic.com/cdbs/www-data/pdf/RDA0000/AOA0000C301.pdf"
			(at 0 0 270)
			(layer "F.Fab")
			(hide yes)
			(effects
				(font
					(size 1.27 1.27)
					(thickness 0.15)
				)
			)
		)
		(property "Description" "SMD Chip Resistor, Jumper, 0 ohm, 100 mW, 0402 [1005 Metric], Thick Film, General Purpose"
			(at 0 0 270)
			(layer "F.Fab")
			(hide yes)
			(effects
				(font
					(size 1.27 1.27)
					(thickness 0.15)
				)
			)
		)
		(property "Author" "Antmicro"
			(at -1.5 203.9 0)
			(layer "F.Fab")
			(hide yes)
			(effects
				(font
					(size 1 1)
					(thickness 0.15)
				)
			)
		)
		(property "Current" "1A"
			(at -1.5 203.9 0)
			(layer "F.Fab")
			(hide yes)
			(effects
				(font
					(size 1 1)
					(thickness 0.15)
				)
			)
		)
		(property "License" "Apache-2.0"
			(at -1.5 203.9 0)
			(layer "F.Fab")
			(hide yes)
			(effects
				(font
					(size 1 1)
					(thickness 0.15)
				)
			)
		)
		(property "MPN" "ERJ2GE0R00X"
			(at -1.5 203.9 0)
			(layer "F.Fab")
			(hide yes)
			(effects
				(font
					(size 1 1)
					(thickness 0.15)
				)
			)
		)
		(property "Manufacturer" "Panasonic"
			(at -1.5 203.9 0)
			(layer "F.Fab")
			(hide yes)
			(effects
				(font
					(size 1 1)
					(thickness 0.15)
				)
			)
		)
		(property "Tolerance" "~"
			(at -1.5 203.9 0)
			(layer "F.Fab")
			(hide yes)
			(effects
				(font
					(size 1 1)
					(thickness 0.15)
				)
			)
		)
		(property "Val" "0R"
			(at -1.5 203.9 0)
			(layer "F.Fab")
			(hide yes)
			(effects
				(font
					(size 1 1)
					(thickness 0.15)
				)
			)
		)
		(sheetname "/FPGA/")
		(sheetfile "fpga.kicad_sch")
		(attr smd)
		(fp_rect
			(start -0.925 -0.47)
			(end 0.925 0.47)
			(stroke
				(width 0.05)
				(type default)
			)
			(fill no)
			(layer "F.CrtYd")
		)
		(fp_rect
			(start -0.5 -0.25)
			(end 0.5 0.25)
			(stroke
				(width 0.15)
				(type solid)
			)
			(fill no)
			(layer "F.Fab")
		)
		(fp_text user "${REFERENCE}"
			(at -0.95 3.168 270)
			(layer "F.Fab")
			(effects
				(font
					(size 0.7 0.7)
					(thickness 0.15)
				)
				(justify left bottom)
			)
		)
		(fp_text user "License: Apache-2.0"
			(at -0.95 5.169 270)
			(layer "F.Fab")
			(effects
				(font
					(size 0.7 0.7)
					(thickness 0.15)
				)
				(justify left bottom)
			)
		)
		(fp_text user "Author: Antmicro"
			(at -0.95 4.169 270)
			(layer "F.Fab")
			(effects
				(font
					(size 0.7 0.7)
					(thickness 0.15)
				)
				(justify left bottom)
			)
		)
		(pad "1" smd roundrect
			(at -0.48 0 270)
			(size 0.59 0.64)
			(layers "F.Cu" "F.Mask" "F.Paste")
			(roundrect_rratio 0.25)
			(net 299 "Net-(U17-~{RESET})")
			(pintype "passive")
		)
		(pad "2" smd roundrect
			(at 0.48 0 270)
			(size 0.59 0.64)
			(layers "F.Cu" "F.Mask" "F.Paste")
			(roundrect_rratio 0.25)
			(net 2 "+3V3")
			(pintype "passive")
		)
	)
	(footprint "antmicro-footprints:R_0402_1005Metric"
		(layer "F.Cu")
		(at 102.94 115.185 90)
		(descr "Resistor SMD 0402")
		(tags "resistor SMD 0402")
		(property "Reference" "R96"
			(at 0.895 0.39 90)
			(layer "F.SilkS")
			(effects
				(font
					(size 0.65 0.65)
					(thickness 0.15)
				)
				(justify left bottom)
			)
		)
		(property "Value" "R_0R_0402"
			(at 0 1.4 90)
			(layer "F.Fab")
			(hide yes)
			(effects
				(font
					(size 0.7 0.7)
					(thickness 0.15)
				)
				(justify left bottom)
			)
		)
		(property "Datasheet" "https://industrial.panasonic.com/cdbs/www-data/pdf/RDA0000/AOA0000C301.pdf"
			(at 0 0 90)
			(layer "F.Fab")
			(hide yes)
			(effects
				(font
					(size 1.27 1.27)
					(thickness 0.15)
				)
			)
		)
		(property "Description" "SMD Chip Resistor, Jumper, 0 ohm, 100 mW, 0402 [1005 Metric], Thick Film, General Purpose"
			(at 0 0 90)
			(layer "F.Fab")
			(hide yes)
			(effects
				(font
					(size 1.27 1.27)
					(thickness 0.15)
				)
			)
		)
		(property "Author" "Antmicro"
			(at 218.125 12.245 0)
			(layer "F.Fab")
			(hide yes)
			(effects
				(font
					(size 1 1)
					(thickness 0.15)
				)
			)
		)
		(property "Current" "1A"
			(at 218.125 12.245 0)
			(layer "F.Fab")
			(hide yes)
			(effects
				(font
					(size 1 1)
					(thickness 0.15)
				)
			)
		)
		(property "License" "Apache-2.0"
			(at 218.125 12.245 0)
			(layer "F.Fab")
			(hide yes)
			(effects
				(font
					(size 1 1)
					(thickness 0.15)
				)
			)
		)
		(property "MPN" "ERJ2GE0R00X"
			(at 218.125 12.245 0)
			(layer "F.Fab")
			(hide yes)
			(effects
				(font
					(size 1 1)
					(thickness 0.15)
				)
			)
		)
		(property "Manufacturer" "Panasonic"
			(at 218.125 12.245 0)
			(layer "F.Fab")
			(hide yes)
			(effects
				(font
					(size 1 1)
					(thickness 0.15)
				)
			)
		)
		(property "Tolerance" "~"
			(at 218.125 12.245 0)
			(layer "F.Fab")
			(hide yes)
			(effects
				(font
					(size 1 1)
					(thickness 0.15)
				)
			)
		)
		(property "Val" "0R"
			(at 218.125 12.245 0)
			(layer "F.Fab")
			(hide yes)
			(effects
				(font
					(size 1 1)
					(thickness 0.15)
				)
			)
		)
		(sheetname "/FPGA/")
		(sheetfile "fpga.kicad_sch")
		(attr smd)
		(fp_rect
			(start -0.925 -0.47)
			(end 0.925 0.47)
			(stroke
				(width 0.05)
				(type default)
			)
			(fill no)
			(layer "F.CrtYd")
		)
		(fp_rect
			(start -0.5 -0.25)
			(end 0.5 0.25)
			(stroke
				(width 0.15)
				(type solid)
			)
			(fill no)
			(layer "F.Fab")
		)
		(fp_text user "License: Apache-2.0"
			(at -0.95 5.169 90)
			(layer "F.Fab")
			(effects
				(font
					(size 0.7 0.7)
					(thickness 0.15)
				)
				(justify left bottom)
			)
		)
		(fp_text user "${REFERENCE}"
			(at -0.95 3.168 90)
			(layer "F.Fab")
			(effects
				(font
					(size 0.7 0.7)
					(thickness 0.15)
				)
				(justify left bottom)
			)
		)
		(fp_text user "Author: Antmicro"
			(at -0.95 4.169 90)
			(layer "F.Fab")
			(effects
				(font
					(size 0.7 0.7)
					(thickness 0.15)
				)
				(justify left bottom)
			)
		)
		(pad "1" smd roundrect
			(at -0.48 0 90)
			(size 0.59 0.64)
			(layers "F.Cu" "F.Mask" "F.Paste")
			(roundrect_rratio 0.25)
			(net 139 "Net-(J7-Pad10)")
			(pintype "passive")
		)
		(pad "2" smd roundrect
			(at 0.48 0 90)
			(size 0.59 0.64)
			(layers "F.Cu" "F.Mask" "F.Paste")
			(roundrect_rratio 0.25)
			(net 173 "JTAG_EN")
			(pintype "passive")
		)
	)
	(footprint "antmicro-footprints:R_0402_1005Metric"
		(layer "F.Cu")
		(at 144.28 76.19)
		(descr "Resistor SMD 0402")
		(tags "resistor SMD 0402")
		(property "Reference" "R22"
			(at -3.05 0.44 0)
			(layer "F.SilkS")
			(effects
				(font
					(size 0.65 0.65)
					(thickness 0.15)
				)
				(justify left bottom)
			)
		)
		(property "Value" "R_3k01_0402"
			(at 0 1.4 0)
			(layer "F.Fab")
			(hide yes)
			(effects
				(font
					(size 0.7 0.7)
					(thickness 0.15)
				)
				(justify left bottom)
			)
		)
		(property "Datasheet" "https://www.bourns.com/docs/product-datasheets/cr.pdf"
			(at 0 0 0)
			(layer "F.Fab")
			(hide yes)
			(effects
				(font
					(size 1.27 1.27)
					(thickness 0.15)
				)
			)
		)
		(property "Description" "SMD Chip Resistor, 3.01 kohm, ± 1%, 62.5 mW, 0402 [1005 Metric], Thick Film, General Purpose"
			(at 0 0 0)
			(layer "F.Fab")
			(hide yes)
			(effects
				(font
					(size 1.27 1.27)
					(thickness 0.15)
				)
			)
		)
		(property "Author" "Antmicro"
			(at 0 0 0)
			(layer "F.Fab")
			(hide yes)
			(effects
				(font
					(size 1 1)
					(thickness 0.15)
				)
			)
		)
		(property "License" "Apache-2.0"
			(at 0 0 0)
			(layer "F.Fab")
			(hide yes)
			(effects
				(font
					(size 1 1)
					(thickness 0.15)
				)
			)
		)
		(property "MPN" "CR0402-FX-3011GLF"
			(at 0 0 0)
			(layer "F.Fab")
			(hide yes)
			(effects
				(font
					(size 1 1)
					(thickness 0.15)
				)
			)
		)
		(property "Manufacturer" "Bourns"
			(at 0 0 0)
			(layer "F.Fab")
			(hide yes)
			(effects
				(font
					(size 1 1)
					(thickness 0.15)
				)
			)
		)
		(property "Tolerance" "1%"
			(at 0 0 0)
			(layer "F.Fab")
			(hide yes)
			(effects
				(font
					(size 1 1)
					(thickness 0.15)
				)
			)
		)
		(property "Val" "3k01"
			(at 0 0 0)
			(layer "F.Fab")
			(hide yes)
			(effects
				(font
					(size 1 1)
					(thickness 0.15)
				)
			)
		)
		(sheetname "/Power Supply/")
		(sheetfile "supply.kicad_sch")
		(attr smd)
		(fp_rect
			(start -0.925 -0.47)
			(end 0.925 0.47)
			(stroke
				(width 0.05)
				(type default)
			)
			(fill no)
			(layer "F.CrtYd")
		)
		(fp_rect
			(start -0.5 -0.25)
			(end 0.5 0.25)
			(stroke
				(width 0.15)
				(type solid)
			)
			(fill no)
			(layer "F.Fab")
		)
		(fp_text user "${REFERENCE}"
			(at -0.95 3.168 0)
			(layer "F.Fab")
			(effects
				(font
					(size 0.7 0.7)
					(thickness 0.15)
				)
				(justify left bottom)
			)
		)
		(fp_text user "Author: Antmicro"
			(at -0.95 4.169 0)
			(layer "F.Fab")
			(effects
				(font
					(size 0.7 0.7)
					(thickness 0.15)
				)
				(justify left bottom)
			)
		)
		(fp_text user "License: Apache-2.0"
			(at -0.95 5.169 0)
			(layer "F.Fab")
			(effects
				(font
					(size 0.7 0.7)
					(thickness 0.15)
				)
				(justify left bottom)
			)
		)
		(pad "1" smd roundrect
			(at -0.48 0)
			(size 0.59 0.64)
			(layers "F.Cu" "F.Mask" "F.Paste")
			(roundrect_rratio 0.25)
			(net 267 "Net-(U5-FB)")
			(pintype "passive")
		)
		(pad "2" smd roundrect
			(at 0.48 0)
			(size 0.59 0.64)
			(layers "F.Cu" "F.Mask" "F.Paste")
			(roundrect_rratio 0.25)
			(net 273 "/Power Supply/1V0_OUT")
			(pintype "passive")
		)
	)
	(footprint "antmicro-footprints:R_0402_1005Metric"
		(layer "F.Cu")
		(at 167.2 94.6)
		(descr "Resistor SMD 0402")
		(tags "resistor SMD 0402")
		(property "Reference" "R121"
			(at -3.67 0.34 0)
			(layer "F.SilkS")
			(effects
				(font
					(size 0.65 0.65)
					(thickness 0.15)
				)
				(justify left bottom)
			)
		)
		(property "Value" "R_0R_0402"
			(at 0 1.4 0)
			(layer "F.Fab")
			(hide yes)
			(effects
				(font
					(size 0.7 0.7)
					(thickness 0.15)
				)
				(justify left bottom)
			)
		)
		(property "Datasheet" "https://industrial.panasonic.com/cdbs/www-data/pdf/RDA0000/AOA0000C301.pdf"
			(at 0 0 0)
			(layer "F.Fab")
			(hide yes)
			(effects
				(font
					(size 1.27 1.27)
					(thickness 0.15)
				)
			)
		)
		(property "Description" "SMD Chip Resistor, Jumper, 0 ohm, 100 mW, 0402 [1005 Metric], Thick Film, General Purpose"
			(at 0 0 0)
			(layer "F.Fab")
			(hide yes)
			(effects
				(font
					(size 1.27 1.27)
					(thickness 0.15)
				)
			)
		)
		(property "Author" "Antmicro"
			(at 0 0 0)
			(layer "F.Fab")
			(hide yes)
			(effects
				(font
					(size 1 1)
					(thickness 0.15)
				)
			)
		)
		(property "Current" "1A"
			(at 0 0 0)
			(layer "F.Fab")
			(hide yes)
			(effects
				(font
					(size 1 1)
					(thickness 0.15)
				)
			)
		)
		(property "License" "Apache-2.0"
			(at 0 0 0)
			(layer "F.Fab")
			(hide yes)
			(effects
				(font
					(size 1 1)
					(thickness 0.15)
				)
			)
		)
		(property "MPN" "ERJ2GE0R00X"
			(at 0 0 0)
			(layer "F.Fab")
			(hide yes)
			(effects
				(font
					(size 1 1)
					(thickness 0.15)
				)
			)
		)
		(property "Manufacturer" "Panasonic"
			(at 0 0 0)
			(layer "F.Fab")
			(hide yes)
			(effects
				(font
					(size 1 1)
					(thickness 0.15)
				)
			)
		)
		(property "Tolerance" "~"
			(at 0 0 0)
			(layer "F.Fab")
			(hide yes)
			(effects
				(font
					(size 1 1)
					(thickness 0.15)
				)
			)
		)
		(property "Val" "0R"
			(at 0 0 0)
			(layer "F.Fab")
			(hide yes)
			(effects
				(font
					(size 1 1)
					(thickness 0.15)
				)
			)
		)
		(sheetname "/Peripherals/")
		(sheetfile "peripherals.kicad_sch")
		(attr smd)
		(fp_rect
			(start -0.925 -0.47)
			(end 0.925 0.47)
			(stroke
				(width 0.05)
				(type default)
			)
			(fill no)
			(layer "F.CrtYd")
		)
		(fp_rect
			(start -0.5 -0.25)
			(end 0.5 0.25)
			(stroke
				(width 0.15)
				(type solid)
			)
			(fill no)
			(layer "F.Fab")
		)
		(fp_text user "Author: Antmicro"
			(at -0.95 4.169 0)
			(layer "F.Fab")
			(effects
				(font
					(size 0.7 0.7)
					(thickness 0.15)
				)
				(justify left bottom)
			)
		)
		(fp_text user "${REFERENCE}"
			(at -0.95 3.168 0)
			(layer "F.Fab")
			(effects
				(font
					(size 0.7 0.7)
					(thickness 0.15)
				)
				(justify left bottom)
			)
		)
		(fp_text user "License: Apache-2.0"
			(at -0.95 5.169 0)
			(layer "F.Fab")
			(effects
				(font
					(size 0.7 0.7)
					(thickness 0.15)
				)
				(justify left bottom)
			)
		)
		(pad "1" smd roundrect
			(at -0.48 0)
			(size 0.59 0.64)
			(layers "F.Cu" "F.Mask" "F.Paste")
			(roundrect_rratio 0.25)
			(net 90 "/Peripherals/FFC1_VSYNC1")
			(pintype "passive")
		)
		(pad "2" smd roundrect
			(at 0.48 0)
			(size 0.59 0.64)
			(layers "F.Cu" "F.Mask" "F.Paste")
			(roundrect_rratio 0.25)
			(net 337 "Net-(J4-Pad34)")
			(pintype "passive")
		)
	)
	(footprint "antmicro-footprints:LED_0603_1608Metric_G"
		(layer "F.Cu")
		(at 141.46 84 180)
		(descr "LED SMD 0603 Green")
		(tags "LED SMD 0603 Green")
		(property "Reference" "D13"
			(at -3.27 0.36 0)
			(layer "F.SilkS")
			(effects
				(font
					(size 0.65 0.65)
					(thickness 0.15)
				)
				(justify right top)
			)
		)
		(property "Value" "LED_G_0603_LTST-C190GKT"
			(at 0 1.6 0)
			(layer "F.Fab")
			(hide yes)
			(effects
				(font
					(size 0.7 0.7)
					(thickness 0.15)
				)
				(justify right top)
			)
		)
		(property "Datasheet" "https://media.digikey.com/pdf/Data%20Sheets/Lite-On%20PDFs/LTST-C190GKT.pdf"
			(at 0 0 0)
			(layer "F.Fab")
			(hide yes)
			(effects
				(font
					(size 1.27 1.27)
					(thickness 0.15)
				)
			)
		)
		(property "Description" "LED, Green, SMD, 0603, 20 mA, 2.1 V, 569 nm"
			(at 0 0 0)
			(layer "F.Fab")
			(hide yes)
			(effects
				(font
					(size 1.27 1.27)
					(thickness 0.15)
				)
			)
		)
		(property "Author" "Antmicro"
			(at 0 0 0)
			(layer "F.Fab")
			(hide yes)
			(effects
				(font
					(size 1 1)
					(thickness 0.15)
				)
			)
		)
		(property "License" "Apache-2.0"
			(at 0 0 0)
			(layer "F.Fab")
			(hide yes)
			(effects
				(font
					(size 1 1)
					(thickness 0.15)
				)
			)
		)
		(property "MPN" "LTST-C190GKT"
			(at 0 0 0)
			(layer "F.Fab")
			(hide yes)
			(effects
				(font
					(size 1 1)
					(thickness 0.15)
				)
			)
		)
		(property "Manufacturer" "Lite-On"
			(at 0 0 0)
			(layer "F.Fab")
			(hide yes)
			(effects
				(font
					(size 1 1)
					(thickness 0.15)
				)
			)
		)
		(property "Color" "Green"
			(at 0 0 180)
			(unlocked yes)
			(layer "F.Fab")
			(hide yes)
			(effects
				(font
					(size 1 1)
					(thickness 0.15)
				)
			)
		)
		(sheetname "/Peripherals/")
		(sheetfile "peripherals.kicad_sch")
		(attr smd)
		(fp_line
			(start 0.22 0.35)
			(end -0.22 0.35)
			(stroke
				(width 0.15)
				(type solid)
			)
			(layer "F.SilkS")
		)
		(fp_line
			(start 0.22 -0.35)
			(end -0.22 -0.35)
			(stroke
				(width 0.15)
				(type solid)
			)
			(layer "F.SilkS")
		)
		(fp_line
			(start 0.105328 0.201008)
			(end 0.105328 -0.198992)
			(stroke
				(width 0.1)
				(type solid)
			)
			(layer "F.SilkS")
		)
		(fp_line
			(start 0.105328 0.201008)
			(end -0.094672 0.001008)
			(stroke
				(width 0.1)
				(type solid)
			)
			(layer "F.SilkS")
		)
		(fp_line
			(start 0.105328 0.001008)
			(end 0.24 0.001)
			(stroke
				(width 0.1)
				(type solid)
			)
			(layer "F.SilkS")
		)
		(fp_line
			(start -0.094672 0.201008)
			(end -0.094672 -0.198992)
			(stroke
				(width 0.1)
				(type solid)
			)
			(layer "F.SilkS")
		)
		(fp_line
			(start -0.094672 0.001008)
			(end 0.105328 -0.198992)
			(stroke
				(width 0.1)
				(type solid)
			)
			(layer "F.SilkS")
		)
		(fp_line
			(start -0.094672 0.001008)
			(end -0.24 0.001008)
			(stroke
				(width 0.1)
				(type solid)
			)
			(layer "F.SilkS")
		)
		(fp_line
			(start -1.18 -0.319)
			(end -1.18 0.321)
			(stroke
				(width 0.15)
				(type solid)
			)
			(layer "F.SilkS")
		)
		(fp_rect
			(start 1.25 0.65)
			(end -1.25 -0.65)
			(stroke
				(width 0.05)
				(type solid)
			)
			(fill no)
			(layer "F.CrtYd")
		)
		(fp_line
			(start 0.599 0)
			(end 0.201 0)
			(stroke
				(width 0.15)
				(type solid)
			)
			(layer "F.Fab")
		)
		(fp_line
			(start 0.201 0.2)
			(end 0.201 0)
			(stroke
				(width 0.15)
				(type solid)
			)
			(layer "F.Fab")
		)
		(fp_line
			(start 0.201 0)
			(end 0.201 -0.202)
			(stroke
				(width 0.15)
				(type solid)
			)
			(layer "F.Fab")
		)
		(fp_line
			(start 0.201 -0.202)
			(end -0.101 0)
			(stroke
				(width 0.15)
				(type solid)
			)
			(layer "F.Fab")
		)
		(fp_line
			(start -0.101 0)
			(end 0.201 0.2)
			(stroke
				(width 0.15)
				(type solid)
			)
			(layer "F.Fab")
		)
		(fp_line
			(start -0.199 0.2)
			(end -0.199 0.1)
			(stroke
				(width 0.15)
				(type solid)
			)
			(layer "F.Fab")
		)
		(fp_line
			(start -0.199 0)
			(end -0.597 0)
			(stroke
				(width 0.15)
				(type solid)
			)
			(layer "F.Fab")
		)
		(fp_line
			(start -0.199 -0.202)
			(end -0.199 0.1)
			(stroke
				(width 0.15)
				(type solid)
			)
			(layer "F.Fab")
		)
		(fp_rect
			(start 0.848 0.4)
			(end -0.85 -0.402)
			(stroke
				(width 0.15)
				(type solid)
			)
			(fill no)
			(layer "F.Fab")
		)
		(fp_text user "License: Apache-2.0"
			(at -1.4224 3.599 0)
			(layer "F.Fab")
			(effects
				(font
					(size 0.7 0.7)
					(thickness 0.15)
				)
				(justify right top)
			)
		)
		(fp_text user "Author: Antmicro"
			(at -1.4224 4.799 0)
			(layer "F.Fab")
			(effects
				(font
					(size 0.7 0.7)
					(thickness 0.15)
				)
				(justify right top)
			)
		)
		(fp_text user "${REFERENCE}"
			(at -1.4224 5.999 0)
			(layer "F.Fab")
			(effects
				(font
					(size 0.7 0.7)
					(thickness 0.15)
				)
				(justify right top)
			)
		)
		(pad "1" smd roundrect
			(at -0.7 0)
			(size 0.8 1)
			(layers "F.Cu" "F.Mask" "F.Paste")
			(roundrect_rratio 0.2)
			(net 296 "Net-(D13-C)")
			(pinfunction "C")
			(pintype "passive")
		)
		(pad "2" smd roundrect
			(at 0.7 0)
			(size 0.8 1)
			(layers "F.Cu" "F.Mask" "F.Paste")
			(roundrect_rratio 0.2)
			(net 295 "Net-(D13-A)")
			(pinfunction "A")
			(pintype "passive")
		)
	)
	(footprint "antmicro-footprints:C_0603_1608Metric"
		(layer "F.Cu")
		(at 160.63 60.19)
		(descr "Capacitor SMD 0603")
		(tags "capacitor 0603")
		(property "Reference" "C28"
			(at -0.55 -0.97 270)
			(layer "F.SilkS")
			(effects
				(font
					(size 0.65 0.65)
					(thickness 0.15)
				)
				(justify left bottom)
			)
		)
		(property "Value" "C_22u_0603"
			(at 0 1.6 0)
			(layer "F.Fab")
			(hide yes)
			(effects
				(font
					(size 0.7 0.7)
					(thickness 0.15)
				)
				(justify left bottom)
			)
		)
		(property "Datasheet" "https://www.murata.com/products/productdetail?partno=GRM188R60J226MEA0%23"
			(at 0 0 0)
			(layer "F.Fab")
			(hide yes)
			(effects
				(font
					(size 1.27 1.27)
					(thickness 0.15)
				)
			)
		)
		(property "Description" "SMD Multilayer Ceramic Capacitor, 22 µF, 6.3 V, 0603 [1608 Metric], ± 20%, X5R, GRM Series"
			(at 0 0 0)
			(layer "F.Fab")
			(hide yes)
			(effects
				(font
					(size 1.27 1.27)
					(thickness 0.15)
				)
			)
		)
		(property "Author" "Antmicro"
			(at 0 0 0)
			(layer "F.Fab")
			(hide yes)
			(effects
				(font
					(size 1 1)
					(thickness 0.15)
				)
			)
		)
		(property "Dielectric" ""
			(at 0 0 0)
			(layer "F.Fab")
			(hide yes)
			(effects
				(font
					(size 1 1)
					(thickness 0.15)
				)
			)
		)
		(property "License" "Apache-2.0"
			(at 0 0 0)
			(layer "F.Fab")
			(hide yes)
			(effects
				(font
					(size 1 1)
					(thickness 0.15)
				)
			)
		)
		(property "MPN" "GRM188R60J226MEA0D"
			(at 0 0 0)
			(layer "F.Fab")
			(hide yes)
			(effects
				(font
					(size 1 1)
					(thickness 0.15)
				)
			)
		)
		(property "Manufacturer" "Murata"
			(at 0 0 0)
			(layer "F.Fab")
			(hide yes)
			(effects
				(font
					(size 1 1)
					(thickness 0.15)
				)
			)
		)
		(property "Val" "22u"
			(at 0 0 0)
			(layer "F.Fab")
			(hide yes)
			(effects
				(font
					(size 1 1)
					(thickness 0.15)
				)
			)
		)
		(property "Voltage" ""
			(at 0 0 0)
			(layer "F.Fab")
			(hide yes)
			(effects
				(font
					(size 1 1)
					(thickness 0.15)
				)
			)
		)
		(sheetname "/Power Supply/")
		(sheetfile "supply.kicad_sch")
		(attr smd)
		(fp_line
			(start -0.15 -0.4)
			(end 0.15 -0.4)
			(stroke
				(width 0.15)
				(type solid)
			)
			(layer "F.SilkS")
		)
		(fp_line
			(start -0.15 0.4)
			(end 0.15 0.4)
			(stroke
				(width 0.15)
				(type solid)
			)
			(layer "F.SilkS")
		)
		(fp_rect
			(start -1.25 -0.65)
			(end 1.25 0.65)
			(stroke
				(width 0.05)
				(type solid)
			)
			(fill no)
			(layer "F.CrtYd")
		)
		(fp_rect
			(start -0.8 -0.4)
			(end 0.8 0.4)
			(stroke
				(width 0.15)
				(type solid)
			)
			(fill no)
			(layer "F.Fab")
		)
		(fp_text user "Author: Antmicro"
			(at -1.682 4.894 0)
			(layer "F.Fab")
			(effects
				(font
					(size 0.7 0.7)
					(thickness 0.15)
				)
				(justify left bottom)
			)
		)
		(fp_text user "${REFERENCE}"
			(at -1.682 3.895 0)
			(layer "F.Fab")
			(effects
				(font
					(size 0.7 0.7)
					(thickness 0.15)
				)
				(justify left bottom)
			)
		)
		(fp_text user "License: Apache-2.0"
			(at -1.682 5.895 0)
			(layer "F.Fab")
			(effects
				(font
					(size 0.7 0.7)
					(thickness 0.15)
				)
				(justify left bottom)
			)
		)
		(pad "1" smd roundrect
			(at -0.7 0)
			(size 0.8 1)
			(layers "F.Cu" "F.Mask" "F.Paste")
			(roundrect_rratio 0.2)
			(net 1 "GND")
			(pintype "passive")
		)
		(pad "2" smd roundrect
			(at 0.7 0)
			(size 0.8 1)
			(layers "F.Cu" "F.Mask" "F.Paste")
			(roundrect_rratio 0.2)
			(net 275 "/Power Supply/3V3_OUT")
			(pintype "passive")
		)
	)
	(footprint "antmicro-footprints:R_0603_1608Metric"
		(layer "F.Cu")
		(at 158.29 78.2)
		(descr "Resistor SMD 0603")
		(tags "resistor SMD 0603")
		(property "Reference" "R116"
			(at -4.06 0.54 0)
			(layer "F.SilkS")
			(effects
				(font
					(size 0.65 0.65)
					(thickness 0.15)
				)
				(justify left bottom)
			)
		)
		(property "Value" "R_0R_0603"
			(at 0 1.6 0)
			(layer "F.Fab")
			(hide yes)
			(effects
				(font
					(size 0.7 0.7)
					(thickness 0.15)
				)
				(justify left bottom)
			)
		)
		(property "Datasheet" "https://www.bourns.com/docs/product-datasheets/cr.pdf?sfvrsn=574d41f6_14"
			(at 0 0 0)
			(layer "F.Fab")
			(hide yes)
			(effects
				(font
					(size 1.27 1.27)
					(thickness 0.15)
				)
			)
		)
		(property "Description" "Zero Ohm Resistor, Jumper, 0603 [1608 Metric], Thick Film, 100 mW, 1 A, Surface Mount Device, CR"
			(at 0 0 0)
			(layer "F.Fab")
			(hide yes)
			(effects
				(font
					(size 1.27 1.27)
					(thickness 0.15)
				)
			)
		)
		(property "Author" "Antmicro"
			(at 0 0 0)
			(layer "F.Fab")
			(hide yes)
			(effects
				(font
					(size 1 1)
					(thickness 0.15)
				)
			)
		)
		(property "Current" "1A"
			(at 0 0 0)
			(layer "F.Fab")
			(hide yes)
			(effects
				(font
					(size 1 1)
					(thickness 0.15)
				)
			)
		)
		(property "License" "Apache-2.0"
			(at 0 0 0)
			(layer "F.Fab")
			(hide yes)
			(effects
				(font
					(size 1 1)
					(thickness 0.15)
				)
			)
		)
		(property "MPN" "CR0603-J/-000ELF"
			(at 0 0 0)
			(layer "F.Fab")
			(hide yes)
			(effects
				(font
					(size 1 1)
					(thickness 0.15)
				)
			)
		)
		(property "Manufacturer" "Bourns"
			(at 0 0 0)
			(layer "F.Fab")
			(hide yes)
			(effects
				(font
					(size 1 1)
					(thickness 0.15)
				)
			)
		)
		(property "Tolerance" "~"
			(at 0 0 0)
			(layer "F.Fab")
			(hide yes)
			(effects
				(font
					(size 1 1)
					(thickness 0.15)
				)
			)
		)
		(property "Val" "0R"
			(at 0 0 0)
			(layer "F.Fab")
			(hide yes)
			(effects
				(font
					(size 1 1)
					(thickness 0.15)
				)
			)
		)
		(sheetname "/Peripherals/")
		(sheetfile "peripherals.kicad_sch")
		(attr smd)
		(fp_line
			(start -0.15 -0.4)
			(end 0.15 -0.4)
			(stroke
				(width 0.15)
				(type solid)
			)
			(layer "F.SilkS")
		)
		(fp_line
			(start -0.15 0.4)
			(end 0.15 0.4)
			(stroke
				(width 0.15)
				(type solid)
			)
			(layer "F.SilkS")
		)
		(fp_rect
			(start -1.25 -0.65)
			(end 1.25 0.65)
			(stroke
				(width 0.05)
				(type solid)
			)
			(fill no)
			(layer "F.CrtYd")
		)
		(fp_rect
			(start -0.8 -0.4)
			(end 0.8 0.4)
			(stroke
				(width 0.15)
				(type solid)
			)
			(fill no)
			(layer "F.Fab")
		)
		(fp_text user "License: Apache-2.0"
			(at -1.25 5.9 0)
			(layer "F.Fab")
			(effects
				(font
					(size 0.7 0.7)
					(thickness 0.15)
				)
				(justify left bottom)
			)
		)
		(fp_text user "Author: Antmicro"
			(at -1.25 4.9 0)
			(layer "F.Fab")
			(effects
				(font
					(size 0.7 0.7)
					(thickness 0.15)
				)
				(justify left bottom)
			)
		)
		(fp_text user "${REFERENCE}"
			(at -1.25 3.898 0)
			(layer "F.Fab")
			(effects
				(font
					(size 0.7 0.7)
					(thickness 0.15)
				)
				(justify left bottom)
			)
		)
		(pad "1" smd roundrect
			(at -0.7 0)
			(size 0.8 1)
			(layers "F.Cu" "F.Mask" "F.Paste")
			(roundrect_rratio 0.2)
			(net 101 "SDA")
			(pintype "passive")
		)
		(pad "2" smd roundrect
			(at 0.7 0)
			(size 0.8 1)
			(layers "F.Cu" "F.Mask" "F.Paste")
			(roundrect_rratio 0.2)
			(net 312 "Net-(J8-Pad3)")
			(pintype "passive")
		)
	)
	(footprint "antmicro-footprints:R_1206_3216Metric"
		(layer "F.Cu")
		(at 156.29 110.5)
		(property "Reference" "R4"
			(at -0.86 -1.36 0)
			(layer "F.SilkS")
			(effects
				(font
					(size 0.65 0.65)
					(thickness 0.15)
				)
				(justify left bottom)
			)
		)
		(property "Value" "R_0R_1206"
			(at 0 2 0)
			(layer "F.Fab")
			(hide yes)
			(effects
				(font
					(size 0.7 0.7)
					(thickness 0.15)
				)
				(justify left bottom)
			)
		)
		(property "Datasheet" "https://www.farnell.com/datasheets/2860635.pdf"
			(at 0 0 0)
			(layer "F.Fab")
			(hide yes)
			(effects
				(font
					(size 1.27 1.27)
					(thickness 0.15)
				)
			)
		)
		(property "Description" "Zero Ohm Resistor, Jumper, 1206 [3216 Metric], Thick Film, 250 mW, 2 A, Surface Mount Device"
			(at 0 0 0)
			(layer "F.Fab")
			(hide yes)
			(effects
				(font
					(size 1.27 1.27)
					(thickness 0.15)
				)
			)
		)
		(property "Author" "Antmicro"
			(at 0 0 0)
			(layer "F.Fab")
			(hide yes)
			(effects
				(font
					(size 1 1)
					(thickness 0.15)
				)
			)
		)
		(property "Current" "2A"
			(at 0 0 0)
			(layer "F.Fab")
			(hide yes)
			(effects
				(font
					(size 1 1)
					(thickness 0.15)
				)
			)
		)
		(property "License" "Apache-2.0"
			(at 0 0 0)
			(layer "F.Fab")
			(hide yes)
			(effects
				(font
					(size 1 1)
					(thickness 0.15)
				)
			)
		)
		(property "MPN" "MCMR12X000_PTL"
			(at 0 0 0)
			(layer "F.Fab")
			(hide yes)
			(effects
				(font
					(size 1 1)
					(thickness 0.15)
				)
			)
		)
		(property "Manufacturer" "Multicomp Pro"
			(at 0 0 0)
			(layer "F.Fab")
			(hide yes)
			(effects
				(font
					(size 1 1)
					(thickness 0.15)
				)
			)
		)
		(property "Tolerance" "~"
			(at 0 0 0)
			(layer "F.Fab")
			(hide yes)
			(effects
				(font
					(size 1 1)
					(thickness 0.15)
				)
			)
		)
		(property "Val" "0R"
			(at 0 0 0)
			(layer "F.Fab")
			(hide yes)
			(effects
				(font
					(size 1 1)
					(thickness 0.15)
				)
			)
		)
		(sheetname "/Power Supply/")
		(sheetfile "supply.kicad_sch")
		(attr smd)
		(fp_line
			(start 0.8 -0.899)
			(end -0.8 -0.899)
			(stroke
				(width 0.15)
				(type solid)
			)
			(layer "F.SilkS")
		)
		(fp_line
			(start 0.8 0.901)
			(end -0.8 0.901)
			(stroke
				(width 0.15)
				(type solid)
			)
			(layer "F.SilkS")
		)
		(fp_rect
			(start -2.325 -1.15)
			(end 2.325 1.15)
			(stroke
				(width 0.05)
				(type default)
			)
			(fill no)
			(layer "F.CrtYd")
		)
		(fp_line
			(start -1.601 -0.802)
			(end -1.601 0.8)
			(stroke
				(width 0.15)
				(type solid)
			)
			(layer "F.Fab")
		)
		(fp_line
			(start -1.601 -0.802)
			(end 1.6 -0.802)
			(stroke
				(width 0.15)
				(type solid)
			)
			(layer "F.Fab")
		)
		(fp_line
			(start -1.601 0.8)
			(end 1.6 0.8)
			(stroke
				(width 0.15)
				(type solid)
			)
			(layer "F.Fab")
		)
		(fp_line
			(start 1.6 -0.802)
			(end 1.6 0.8)
			(stroke
				(width 0.15)
				(type solid)
			)
			(layer "F.Fab")
		)
		(fp_text user "${REFERENCE}"
			(at -2.401 3.5 0)
			(layer "F.Fab")
			(effects
				(font
					(size 0.7 0.7)
					(thickness 0.15)
				)
				(justify left bottom)
			)
		)
		(fp_text user "License: Apache-2.0"
			(at -2.401 6.3 0)
			(layer "F.Fab")
			(effects
				(font
					(size 0.7 0.7)
					(thickness 0.15)
				)
				(justify left bottom)
			)
		)
		(fp_text user "Author: Antmicro"
			(at -2.401 4.899 0)
			(layer "F.Fab")
			(effects
				(font
					(size 0.7 0.7)
					(thickness 0.15)
				)
				(justify left bottom)
			)
		)
		(pad "1" smd roundrect
			(at -1.5 0.001)
			(size 1.15 1.8)
			(layers "F.Cu" "F.Mask" "F.Paste")
			(roundrect_rratio 0.25)
			(net 19 "FFC2_5V")
			(pintype "passive")
		)
		(pad "2" smd roundrect
			(at 1.5 0.001)
			(size 1.15 1.8)
			(layers "F.Cu" "F.Mask" "F.Paste")
			(roundrect_rratio 0.25)
			(net 329 "/Power Supply/FFC2_5V_1")
			(pintype "passive")
		)
	)
	(footprint "antmicro-footprints:R_0603_1608Metric"
		(layer "F.Cu")
		(at 138.79 107.6 90)
		(descr "Resistor SMD 0603")
		(tags "resistor SMD 0603")
		(property "Reference" "R29"
			(at -0.54 -1.96 90)
			(layer "F.SilkS")
			(effects
				(font
					(size 0.65 0.65)
					(thickness 0.15)
				)
				(justify left bottom)
			)
		)
		(property "Value" "R_0R_0603"
			(at 0 1.6 90)
			(layer "F.Fab")
			(hide yes)
			(effects
				(font
					(size 0.7 0.7)
					(thickness 0.15)
				)
				(justify left bottom)
			)
		)
		(property "Datasheet" "https://www.bourns.com/docs/product-datasheets/cr.pdf?sfvrsn=574d41f6_14"
			(at 0 0 90)
			(layer "F.Fab")
			(hide yes)
			(effects
				(font
					(size 1.27 1.27)
					(thickness 0.15)
				)
			)
		)
		(property "Description" "Zero Ohm Resistor, Jumper, 0603 [1608 Metric], Thick Film, 100 mW, 1 A, Surface Mount Device, CR"
			(at 0 0 90)
			(layer "F.Fab")
			(hide yes)
			(effects
				(font
					(size 1.27 1.27)
					(thickness 0.15)
				)
			)
		)
		(property "Author" "Antmicro"
			(at 246.39 -31.19 0)
			(layer "F.Fab")
			(hide yes)
			(effects
				(font
					(size 1 1)
					(thickness 0.15)
				)
			)
		)
		(property "Current" "1A"
			(at 246.39 -31.19 0)
			(layer "F.Fab")
			(hide yes)
			(effects
				(font
					(size 1 1)
					(thickness 0.15)
				)
			)
		)
		(property "License" "Apache-2.0"
			(at 246.39 -31.19 0)
			(layer "F.Fab")
			(hide yes)
			(effects
				(font
					(size 1 1)
					(thickness 0.15)
				)
			)
		)
		(property "MPN" "CR0603-J/-000ELF"
			(at 246.39 -31.19 0)
			(layer "F.Fab")
			(hide yes)
			(effects
				(font
					(size 1 1)
					(thickness 0.15)
				)
			)
		)
		(property "Manufacturer" "Bourns"
			(at 246.39 -31.19 0)
			(layer "F.Fab")
			(hide yes)
			(effects
				(font
					(size 1 1)
					(thickness 0.15)
				)
			)
		)
		(property "Tolerance" "~"
			(at 246.39 -31.19 0)
			(layer "F.Fab")
			(hide yes)
			(effects
				(font
					(size 1 1)
					(thickness 0.15)
				)
			)
		)
		(property "Val" "0R"
			(at 246.39 -31.19 0)
			(layer "F.Fab")
			(hide yes)
			(effects
				(font
					(size 1 1)
					(thickness 0.15)
				)
			)
		)
		(sheetname "/Power Supply/")
		(sheetfile "supply.kicad_sch")
		(attr smd)
		(fp_line
			(start -0.15 -0.4)
			(end 0.15 -0.4)
			(stroke
				(width 0.15)
				(type solid)
			)
			(layer "F.SilkS")
		)
		(fp_line
			(start -0.15 0.4)
			(end 0.15 0.4)
			(stroke
				(width 0.15)
				(type solid)
			)
			(layer "F.SilkS")
		)
		(fp_rect
			(start -1.25 -0.65)
			(end 1.25 0.65)
			(stroke
				(width 0.05)
				(type solid)
			)
			(fill no)
			(layer "F.CrtYd")
		)
		(fp_rect
			(start -0.8 -0.4)
			(end 0.8 0.4)
			(stroke
				(width 0.15)
				(type solid)
			)
			(fill no)
			(layer "F.Fab")
		)
		(fp_text user "Author: Antmicro"
			(at -1.25 4.9 90)
			(layer "F.Fab")
			(effects
				(font
					(size 0.7 0.7)
					(thickness 0.15)
				)
				(justify left bottom)
			)
		)
		(fp_text user "${REFERENCE}"
			(at -1.25 3.898 90)
			(layer "F.Fab")
			(effects
				(font
					(size 0.7 0.7)
					(thickness 0.15)
				)
				(justify left bottom)
			)
		)
		(fp_text user "License: Apache-2.0"
			(at -1.25 5.9 90)
			(layer "F.Fab")
			(effects
				(font
					(size 0.7 0.7)
					(thickness 0.15)
				)
				(justify left bottom)
			)
		)
		(pad "1" smd roundrect
			(at -0.7 0 90)
			(size 0.8 1)
			(layers "F.Cu" "F.Mask" "F.Paste")
			(roundrect_rratio 0.2)
			(net 272 "Net-(U8-V_{OUT})")
			(pintype "passive")
		)
		(pad "2" smd roundrect
			(at 0.7 0 90)
			(size 0.8 1)
			(layers "F.Cu" "F.Mask" "F.Paste")
			(roundrect_rratio 0.2)
			(net 49 "1V0_Clean")
			(pintype "passive")
		)
	)
	(footprint "antmicro-footprints:F_0603_1608Metric"
		(layer "F.Cu")
		(at 154.25 116.25 180)
		(property "Reference" "F1"
			(at 0.42 0.91 180)
			(layer "F.SilkS")
			(effects
				(font
					(size 0.65 0.65)
					(thickness 0.15)
				)
				(justify left bottom)
			)
		)
		(property "Value" "F_1.25A_0603"
			(at 0 1.7 180)
			(layer "F.Fab")
			(hide yes)
			(effects
				(font
					(size 0.7 0.7)
					(thickness 0.15)
				)
				(justify left bottom)
			)
		)
		(property "Datasheet" "https://www.littelfuse.com/~/media/electronics/datasheets/fuses/littelfuse_fuse_467_datasheet.pdf.pdf"
			(at 0 0 180)
			(layer "F.Fab")
			(hide yes)
			(effects
				(font
					(size 1.27 1.27)
					(thickness 0.15)
				)
			)
		)
		(property "Description" "Fuse, Surface Mount, 1.25 A, Very Fast Acting, 32 V, 32 V, 0603 (1608 Metric), 467"
			(at 0 0 180)
			(layer "F.Fab")
			(hide yes)
			(effects
				(font
					(size 1.27 1.27)
					(thickness 0.15)
				)
			)
		)
		(property "Author" "Antmicro"
			(at 308.5 232.5 0)
			(layer "F.Fab")
			(hide yes)
			(effects
				(font
					(size 1 1)
					(thickness 0.15)
				)
			)
		)
		(property "License" "Apache-2.0"
			(at 308.5 232.5 0)
			(layer "F.Fab")
			(hide yes)
			(effects
				(font
					(size 1 1)
					(thickness 0.15)
				)
			)
		)
		(property "MPN" "04671.25NR"
			(at 308.5 232.5 0)
			(layer "F.Fab")
			(hide yes)
			(effects
				(font
					(size 1 1)
					(thickness 0.15)
				)
			)
		)
		(property "Manufacturer" "Littelfuse"
			(at 308.5 232.5 0)
			(layer "F.Fab")
			(hide yes)
			(effects
				(font
					(size 1 1)
					(thickness 0.15)
				)
			)
		)
		(sheetname "/Peripherals/")
		(sheetfile "peripherals.kicad_sch")
		(attr smd)
		(fp_line
			(start -0.15 0.4)
			(end 0.15 0.4)
			(stroke
				(width 0.15)
				(type solid)
			)
			(layer "F.SilkS")
		)
		(fp_line
			(start -0.15 -0.4)
			(end 0.15 -0.4)
			(stroke
				(width 0.15)
				(type solid)
			)
			(layer "F.SilkS")
		)
		(fp_rect
			(start -1.25 -0.65)
			(end 1.25 0.65)
			(stroke
				(width 0.05)
				(type solid)
			)
			(fill no)
			(layer "F.CrtYd")
		)
		(fp_line
			(start 0.8 0.406)
			(end -0.803 0.406)
			(stroke
				(width 0.15)
				(type solid)
			)
			(layer "F.Fab")
		)
		(fp_line
			(start 0.8 -0.408)
			(end 0.8 0.406)
			(stroke
				(width 0.15)
				(type solid)
			)
			(layer "F.Fab")
		)
		(fp_line
			(start 0.8 -0.408)
			(end -0.803 -0.408)
			(stroke
				(width 0.15)
				(type solid)
			)
			(layer "F.Fab")
		)
		(fp_line
			(start -0.803 0.406)
			(end -0.803 -0.408)
			(stroke
				(width 0.15)
				(type solid)
			)
			(layer "F.Fab")
		)
		(fp_text user "Author: Antmicro"
			(at -1.653 3.162 180)
			(layer "F.Fab")
			(effects
				(font
					(size 0.7 0.7)
					(thickness 0.15)
				)
				(justify left bottom)
			)
		)
		(fp_text user "License: Apache-2.0"
			(at -1.653 5.9 180)
			(layer "F.Fab")
			(effects
				(font
					(size 0.7 0.7)
					(thickness 0.15)
				)
				(justify left bottom)
			)
		)
		(fp_text user "${REFERENCE}"
			(at -1.653 4.6 180)
			(layer "F.Fab")
			(effects
				(font
					(size 0.7 0.7)
					(thickness 0.15)
				)
				(justify left bottom)
			)
		)
		(pad "1" smd roundrect
			(at -0.7 0 180)
			(size 0.8 1)
			(layers "F.Cu" "F.Mask" "F.Paste")
			(roundrect_rratio 0.2)
			(net 2 "+3V3")
			(pintype "passive")
		)
		(pad "2" smd roundrect
			(at 0.7 0 180)
			(size 0.8 1)
			(layers "F.Cu" "F.Mask" "F.Paste")
			(roundrect_rratio 0.2)
			(net 331 "/Peripherals/3V3_MISC")
			(pintype "passive")
		)
	)
	(footprint "antmicro-footprints:R_0402_1005Metric"
		(layer "F.Cu")
		(at 167.2 96.6)
		(descr "Resistor SMD 0402")
		(tags "resistor SMD 0402")
		(property "Reference" "R73"
			(at -3.67 0.34 0)
			(layer "F.SilkS")
			(effects
				(font
					(size 0.65 0.65)
					(thickness 0.15)
				)
				(justify left bottom)
			)
		)
		(property "Value" "R_0R_0402"
			(at 0 1.4 0)
			(layer "F.Fab")
			(hide yes)
			(effects
				(font
					(size 0.7 0.7)
					(thickness 0.15)
				)
				(justify left bottom)
			)
		)
		(property "Datasheet" "https://industrial.panasonic.com/cdbs/www-data/pdf/RDA0000/AOA0000C301.pdf"
			(at 0 0 0)
			(layer "F.Fab")
			(hide yes)
			(effects
				(font
					(size 1.27 1.27)
					(thickness 0.15)
				)
			)
		)
		(property "Description" "SMD Chip Resistor, Jumper, 0 ohm, 100 mW, 0402 [1005 Metric], Thick Film, General Purpose"
			(at 0 0 0)
			(layer "F.Fab")
			(hide yes)
			(effects
				(font
					(size 1.27 1.27)
					(thickness 0.15)
				)
			)
		)
		(property "Author" "Antmicro"
			(at 0 0 0)
			(layer "F.Fab")
			(hide yes)
			(effects
				(font
					(size 1 1)
					(thickness 0.15)
				)
			)
		)
		(property "Current" "1A"
			(at 0 0 0)
			(layer "F.Fab")
			(hide yes)
			(effects
				(font
					(size 1 1)
					(thickness 0.15)
				)
			)
		)
		(property "License" "Apache-2.0"
			(at 0 0 0)
			(layer "F.Fab")
			(hide yes)
			(effects
				(font
					(size 1 1)
					(thickness 0.15)
				)
			)
		)
		(property "MPN" "ERJ2GE0R00X"
			(at 0 0 0)
			(layer "F.Fab")
			(hide yes)
			(effects
				(font
					(size 1 1)
					(thickness 0.15)
				)
			)
		)
		(property "Manufacturer" "Panasonic"
			(at 0 0 0)
			(layer "F.Fab")
			(hide yes)
			(effects
				(font
					(size 1 1)
					(thickness 0.15)
				)
			)
		)
		(property "Tolerance" "~"
			(at 0 0 0)
			(layer "F.Fab")
			(hide yes)
			(effects
				(font
					(size 1 1)
					(thickness 0.15)
				)
			)
		)
		(property "Val" "0R"
			(at 0 0 0)
			(layer "F.Fab")
			(hide yes)
			(effects
				(font
					(size 1 1)
					(thickness 0.15)
				)
			)
		)
		(sheetname "/Peripherals/")
		(sheetfile "peripherals.kicad_sch")
		(attr smd)
		(fp_rect
			(start -0.925 -0.47)
			(end 0.925 0.47)
			(stroke
				(width 0.05)
				(type default)
			)
			(fill no)
			(layer "F.CrtYd")
		)
		(fp_rect
			(start -0.5 -0.25)
			(end 0.5 0.25)
			(stroke
				(width 0.15)
				(type solid)
			)
			(fill no)
			(layer "F.Fab")
		)
		(fp_text user "${REFERENCE}"
			(at -0.95 3.168 0)
			(layer "F.Fab")
			(effects
				(font
					(size 0.7 0.7)
					(thickness 0.15)
				)
				(justify left bottom)
			)
		)
		(fp_text user "Author: Antmicro"
			(at -0.95 4.169 0)
			(layer "F.Fab")
			(effects
				(font
					(size 0.7 0.7)
					(thickness 0.15)
				)
				(justify left bottom)
			)
		)
		(fp_text user "License: Apache-2.0"
			(at -0.95 5.169 0)
			(layer "F.Fab")
			(effects
				(font
					(size 0.7 0.7)
					(thickness 0.15)
				)
				(justify left bottom)
			)
		)
		(pad "1" smd roundrect
			(at -0.48 0)
			(size 0.59 0.64)
			(layers "F.Cu" "F.Mask" "F.Paste")
			(roundrect_rratio 0.25)
			(net 88 "/Peripherals/FFC1_VSYNC0")
			(pintype "passive")
		)
		(pad "2" smd roundrect
			(at 0.48 0)
			(size 0.59 0.64)
			(layers "F.Cu" "F.Mask" "F.Paste")
			(roundrect_rratio 0.25)
			(net 56 "Net-(J4-Pad32)")
			(pintype "passive")
		)
	)
	(footprint "antmicro-footprints:TP_SMD_0.75mm"
		(layer "F.Cu")
		(at 104.3 98.7 -90)
		(property "Reference" "TP20"
			(at 0.42 0.46 180)
			(layer "F.SilkS")
			(effects
				(font
					(size 0.65 0.65)
					(thickness 0.15)
				)
				(justify right bottom)
			)
		)
		(property "Value" "TP_0.75mm_SMD"
			(at 0 1.2 90)
			(layer "F.Fab")
			(hide yes)
			(effects
				(font
					(size 0.7 0.7)
					(thickness 0.15)
				)
				(justify right bottom)
			)
		)
		(property "Description" "SMT test point"
			(at 0 0 270)
			(layer "F.Fab")
			(hide yes)
			(effects
				(font
					(size 1.27 1.27)
					(thickness 0.15)
				)
			)
		)
		(property "Author" "Antmicro"
			(at 5.6 203 0)
			(layer "F.Fab")
			(hide yes)
			(effects
				(font
					(size 1 1)
					(thickness 0.15)
				)
			)
		)
		(property "License" "Apache-2.0"
			(at 5.6 203 0)
			(layer "F.Fab")
			(hide yes)
			(effects
				(font
					(size 1 1)
					(thickness 0.15)
				)
			)
		)
		(property "MPN" ""
			(at 5.6 203 0)
			(layer "F.Fab")
			(hide yes)
			(effects
				(font
					(size 1 1)
					(thickness 0.15)
				)
			)
		)
		(property "Manufacturer" ""
			(at 5.6 203 0)
			(layer "F.Fab")
			(hide yes)
			(effects
				(font
					(size 1 1)
					(thickness 0.15)
				)
			)
		)
		(sheetname "/FPGA/")
		(sheetfile "fpga.kicad_sch")
		(attr exclude_from_pos_files)
		(fp_circle
			(center 0 0)
			(end 0.475 0)
			(stroke
				(width 0.05)
				(type default)
			)
			(fill no)
			(layer "F.CrtYd")
		)
		(fp_text user "${REFERENCE}"
			(at -0.4 2.7 270)
			(layer "F.Fab")
			(effects
				(font
					(size 0.7 0.7)
					(thickness 0.15)
				)
				(justify left bottom)
			)
		)
		(fp_text user "Author: Antmicro"
			(at -0.4 3.901 270)
			(layer "F.Fab")
			(effects
				(font
					(size 0.7 0.7)
					(thickness 0.15)
				)
				(justify left bottom)
			)
		)
		(fp_text user "License: Apache-2.0"
			(at -0.4 5.101 270)
			(layer "F.Fab")
			(effects
				(font
					(size 0.7 0.7)
					(thickness 0.15)
				)
				(justify left bottom)
			)
		)
		(pad "1" smd circle
			(at 0 0 270)
			(size 0.75 0.75)
			(layers "F.Cu" "F.Mask")
			(net 303 "Net-(U18-SCLK)")
			(pinfunction "1")
			(pintype "passive")
		)
	)
	(footprint "antmicro-footprints:SW_B3U-3000PM_SMD"
		(layer "F.Cu")
		(at 143.83 122.74)
		(property "Reference" "S1"
			(at 3.2 0.2 90)
			(layer "F.SilkS")
			(effects
				(font
					(size 0.65 0.65)
					(thickness 0.15)
				)
				(justify left bottom)
			)
		)
		(property "Value" "SW_B3U-3000PM"
			(at 0 2.8 0)
			(layer "F.Fab")
			(hide yes)
			(effects
				(font
					(size 0.7 0.7)
					(thickness 0.15)
				)
				(justify left bottom)
			)
		)
		(property "Datasheet" "http://www.farnell.com/datasheets/2610940.pdf"
			(at 0 0 0)
			(layer "F.Fab")
			(hide yes)
			(effects
				(font
					(size 1.27 1.27)
					(thickness 0.15)
				)
			)
		)
		(property "Description" "Tactile Switch SPST-NO Side Actuated Surface Mount, Right Angle"
			(at 0 0 0)
			(layer "F.Fab")
			(hide yes)
			(effects
				(font
					(size 1.27 1.27)
					(thickness 0.15)
				)
			)
		)
		(property "Author" "Antmicro"
			(at 0 0 0)
			(layer "F.Fab")
			(hide yes)
			(effects
				(font
					(size 1 1)
					(thickness 0.15)
				)
			)
		)
		(property "License" "Apache-2.0"
			(at 0 0 0)
			(layer "F.Fab")
			(hide yes)
			(effects
				(font
					(size 1 1)
					(thickness 0.15)
				)
			)
		)
		(property "MPN" "B3U-3000PM"
			(at 0 0 0)
			(layer "F.Fab")
			(hide yes)
			(effects
				(font
					(size 1 1)
					(thickness 0.15)
				)
			)
		)
		(property "Manufacturer" "Omron"
			(at 0 0 0)
			(layer "F.Fab")
			(hide yes)
			(effects
				(font
					(size 1 1)
					(thickness 0.15)
				)
			)
		)
		(sheetname "/FPGA/")
		(sheetfile "fpga.kicad_sch")
		(attr smd)
		(fp_line
			(start -1.5 -1.299)
			(end -1.5 -1.599)
			(stroke
				(width 0.15)
				(type solid)
			)
			(layer "F.SilkS")
		)
		(fp_line
			(start -1.5 0.9)
			(end -1.5 0.6)
			(stroke
				(width 0.15)
				(type solid)
			)
			(layer "F.SilkS")
		)
		(fp_line
			(start -1.5 0.9)
			(end 1.5 0.9)
			(stroke
				(width 0.15)
				(type solid)
			)
			(layer "F.SilkS")
		)
		(fp_line
			(start -0.9 0.9)
			(end -0.9 1.301)
			(stroke
				(width 0.15)
				(type solid)
			)
			(layer "F.SilkS")
		)
		(fp_line
			(start -0.5 1.651)
			(end -0.9 1.301)
			(stroke
				(width 0.15)
				(type solid)
			)
			(layer "F.SilkS")
		)
		(fp_line
			(start 0.5 1.651)
			(end -0.5 1.651)
			(stroke
				(width 0.15)
				(type solid)
			)
			(layer "F.SilkS")
		)
		(fp_line
			(start 0.5 1.651)
			(end 0.9 1.301)
			(stroke
				(width 0.15)
				(type solid)
			)
			(layer "F.SilkS")
		)
		(fp_line
			(start 0.9 0.9)
			(end 0.9 1.301)
			(stroke
				(width 0.15)
				(type solid)
			)
			(layer "F.SilkS")
		)
		(fp_line
			(start 1.5 -1.599)
			(end -1.501 -1.599)
			(stroke
				(width 0.15)
				(type solid)
			)
			(layer "F.SilkS")
		)
		(fp_line
			(start 1.5 -1.299)
			(end 1.5 -1.599)
			(stroke
				(width 0.15)
				(type solid)
			)
			(layer "F.SilkS")
		)
		(fp_line
			(start 1.5 0.9)
			(end 1.5 0.6)
			(stroke
				(width 0.15)
				(type solid)
			)
			(layer "F.SilkS")
		)
		(fp_rect
			(start -2.4 -1.9)
			(end 2.4 1.9)
			(stroke
				(width 0.05)
				(type solid)
			)
			(fill no)
			(layer "F.CrtYd")
		)
		(fp_line
			(start -0.9 -1.6)
			(end -1.5 -1)
			(stroke
				(width 0.15)
				(type solid)
			)
			(layer "F.Fab")
		)
		(fp_line
			(start -0.9 0.9)
			(end -0.9 1.301)
			(stroke
				(width 0.15)
				(type solid)
			)
			(layer "F.Fab")
		)
		(fp_line
			(start -0.5 1.651)
			(end -0.9 1.301)
			(stroke
				(width 0.15)
				(type solid)
			)
			(layer "F.Fab")
		)
		(fp_line
			(start 0.5 1.651)
			(end -0.5 1.651)
			(stroke
				(width 0.15)
				(type solid)
			)
			(layer "F.Fab")
		)
		(fp_line
			(start 0.5 1.651)
			(end 0.9 1.301)
			(stroke
				(width 0.15)
				(type solid)
			)
			(layer "F.Fab")
		)
		(fp_line
			(start 0.9 0.9)
			(end 0.9 1.301)
			(stroke
				(width 0.15)
				(type solid)
			)
			(layer "F.Fab")
		)
		(fp_rect
			(start -1.5 -1.6)
			(end 1.5 0.9)
			(stroke
				(width 0.15)
				(type solid)
			)
			(fill no)
			(layer "F.Fab")
		)
		(fp_text user "License: Apache-2.0"
			(at -2.4 6.849 0)
			(layer "F.Fab")
			(effects
				(font
					(size 0.7 0.7)
					(thickness 0.15)
				)
				(justify left bottom)
			)
		)
		(fp_text user "Author: Antmicro"
			(at -2.4 5.649 0)
			(layer "F.Fab")
			(effects
				(font
					(size 0.7 0.7)
					(thickness 0.15)
				)
				(justify left bottom)
			)
		)
		(fp_text user "${REFERENCE}"
			(at -2.4 4.448 0)
			(layer "F.Fab")
			(effects
				(font
					(size 0.7 0.7)
					(thickness 0.15)
				)
				(justify left bottom)
			)
		)
		(pad "1" smd rect
			(at -1.7 -0.35)
			(size 0.8 1.7)
			(layers "F.Cu" "F.Mask" "F.Paste")
			(net 1 "GND")
			(pinfunction "1")
			(pintype "passive")
		)
		(pad "2" smd rect
			(at 1.7 -0.35)
			(size 0.8 1.7)
			(layers "F.Cu" "F.Mask" "F.Paste")
			(net 281 "Net-(R72-Pad2)")
			(pinfunction "2")
			(pintype "passive")
		)
	)
	(footprint "antmicro-footprints:TSOT23-6"
		(layer "F.Cu")
		(at 142.989 69.204 180)
		(property "Reference" "U5"
			(at 1.059 2.144 0)
			(layer "F.SilkS")
			(effects
				(font
					(size 0.65 0.65)
					(thickness 0.15)
				)
				(justify right top)
			)
		)
		(property "Value" "AP62301WU-7"
			(at -0.005 2.6 0)
			(layer "F.Fab")
			(hide yes)
			(effects
				(font
					(size 0.7 0.7)
					(thickness 0.15)
				)
				(justify right top)
			)
		)
		(property "Datasheet" "https://www.diodes.com/assets/Datasheets/AP62300_AP62301_AP62300T.pdf"
			(at 0 0 0)
			(layer "F.Fab")
			(hide yes)
			(effects
				(font
					(size 1.27 1.27)
					(thickness 0.15)
				)
			)
		)
		(property "Description" "DC-DC Switching Synchronous Buck Regulator, Adjustable, 4.2V-18Vin, 0.8V-7V/3A out, TSOT-26-6"
			(at 0 0 0)
			(layer "F.Fab")
			(hide yes)
			(effects
				(font
					(size 1.27 1.27)
					(thickness 0.15)
				)
			)
		)
		(property "Author" "Antmicro"
			(at 212.17 -73.79 90)
			(layer "F.Fab")
			(hide yes)
			(effects
				(font
					(size 1 1)
					(thickness 0.15)
				)
			)
		)
		(property "License" "Apache-2.0"
			(at 212.17 -73.79 90)
			(layer "F.Fab")
			(hide yes)
			(effects
				(font
					(size 1 1)
					(thickness 0.15)
				)
			)
		)
		(property "MPN" "AP62301WU-7"
			(at 212.17 -73.79 90)
			(layer "F.Fab")
			(hide yes)
			(effects
				(font
					(size 1 1)
					(thickness 0.15)
				)
			)
		)
		(property "Manufacturer" "Diodes Incorporated"
			(at 212.17 -73.79 90)
			(layer "F.Fab")
			(hide yes)
			(effects
				(font
					(size 1 1)
					(thickness 0.15)
				)
			)
		)
		(sheetname "/Power Supply/")
		(sheetfile "supply.kicad_sch")
		(attr smd)
		(fp_line
			(start 1 1.55)
			(end 1 1.4)
			(stroke
				(width 0.15)
				(type solid)
			)
			(layer "F.SilkS")
		)
		(fp_line
			(start 1 1.55)
			(end -1 1.55)
			(stroke
				(width 0.15)
				(type solid)
			)
			(layer "F.SilkS")
		)
		(fp_line
			(start 1 -1.497)
			(end 1 -1.375)
			(stroke
				(width 0.15)
				(type solid)
			)
			(layer "F.SilkS")
		)
		(fp_line
			(start 1 -1.497)
			(end -1 -1.5)
			(stroke
				(width 0.15)
				(type solid)
			)
			(layer "F.SilkS")
		)
		(fp_line
			(start -1 1.55)
			(end -1 1.4)
			(stroke
				(width 0.15)
				(type solid)
			)
			(layer "F.SilkS")
		)
		(fp_line
			(start -1 -1.5)
			(end -1 -1.375)
			(stroke
				(width 0.15)
				(type solid)
			)
			(layer "F.SilkS")
		)
		(fp_circle
			(center -1.44 -1.5)
			(end -1.39 -1.5)
			(stroke
				(width 0.15)
				(type solid)
			)
			(fill yes)
			(layer "F.SilkS")
		)
		(fp_rect
			(start 1.93 -1.7)
			(end -1.93 1.7)
			(stroke
				(width 0.05)
				(type solid)
			)
			(fill no)
			(layer "F.CrtYd")
		)
		(fp_line
			(start -0.45 -1.521)
			(end -0.876 -1.096)
			(stroke
				(width 0.15)
				(type solid)
			)
			(layer "F.Fab")
		)
		(fp_rect
			(start 0.875 1.528)
			(end -0.875 -1.525)
			(stroke
				(width 0.15)
				(type solid)
			)
			(fill no)
			(layer "F.Fab")
		)
		(fp_text user "License: Apache-2.0"
			(at -1.93 6.199 0)
			(layer "F.Fab")
			(effects
				(font
					(size 0.7 0.7)
					(thickness 0.15)
				)
				(justify right top)
			)
		)
		(fp_text user "Author: Antmicro"
			(at -1.93 5 0)
			(layer "F.Fab")
			(effects
				(font
					(size 0.7 0.7)
					(thickness 0.15)
				)
				(justify right top)
			)
		)
		(fp_text user "${REFERENCE}"
			(at -1.93 3.8 0)
			(layer "F.Fab")
			(effects
				(font
					(size 0.7 0.7)
					(thickness 0.15)
				)
				(justify right top)
			)
		)
		(pad "1" smd rect
			(at -1.301 -0.947 90)
			(size 0.7 1.2)
			(layers "F.Cu" "F.Mask" "F.Paste")
			(net 1 "GND")
			(pinfunction "GND")
			(pintype "power_in")
		)
		(pad "2" smd rect
			(at -1.301 0.004 90)
			(size 0.7 1.2)
			(layers "F.Cu" "F.Mask" "F.Paste")
			(net 276 "/Power Supply/1V0_SW")
			(pinfunction "SW")
			(pintype "power_out")
		)
		(pad "3" smd rect
			(at -1.301 0.954 90)
			(size 0.7 1.2)
			(layers "F.Cu" "F.Mask" "F.Paste")
			(net 326 "/Power Supply/5V_1V0_IN")
			(pinfunction "VIN")
			(pintype "power_in")
		)
		(pad "4" smd rect
			(at 1.299 0.954 90)
			(size 0.7 1.2)
			(layers "F.Cu" "F.Mask" "F.Paste")
			(net 267 "Net-(U5-FB)")
			(pinfunction "FB")
			(pintype "input")
		)
		(pad "5" smd rect
			(at 1.299 0.004 90)
			(size 0.7 1.2)
			(layers "F.Cu" "F.Mask" "F.Paste")
			(net 373 "Net-(U5-EN)")
			(pinfunction "EN")
			(pintype "input")
		)
		(pad "6" smd rect
			(at 1.299 -0.947 90)
			(size 0.7 1.2)
			(layers "F.Cu" "F.Mask" "F.Paste")
			(net 61 "Net-(U5-BST)")
			(pinfunction "BST")
			(pintype "output")
		)
	)
	(footprint "antmicro-footprints:R_0603_1608Metric"
		(layer "F.Cu")
		(at 141.46 85.5)
		(descr "Resistor SMD 0603")
		(tags "resistor SMD 0603")
		(property "Reference" "R136"
			(at 1.27 0.44 0)
			(layer "F.SilkS")
			(effects
				(font
					(size 0.65 0.65)
					(thickness 0.15)
				)
				(justify left bottom)
			)
		)
		(property "Value" "R_200R_0603"
			(at 0 1.6 0)
			(layer "F.Fab")
			(hide yes)
			(effects
				(font
					(size 0.7 0.7)
					(thickness 0.15)
				)
				(justify left bottom)
			)
		)
		(property "Datasheet" "https://www.bourns.com/docs/product-datasheets/cr.pdf"
			(at 0 0 0)
			(layer "F.Fab")
			(hide yes)
			(effects
				(font
					(size 1.27 1.27)
					(thickness 0.15)
				)
			)
		)
		(property "Description" "SMD Chip Resistor, 200 ohm, ± 1%, 100 mW, 0603 [1608 Metric], Thick Film, General Purpose"
			(at 0 0 0)
			(layer "F.Fab")
			(hide yes)
			(effects
				(font
					(size 1.27 1.27)
					(thickness 0.15)
				)
			)
		)
		(property "Author" "Antmicro"
			(at 0 0 0)
			(layer "F.Fab")
			(hide yes)
			(effects
				(font
					(size 1 1)
					(thickness 0.15)
				)
			)
		)
		(property "License" "Apache-2.0"
			(at 0 0 0)
			(layer "F.Fab")
			(hide yes)
			(effects
				(font
					(size 1 1)
					(thickness 0.15)
				)
			)
		)
		(property "MPN" "CR0603-FX-2000ELF"
			(at 0 0 0)
			(layer "F.Fab")
			(hide yes)
			(effects
				(font
					(size 1 1)
					(thickness 0.15)
				)
			)
		)
		(property "Manufacturer" "Bourns"
			(at 0 0 0)
			(layer "F.Fab")
			(hide yes)
			(effects
				(font
					(size 1 1)
					(thickness 0.15)
				)
			)
		)
		(property "Tolerance" "1%"
			(at 0 0 0)
			(layer "F.Fab")
			(hide yes)
			(effects
				(font
					(size 1 1)
					(thickness 0.15)
				)
			)
		)
		(property "Val" "200R"
			(at 0 0 0)
			(layer "F.Fab")
			(hide yes)
			(effects
				(font
					(size 1 1)
					(thickness 0.15)
				)
			)
		)
		(sheetname "/Peripherals/")
		(sheetfile "peripherals.kicad_sch")
		(attr smd)
		(fp_line
			(start -0.15 -0.4)
			(end 0.15 -0.4)
			(stroke
				(width 0.15)
				(type solid)
			)
			(layer "F.SilkS")
		)
		(fp_line
			(start -0.15 0.4)
			(end 0.15 0.4)
			(stroke
				(width 0.15)
				(type solid)
			)
			(layer "F.SilkS")
		)
		(fp_rect
			(start -1.25 -0.65)
			(end 1.25 0.65)
			(stroke
				(width 0.05)
				(type solid)
			)
			(fill no)
			(layer "F.CrtYd")
		)
		(fp_rect
			(start -0.8 -0.4)
			(end 0.8 0.4)
			(stroke
				(width 0.15)
				(type solid)
			)
			(fill no)
			(layer "F.Fab")
		)
		(fp_text user "${REFERENCE}"
			(at -1.25 3.898 0)
			(layer "F.Fab")
			(effects
				(font
					(size 0.7 0.7)
					(thickness 0.15)
				)
				(justify left bottom)
			)
		)
		(fp_text user "Author: Antmicro"
			(at -1.25 4.9 0)
			(layer "F.Fab")
			(effects
				(font
					(size 0.7 0.7)
					(thickness 0.15)
				)
				(justify left bottom)
			)
		)
		(fp_text user "License: Apache-2.0"
			(at -1.25 5.9 0)
			(layer "F.Fab")
			(effects
				(font
					(size 0.7 0.7)
					(thickness 0.15)
				)
				(justify left bottom)
			)
		)
		(pad "1" smd roundrect
			(at -0.7 0)
			(size 0.8 1)
			(layers "F.Cu" "F.Mask" "F.Paste")
			(roundrect_rratio 0.2)
			(net 295 "Net-(D13-A)")
			(pintype "passive")
		)
		(pad "2" smd roundrect
			(at 0.7 0)
			(size 0.8 1)
			(layers "F.Cu" "F.Mask" "F.Paste")
			(roundrect_rratio 0.2)
			(net 348 "/Peripherals/FTDI_VCCIO")
			(pintype "passive")
		)
	)
	(footprint "antmicro-footprints:TP_SMD_0.75mm"
		(layer "F.Cu")
		(at 99 68.25)
		(property "Reference" "TP26"
			(at -3.22 0.39 0)
			(layer "F.SilkS")
			(effects
				(font
					(size 0.65 0.65)
					(thickness 0.15)
				)
				(justify left bottom)
			)
		)
		(property "Value" "TP_0.75mm_SMD"
			(at 0 1.2 0)
			(layer "F.Fab")
			(hide yes)
			(effects
				(font
					(size 0.7 0.7)
					(thickness 0.15)
				)
				(justify left bottom)
			)
		)
		(property "Description" "SMT test point"
			(at 0 0 0)
			(layer "F.Fab")
			(hide yes)
			(effects
				(font
					(size 1.27 1.27)
					(thickness 0.15)
				)
			)
		)
		(property "Author" "Antmicro"
			(at 0 0 0)
			(layer "F.Fab")
			(hide yes)
			(effects
				(font
					(size 1 1)
					(thickness 0.15)
				)
			)
		)
		(property "License" "Apache-2.0"
			(at 0 0 0)
			(layer "F.Fab")
			(hide yes)
			(effects
				(font
					(size 1 1)
					(thickness 0.15)
				)
			)
		)
		(property "MPN" ""
			(at 0 0 0)
			(layer "F.Fab")
			(hide yes)
			(effects
				(font
					(size 1 1)
					(thickness 0.15)
				)
			)
		)
		(property "Manufacturer" ""
			(at 0 0 0)
			(layer "F.Fab")
			(hide yes)
			(effects
				(font
					(size 1 1)
					(thickness 0.15)
				)
			)
		)
		(sheetname "/SDI/")
		(sheetfile "sdi.kicad_sch")
		(attr exclude_from_pos_files)
		(fp_circle
			(center 0 0)
			(end 0.475 0)
			(stroke
				(width 0.05)
				(type default)
			)
			(fill no)
			(layer "F.CrtYd")
		)
		(fp_text user "License: Apache-2.0"
			(at -0.4 5.101 0)
			(layer "F.Fab")
			(effects
				(font
					(size 0.7 0.7)
					(thickness 0.15)
				)
				(justify left bottom)
			)
		)
		(fp_text user "${REFERENCE}"
			(at -0.4 2.7 0)
			(layer "F.Fab")
			(effects
				(font
					(size 0.7 0.7)
					(thickness 0.15)
				)
				(justify left bottom)
			)
		)
		(fp_text user "Author: Antmicro"
			(at -0.4 3.901 0)
			(layer "F.Fab")
			(effects
				(font
					(size 0.7 0.7)
					(thickness 0.15)
				)
				(justify left bottom)
			)
		)
		(pad "1" smd circle
			(at 0 0)
			(size 0.75 0.75)
			(layers "F.Cu" "F.Mask")
			(net 212 "/SDI/SDI_STAT2")
			(pinfunction "1")
			(pintype "passive")
		)
	)
	(footprint "antmicro-footprints:R_0402_1005Metric"
		(layer "F.Cu")
		(at 167.2 93.6)
		(descr "Resistor SMD 0402")
		(tags "resistor SMD 0402")
		(property "Reference" "R122"
			(at -3.67 0.34 0)
			(layer "F.SilkS")
			(effects
				(font
					(size 0.65 0.65)
					(thickness 0.15)
				)
				(justify left bottom)
			)
		)
		(property "Value" "R_0R_0402"
			(at 0 1.4 0)
			(layer "F.Fab")
			(hide yes)
			(effects
				(font
					(size 0.7 0.7)
					(thickness 0.15)
				)
				(justify left bottom)
			)
		)
		(property "Datasheet" "https://industrial.panasonic.com/cdbs/www-data/pdf/RDA0000/AOA0000C301.pdf"
			(at 0 0 0)
			(layer "F.Fab")
			(hide yes)
			(effects
				(font
					(size 1.27 1.27)
					(thickness 0.15)
				)
			)
		)
		(property "Description" "SMD Chip Resistor, Jumper, 0 ohm, 100 mW, 0402 [1005 Metric], Thick Film, General Purpose"
			(at 0 0 0)
			(layer "F.Fab")
			(hide yes)
			(effects
				(font
					(size 1.27 1.27)
					(thickness 0.15)
				)
			)
		)
		(property "Author" "Antmicro"
			(at 0 0 0)
			(layer "F.Fab")
			(hide yes)
			(effects
				(font
					(size 1 1)
					(thickness 0.15)
				)
			)
		)
		(property "Current" "1A"
			(at 0 0 0)
			(layer "F.Fab")
			(hide yes)
			(effects
				(font
					(size 1 1)
					(thickness 0.15)
				)
			)
		)
		(property "License" "Apache-2.0"
			(at 0 0 0)
			(layer "F.Fab")
			(hide yes)
			(effects
				(font
					(size 1 1)
					(thickness 0.15)
				)
			)
		)
		(property "MPN" "ERJ2GE0R00X"
			(at 0 0 0)
			(layer "F.Fab")
			(hide yes)
			(effects
				(font
					(size 1 1)
					(thickness 0.15)
				)
			)
		)
		(property "Manufacturer" "Panasonic"
			(at 0 0 0)
			(layer "F.Fab")
			(hide yes)
			(effects
				(font
					(size 1 1)
					(thickness 0.15)
				)
			)
		)
		(property "Tolerance" "~"
			(at 0 0 0)
			(layer "F.Fab")
			(hide yes)
			(effects
				(font
					(size 1 1)
					(thickness 0.15)
				)
			)
		)
		(property "Val" "0R"
			(at 0 0 0)
			(layer "F.Fab")
			(hide yes)
			(effects
				(font
					(size 1 1)
					(thickness 0.15)
				)
			)
		)
		(sheetname "/Peripherals/")
		(sheetfile "peripherals.kicad_sch")
		(attr smd)
		(fp_rect
			(start -0.925 -0.47)
			(end 0.925 0.47)
			(stroke
				(width 0.05)
				(type default)
			)
			(fill no)
			(layer "F.CrtYd")
		)
		(fp_rect
			(start -0.5 -0.25)
			(end 0.5 0.25)
			(stroke
				(width 0.15)
				(type solid)
			)
			(fill no)
			(layer "F.Fab")
		)
		(fp_text user "Author: Antmicro"
			(at -0.95 4.169 0)
			(layer "F.Fab")
			(effects
				(font
					(size 0.7 0.7)
					(thickness 0.15)
				)
				(justify left bottom)
			)
		)
		(fp_text user "${REFERENCE}"
			(at -0.95 3.168 0)
			(layer "F.Fab")
			(effects
				(font
					(size 0.7 0.7)
					(thickness 0.15)
				)
				(justify left bottom)
			)
		)
		(fp_text user "License: Apache-2.0"
			(at -0.95 5.169 0)
			(layer "F.Fab")
			(effects
				(font
					(size 0.7 0.7)
					(thickness 0.15)
				)
				(justify left bottom)
			)
		)
		(pad "1" smd roundrect
			(at -0.48 0)
			(size 0.59 0.64)
			(layers "F.Cu" "F.Mask" "F.Paste")
			(roundrect_rratio 0.25)
			(net 91 "/Peripherals/FCC1_SDA1")
			(pintype "passive")
		)
		(pad "2" smd roundrect
			(at 0.48 0)
			(size 0.59 0.64)
			(layers "F.Cu" "F.Mask" "F.Paste")
			(roundrect_rratio 0.25)
			(net 342 "Net-(J4-Pad39)")
			(pintype "passive")
		)
	)
	(footprint "antmicro-footprints:MP_Pad5.4mm_Drill2.7mm"
		(layer "F.Cu")
		(at 170.03 120.15)
		(descr "Mounting Hole 2.7mm, M2.5")
		(tags "mounting hole 2.7mm m2.5")
		(property "Reference" "MP4"
			(at 0 -2.9 0)
			(layer "F.SilkS")
			(hide yes)
			(effects
				(font
					(size 0.7 0.7)
					(thickness 0.15)
				)
				(justify left bottom)
			)
		)
		(property "Value" "MP_Pad5.4mm_Drill2.7mm"
			(at 0 3.6 0)
			(layer "F.Fab")
			(effects
				(font
					(size 0.7 0.7)
					(thickness 0.15)
				)
				(justify left bottom)
			)
		)
		(property "Description" "Mechanical part"
			(at 0 0 0)
			(layer "F.Fab")
			(hide yes)
			(effects
				(font
					(size 1.27 1.27)
					(thickness 0.15)
				)
			)
		)
		(property "Author" "Antmicro"
			(at 0 0 0)
			(unlocked yes)
			(layer "F.Fab")
			(hide yes)
			(effects
				(font
					(size 1 1)
					(thickness 0.15)
				)
			)
		)
		(property "License" "Apache-2.0"
			(at 0 0 0)
			(unlocked yes)
			(layer "F.Fab")
			(hide yes)
			(effects
				(font
					(size 1 1)
					(thickness 0.15)
				)
			)
		)
		(sheetname "/")
		(sheetfile "sdi-mipi-video-converter.kicad_sch")
		(attr exclude_from_pos_files exclude_from_bom)
		(fp_circle
			(center 0 0)
			(end 2.95 0)
			(stroke
				(width 0.05)
				(type default)
			)
			(fill no)
			(layer "F.CrtYd")
		)
		(fp_text user "Author: Antmicro"
			(at -8.4 7.2 0)
			(layer "F.Fab")
			(effects
				(font
					(size 0.7 0.7)
					(thickness 0.15)
				)
				(justify left bottom)
			)
		)
		(fp_text user "${REFERENCE}"
			(at -8.4 6 0)
			(layer "F.Fab")
			(effects
				(font
					(size 0.7 0.7)
					(thickness 0.15)
				)
				(justify left bottom)
			)
		)
		(fp_text user "License: Apache-2.0"
			(at -8.4 8.4 0)
			(layer "F.Fab")
			(effects
				(font
					(size 0.7 0.7)
					(thickness 0.15)
				)
				(justify left bottom)
			)
		)
		(pad "1" thru_hole circle
			(at 0 0)
			(size 5.4 5.4)
			(drill 2.7)
			(layers "*.Cu" "*.Mask")
			(remove_unused_layers no)
			(net 401 "unconnected-(MP4-Pad1)")
			(pintype "passive+no_connect")
			(solder_paste_margin_ratio -1)
		)
	)
	(footprint "antmicro-footprints:R_0402_1005Metric"
		(layer "F.Cu")
		(at 166.09 69.85 90)
		(descr "Resistor SMD 0402")
		(tags "resistor SMD 0402")
		(property "Reference" "R14"
			(at 1.21 -0.36 180)
			(layer "F.SilkS")
			(effects
				(font
					(size 0.65 0.65)
					(thickness 0.15)
				)
				(justify left bottom)
			)
		)
		(property "Value" "R_470R_0402"
			(at 0 1.4 90)
			(layer "F.Fab")
			(hide yes)
			(effects
				(font
					(size 0.7 0.7)
					(thickness 0.15)
				)
				(justify left bottom)
			)
		)
		(property "Datasheet" "https://www.bourns.com/docs/product-datasheets/cr.pdf"
			(at 0 0 90)
			(layer "F.Fab")
			(hide yes)
			(effects
				(font
					(size 1.27 1.27)
					(thickness 0.15)
				)
			)
		)
		(property "Description" "SMD Chip Resistor, 470 ohm, ± 1%, 62.5 mW, 0402 [1005 Metric], Thick Film, General Purpose"
			(at 0 0 90)
			(layer "F.Fab")
			(hide yes)
			(effects
				(font
					(size 1.27 1.27)
					(thickness 0.15)
				)
			)
		)
		(property "Author" "Antmicro"
			(at 235.94 -96.24 0)
			(layer "F.Fab")
			(hide yes)
			(effects
				(font
					(size 1 1)
					(thickness 0.15)
				)
			)
		)
		(property "License" "Apache-2.0"
			(at 235.94 -96.24 0)
			(layer "F.Fab")
			(hide yes)
			(effects
				(font
					(size 1 1)
					(thickness 0.15)
				)
			)
		)
		(property "MPN" "CR0402-FX-4700GLF"
			(at 235.94 -96.24 0)
			(layer "F.Fab")
			(hide yes)
			(effects
				(font
					(size 1 1)
					(thickness 0.15)
				)
			)
		)
		(property "Manufacturer" "Bourns"
			(at 235.94 -96.24 0)
			(layer "F.Fab")
			(hide yes)
			(effects
				(font
					(size 1 1)
					(thickness 0.15)
				)
			)
		)
		(property "Tolerance" "1%"
			(at 235.94 -96.24 0)
			(layer "F.Fab")
			(hide yes)
			(effects
				(font
					(size 1 1)
					(thickness 0.15)
				)
			)
		)
		(property "Val" "470R"
			(at 235.94 -96.24 0)
			(layer "F.Fab")
			(hide yes)
			(effects
				(font
					(size 1 1)
					(thickness 0.15)
				)
			)
		)
		(sheetname "/Power Supply/")
		(sheetfile "supply.kicad_sch")
		(attr smd)
		(fp_rect
			(start -0.925 -0.47)
			(end 0.925 0.47)
			(stroke
				(width 0.05)
				(type default)
			)
			(fill no)
			(layer "F.CrtYd")
		)
		(fp_rect
			(start -0.5 -0.25)
			(end 0.5 0.25)
			(stroke
				(width 0.15)
				(type solid)
			)
			(fill no)
			(layer "F.Fab")
		)
		(fp_text user "${REFERENCE}"
			(at -0.95 3.168 90)
			(layer "F.Fab")
			(effects
				(font
					(size 0.7 0.7)
					(thickness 0.15)
				)
				(justify left bottom)
			)
		)
		(fp_text user "Author: Antmicro"
			(at -0.95 4.169 90)
			(layer "F.Fab")
			(effects
				(font
					(size 0.7 0.7)
					(thickness 0.15)
				)
				(justify left bottom)
			)
		)
		(fp_text user "License: Apache-2.0"
			(at -0.95 5.169 90)
			(layer "F.Fab")
			(effects
				(font
					(size 0.7 0.7)
					(thickness 0.15)
				)
				(justify left bottom)
			)
		)
		(pad "1" smd roundrect
			(at -0.48 0 90)
			(size 0.59 0.64)
			(layers "F.Cu" "F.Mask" "F.Paste")
			(roundrect_rratio 0.25)
			(net 58 "Net-(D1-A)")
			(pintype "passive")
		)
		(pad "2" smd roundrect
			(at 0.48 0 90)
			(size 0.59 0.64)
			(layers "F.Cu" "F.Mask" "F.Paste")
			(roundrect_rratio 0.25)
			(net 14 "+5V")
			(pintype "passive")
		)
	)
	(footprint "antmicro-footprints:R_0402_1005Metric"
		(layer "F.Cu")
		(at 133.83 111.15 180)
		(descr "Resistor SMD 0402")
		(tags "resistor SMD 0402")
		(property "Reference" "R70"
			(at 3.2 0.01 180)
			(layer "F.SilkS")
			(effects
				(font
					(size 0.65 0.65)
					(thickness 0.15)
				)
				(justify left bottom)
			)
		)
		(property "Value" "R_100R_0402"
			(at 0 1.4 180)
			(layer "F.Fab")
			(hide yes)
			(effects
				(font
					(size 0.7 0.7)
					(thickness 0.15)
				)
				(justify left bottom)
			)
		)
		(property "Datasheet" "https://www.bourns.com/docs/product-datasheets/cr.pdf"
			(at 0 0 180)
			(layer "F.Fab")
			(hide yes)
			(effects
				(font
					(size 1.27 1.27)
					(thickness 0.15)
				)
			)
		)
		(property "Description" "SMD Chip Resistor, 100 ohm, ± 1%, 62.5 mW, 0402 [1005 Metric], Thick Film, General Purpose"
			(at 0 0 180)
			(layer "F.Fab")
			(hide yes)
			(effects
				(font
					(size 1.27 1.27)
					(thickness 0.15)
				)
			)
		)
		(property "Author" "Antmicro"
			(at 267.66 222.3 0)
			(layer "F.Fab")
			(hide yes)
			(effects
				(font
					(size 1 1)
					(thickness 0.15)
				)
			)
		)
		(property "License" "Apache-2.0"
			(at 267.66 222.3 0)
			(layer "F.Fab")
			(hide yes)
			(effects
				(font
					(size 1 1)
					(thickness 0.15)
				)
			)
		)
		(property "MPN" "CR0402-FX-1000GLF"
			(at 267.66 222.3 0)
			(layer "F.Fab")
			(hide yes)
			(effects
				(font
					(size 1 1)
					(thickness 0.15)
				)
			)
		)
		(property "Manufacturer" "Bourns"
			(at 267.66 222.3 0)
			(layer "F.Fab")
			(hide yes)
			(effects
				(font
					(size 1 1)
					(thickness 0.15)
				)
			)
		)
		(property "Tolerance" "1%"
			(at 267.66 222.3 0)
			(layer "F.Fab")
			(hide yes)
			(effects
				(font
					(size 1 1)
					(thickness 0.15)
				)
			)
		)
		(property "Val" "100R"
			(at 267.66 222.3 0)
			(layer "F.Fab")
			(hide yes)
			(effects
				(font
					(size 1 1)
					(thickness 0.15)
				)
			)
		)
		(sheetname "/FPGA/")
		(sheetfile "fpga.kicad_sch")
		(attr smd)
		(fp_rect
			(start -0.925 -0.47)
			(end 0.925 0.47)
			(stroke
				(width 0.05)
				(type default)
			)
			(fill no)
			(layer "F.CrtYd")
		)
		(fp_rect
			(start -0.5 -0.25)
			(end 0.5 0.25)
			(stroke
				(width 0.15)
				(type solid)
			)
			(fill no)
			(layer "F.Fab")
		)
		(fp_text user "${REFERENCE}"
			(at -0.95 3.168 180)
			(layer "F.Fab")
			(effects
				(font
					(size 0.7 0.7)
					(thickness 0.15)
				)
				(justify left bottom)
			)
		)
		(fp_text user "License: Apache-2.0"
			(at -0.95 5.169 180)
			(layer "F.Fab")
			(effects
				(font
					(size 0.7 0.7)
					(thickness 0.15)
				)
				(justify left bottom)
			)
		)
		(fp_text user "Author: Antmicro"
			(at -0.95 4.169 180)
			(layer "F.Fab")
			(effects
				(font
					(size 0.7 0.7)
					(thickness 0.15)
				)
				(justify left bottom)
			)
		)
		(pad "1" smd roundrect
			(at -0.48 0 180)
			(size 0.59 0.64)
			(layers "F.Cu" "F.Mask" "F.Paste")
			(roundrect_rratio 0.25)
			(net 36 "/FPGA/PROGRAMN")
			(pintype "passive")
		)
		(pad "2" smd roundrect
			(at 0.48 0 180)
			(size 0.59 0.64)
			(layers "F.Cu" "F.Mask" "F.Paste")
			(roundrect_rratio 0.25)
			(net 381 "Net-(C80-Pad2)")
			(pintype "passive")
		)
	)
	(footprint "antmicro-footprints:R_0402_1005Metric"
		(layer "F.Cu")
		(at 122.03 112.15 180)
		(descr "Resistor SMD 0402")
		(tags "resistor SMD 0402")
		(property "Reference" "R89"
			(at 1 -0.39 0)
			(layer "F.SilkS")
			(effects
				(font
					(size 0.65 0.65)
					(thickness 0.15)
				)
				(justify right bottom)
			)
		)
		(property "Value" "R_2k2_0402"
			(at 0 1.4 0)
			(layer "F.Fab")
			(hide yes)
			(effects
				(font
					(size 0.7 0.7)
					(thickness 0.15)
				)
				(justify right bottom)
			)
		)
		(property "Datasheet" "https://www.bourns.com/docs/product-datasheets/cr.pdf"
			(at 0 0 180)
			(layer "F.Fab")
			(hide yes)
			(effects
				(font
					(size 1.27 1.27)
					(thickness 0.15)
				)
			)
		)
		(property "Description" "SMD Chip Resistor, 2.2 kohm, ± 1%, 62.5 mW, 0402 [1005 Metric], Thick Film, General Purpose"
			(at 0 0 180)
			(layer "F.Fab")
			(hide yes)
			(effects
				(font
					(size 1.27 1.27)
					(thickness 0.15)
				)
			)
		)
		(property "Author" "Antmicro"
			(at 244.06 224.3 0)
			(layer "F.Fab")
			(hide yes)
			(effects
				(font
					(size 1 1)
					(thickness 0.15)
				)
			)
		)
		(property "License" "Apache-2.0"
			(at 244.06 224.3 0)
			(layer "F.Fab")
			(hide yes)
			(effects
				(font
					(size 1 1)
					(thickness 0.15)
				)
			)
		)
		(property "MPN" "CR0402-FX-2201GLF"
			(at 244.06 224.3 0)
			(layer "F.Fab")
			(hide yes)
			(effects
				(font
					(size 1 1)
					(thickness 0.15)
				)
			)
		)
		(property "Manufacturer" "Bourns"
			(at 244.06 224.3 0)
			(layer "F.Fab")
			(hide yes)
			(effects
				(font
					(size 1 1)
					(thickness 0.15)
				)
			)
		)
		(property "Tolerance" "1%"
			(at 244.06 224.3 0)
			(layer "F.Fab")
			(hide yes)
			(effects
				(font
					(size 1 1)
					(thickness 0.15)
				)
			)
		)
		(property "Val" "2k2"
			(at 244.06 224.3 0)
			(layer "F.Fab")
			(hide yes)
			(effects
				(font
					(size 1 1)
					(thickness 0.15)
				)
			)
		)
		(sheetname "/FPGA/")
		(sheetfile "fpga.kicad_sch")
		(attr smd)
		(fp_rect
			(start -0.925 -0.47)
			(end 0.925 0.47)
			(stroke
				(width 0.05)
				(type default)
			)
			(fill no)
			(layer "F.CrtYd")
		)
		(fp_rect
			(start -0.5 -0.25)
			(end 0.5 0.25)
			(stroke
				(width 0.15)
				(type solid)
			)
			(fill no)
			(layer "F.Fab")
		)
		(fp_text user "${REFERENCE}"
			(at -0.95 3.168 180)
			(layer "F.Fab")
			(effects
				(font
					(size 0.7 0.7)
					(thickness 0.15)
				)
				(justify left bottom)
			)
		)
		(fp_text user "License: Apache-2.0"
			(at -0.95 5.169 180)
			(layer "F.Fab")
			(effects
				(font
					(size 0.7 0.7)
					(thickness 0.15)
				)
				(justify left bottom)
			)
		)
		(fp_text user "Author: Antmicro"
			(at -0.95 4.169 180)
			(layer "F.Fab")
			(effects
				(font
					(size 0.7 0.7)
					(thickness 0.15)
				)
				(justify left bottom)
			)
		)
		(pad "1" smd roundrect
			(at -0.48 0 180)
			(size 0.59 0.64)
			(layers "F.Cu" "F.Mask" "F.Paste")
			(roundrect_rratio 0.25)
			(net 67 "Net-(D5-A)")
			(pintype "passive")
		)
		(pad "2" smd roundrect
			(at 0.48 0 180)
			(size 0.59 0.64)
			(layers "F.Cu" "F.Mask" "F.Paste")
			(roundrect_rratio 0.25)
			(net 2 "+3V3")
			(pintype "passive")
		)
	)
	(footprint "antmicro-footprints:R_0402_1005Metric"
		(layer "F.Cu")
		(at 90.8 69.2 -90)
		(descr "Resistor SMD 0402")
		(tags "resistor SMD 0402")
		(property "Reference" "R55"
			(at -1.31 -0.48 90)
			(layer "F.SilkS")
			(effects
				(font
					(size 0.65 0.65)
					(thickness 0.15)
				)
				(justify left bottom)
			)
		)
		(property "Value" "R_100k_0402"
			(at 0 1.4 90)
			(layer "F.Fab")
			(hide yes)
			(effects
				(font
					(size 0.7 0.7)
					(thickness 0.15)
				)
				(justify right bottom)
			)
		)
		(property "Datasheet" "https://www.bourns.com/docs/product-datasheets/cr.pdf"
			(at 0 0 270)
			(layer "F.Fab")
			(hide yes)
			(effects
				(font
					(size 1.27 1.27)
					(thickness 0.15)
				)
			)
		)
		(property "Description" "SMD Chip Resistor, 100 kohm, ± 1%, 62.5 mW, 0402 [1005 Metric], Thick Film, General Purpose"
			(at 0 0 270)
			(layer "F.Fab")
			(hide yes)
			(effects
				(font
					(size 1.27 1.27)
					(thickness 0.15)
				)
			)
		)
		(property "Author" "Antmicro"
			(at 21.6 160 0)
			(layer "F.Fab")
			(hide yes)
			(effects
				(font
					(size 1 1)
					(thickness 0.15)
				)
			)
		)
		(property "License" "Apache-2.0"
			(at 21.6 160 0)
			(layer "F.Fab")
			(hide yes)
			(effects
				(font
					(size 1 1)
					(thickness 0.15)
				)
			)
		)
		(property "MPN" "CR0402-FX-1003GLF"
			(at 21.6 160 0)
			(layer "F.Fab")
			(hide yes)
			(effects
				(font
					(size 1 1)
					(thickness 0.15)
				)
			)
		)
		(property "Manufacturer" "Bourns"
			(at 21.6 160 0)
			(layer "F.Fab")
			(hide yes)
			(effects
				(font
					(size 1 1)
					(thickness 0.15)
				)
			)
		)
		(property "Tolerance" "1%"
			(at 21.6 160 0)
			(layer "F.Fab")
			(hide yes)
			(effects
				(font
					(size 1 1)
					(thickness 0.15)
				)
			)
		)
		(property "Val" "100k"
			(at 21.6 160 0)
			(layer "F.Fab")
			(hide yes)
			(effects
				(font
					(size 1 1)
					(thickness 0.15)
				)
			)
		)
		(sheetname "/SDI/")
		(sheetfile "sdi.kicad_sch")
		(attr smd)
		(fp_rect
			(start -0.925 -0.47)
			(end 0.925 0.47)
			(stroke
				(width 0.05)
				(type default)
			)
			(fill no)
			(layer "F.CrtYd")
		)
		(fp_rect
			(start -0.5 -0.25)
			(end 0.5 0.25)
			(stroke
				(width 0.15)
				(type solid)
			)
			(fill no)
			(layer "F.Fab")
		)
		(fp_text user "Author: Antmicro"
			(at -0.95 4.169 270)
			(layer "F.Fab")
			(effects
				(font
					(size 0.7 0.7)
					(thickness 0.15)
				)
				(justify left bottom)
			)
		)
		(fp_text user "${REFERENCE}"
			(at -0.95 3.168 270)
			(layer "F.Fab")
			(effects
				(font
					(size 0.7 0.7)
					(thickness 0.15)
				)
				(justify left bottom)
			)
		)
		(fp_text user "License: Apache-2.0"
			(at -0.95 5.169 270)
			(layer "F.Fab")
			(effects
				(font
					(size 0.7 0.7)
					(thickness 0.15)
				)
				(justify left bottom)
			)
		)
		(pad "1" smd roundrect
			(at -0.48 0 270)
			(size 0.59 0.64)
			(layers "F.Cu" "F.Mask" "F.Paste")
			(roundrect_rratio 0.25)
			(net 2 "+3V3")
			(pintype "passive")
		)
		(pad "2" smd roundrect
			(at 0.48 0 270)
			(size 0.59 0.64)
			(layers "F.Cu" "F.Mask" "F.Paste")
			(roundrect_rratio 0.25)
			(net 288 "Net-(U15B-LB_CONT)")
			(pintype "passive")
		)
	)
	(footprint "antmicro-footprints:Conn_JST_SH_1x6_SM06B-SRSS-TB-LF-SN"
		(layer "F.Cu")
		(at 151.5 121.97)
		(property "Reference" "J9"
			(at 0 -3.15 0)
			(layer "F.SilkS")
			(effects
				(font
					(size 0.7 0.7)
					(thickness 0.15)
				)
				(justify left bottom)
			)
		)
		(property "Value" "JST_GH_1x6_SM06B-SRSS-TB-LF-SN"
			(at 0 3.7 0)
			(layer "F.Fab")
			(effects
				(font
					(size 0.7 0.7)
					(thickness 0.15)
				)
				(justify left bottom)
			)
		)
		(property "Datasheet" "https://www.jst-mfg.com/product/pdf/eng/eSH.pdf"
			(at 0 0 0)
			(layer "F.Fab")
			(hide yes)
			(effects
				(font
					(size 1.27 1.27)
					(thickness 0.15)
				)
			)
		)
		(property "Description" "Pin Header, Right Angle, Wire-to-Board, 1 mm, 1 Rows, 6 Contacts, Surface Mount Right Angle, SR"
			(at 0 0 0)
			(layer "F.Fab")
			(hide yes)
			(effects
				(font
					(size 1.27 1.27)
					(thickness 0.15)
				)
			)
		)
		(property "Author" "Antmicro"
			(at 0 0 0)
			(layer "F.Fab")
			(hide yes)
			(effects
				(font
					(size 1 1)
					(thickness 0.15)
				)
			)
		)
		(property "License" "Apache-2.0"
			(at 0 0 0)
			(layer "F.Fab")
			(hide yes)
			(effects
				(font
					(size 1 1)
					(thickness 0.15)
				)
			)
		)
		(property "MPN" "SM06B-SRSS-TB(LF)(SN)"
			(at 0 0 0)
			(layer "F.Fab")
			(hide yes)
			(effects
				(font
					(size 1 1)
					(thickness 0.15)
				)
			)
		)
		(property "Manufacturer" "JST Automotive Connectors"
			(at 0 0 0)
			(layer "F.Fab")
			(hide yes)
			(effects
				(font
					(size 1 1)
					(thickness 0.15)
				)
			)
		)
		(sheetname "/Peripherals/")
		(sheetfile "peripherals.kicad_sch")
		(attr smd)
		(fp_line
			(start -4.2 -1.9)
			(end -4.2 0.7)
			(stroke
				(width 0.15)
				(type solid)
			)
			(layer "F.SilkS")
		)
		(fp_line
			(start -3.1 -1.9)
			(end -4.2 -1.9)
			(stroke
				(width 0.15)
				(type solid)
			)
			(layer "F.SilkS")
		)
		(fp_line
			(start -2.9 2.6)
			(end 2.9 2.6)
			(stroke
				(width 0.15)
				(type solid)
			)
			(layer "F.SilkS")
		)
		(fp_line
			(start 3.1 -1.9)
			(end 4.2 -1.9)
			(stroke
				(width 0.15)
				(type solid)
			)
			(layer "F.SilkS")
		)
		(fp_line
			(start 4.2 -1.9)
			(end 4.2 0.7)
			(stroke
				(width 0.15)
				(type solid)
			)
			(layer "F.SilkS")
		)
		(fp_circle
			(center -3.2 -2.4)
			(end -3.15 -2.4)
			(stroke
				(width 0.15)
				(type solid)
			)
			(fill yes)
			(layer "F.SilkS")
		)
		(fp_rect
			(start -4.65 -3.12)
			(end 4.65 2.92)
			(stroke
				(width 0.05)
				(type solid)
			)
			(fill no)
			(layer "F.CrtYd")
		)
		(fp_rect
			(start -4 -2.475)
			(end 4 2.475)
			(stroke
				(width 0.15)
				(type solid)
			)
			(fill no)
			(layer "F.Fab")
		)
		(fp_text user "Author: Antmicro"
			(at -4.65 4.92 0)
			(layer "F.Fab")
			(effects
				(font
					(size 0.7 0.7)
					(thickness 0.15)
				)
				(justify left bottom)
			)
		)
		(fp_text user "License: Apache-2.0"
			(at -4.65 7.32 0)
			(layer "F.Fab")
			(effects
				(font
					(size 0.7 0.7)
					(thickness 0.15)
				)
				(justify left bottom)
			)
		)
		(fp_text user "${REFERENCE}"
			(at -4.65 6.12 0)
			(layer "F.Fab")
			(effects
				(font
					(size 0.7 0.7)
					(thickness 0.15)
				)
				(justify left bottom)
			)
		)
		(pad "1" smd roundrect
			(at -2.5 -2.1 180)
			(size 0.6 1.55)
			(layers "F.Cu" "F.Mask" "F.Paste")
			(roundrect_rratio 0.25)
			(net 331 "/Peripherals/3V3_MISC")
			(pintype "passive")
		)
		(pad "2" smd roundrect
			(at -1.5 -2.1 180)
			(size 0.6 1.55)
			(layers "F.Cu" "F.Mask" "F.Paste")
			(roundrect_rratio 0.25)
			(net 332 "GPIO0")
			(pintype "passive")
		)
		(pad "3" smd roundrect
			(at -0.5 -2.1 180)
			(size 0.6 1.55)
			(layers "F.Cu" "F.Mask" "F.Paste")
			(roundrect_rratio 0.25)
			(net 333 "GPIO1")
			(pintype "passive")
		)
		(pad "4" smd roundrect
			(at 0.5 -2.1 180)
			(size 0.6 1.55)
			(layers "F.Cu" "F.Mask" "F.Paste")
			(roundrect_rratio 0.25)
			(net 334 "GPIO2")
			(pintype "passive")
		)
		(pad "5" smd roundrect
			(at 1.5 -2.1 180)
			(size 0.6 1.55)
			(layers "F.Cu" "F.Mask" "F.Paste")
			(roundrect_rratio 0.25)
			(net 335 "GPIO3")
			(pintype "passive")
		)
		(pad "6" smd roundrect
			(at 2.5 -2.1 180)
			(size 0.6 1.55)
			(layers "F.Cu" "F.Mask" "F.Paste")
			(roundrect_rratio 0.25)
			(net 1 "GND")
			(pintype "passive")
		)
		(pad "MP" smd roundrect
			(at -3.8 1.775)
			(size 1.2 1.8)
			(layers "F.Cu" "F.Mask" "F.Paste")
			(roundrect_rratio 0.25)
			(net 1 "GND")
			(pintype "passive")
		)
		(pad "MP" smd roundrect
			(at 3.8 1.775)
			(size 1.2 1.8)
			(layers "F.Cu" "F.Mask" "F.Paste")
			(roundrect_rratio 0.25)
			(net 1 "GND")
			(pintype "passive")
		)
	)
	(footprint "antmicro-footprints:R_0402_1005Metric"
		(layer "F.Cu")
		(at 167.2 95.6)
		(descr "Resistor SMD 0402")
		(tags "resistor SMD 0402")
		(property "Reference" "R74"
			(at -3.67 0.34 0)
			(layer "F.SilkS")
			(effects
				(font
					(size 0.65 0.65)
					(thickness 0.15)
				)
				(justify left bottom)
			)
		)
		(property "Value" "R_0R_0402"
			(at 0 1.4 0)
			(layer "F.Fab")
			(hide yes)
			(effects
				(font
					(size 0.7 0.7)
					(thickness 0.15)
				)
				(justify left bottom)
			)
		)
		(property "Datasheet" "https://industrial.panasonic.com/cdbs/www-data/pdf/RDA0000/AOA0000C301.pdf"
			(at 0 0 0)
			(layer "F.Fab")
			(hide yes)
			(effects
				(font
					(size 1.27 1.27)
					(thickness 0.15)
				)
			)
		)
		(property "Description" "SMD Chip Resistor, Jumper, 0 ohm, 100 mW, 0402 [1005 Metric], Thick Film, General Purpose"
			(at 0 0 0)
			(layer "F.Fab")
			(hide yes)
			(effects
				(font
					(size 1.27 1.27)
					(thickness 0.15)
				)
			)
		)
		(property "Author" "Antmicro"
			(at 0 0 0)
			(layer "F.Fab")
			(hide yes)
			(effects
				(font
					(size 1 1)
					(thickness 0.15)
				)
			)
		)
		(property "Current" "1A"
			(at 0 0 0)
			(layer "F.Fab")
			(hide yes)
			(effects
				(font
					(size 1 1)
					(thickness 0.15)
				)
			)
		)
		(property "License" "Apache-2.0"
			(at 0 0 0)
			(layer "F.Fab")
			(hide yes)
			(effects
				(font
					(size 1 1)
					(thickness 0.15)
				)
			)
		)
		(property "MPN" "ERJ2GE0R00X"
			(at 0 0 0)
			(layer "F.Fab")
			(hide yes)
			(effects
				(font
					(size 1 1)
					(thickness 0.15)
				)
			)
		)
		(property "Manufacturer" "Panasonic"
			(at 0 0 0)
			(layer "F.Fab")
			(hide yes)
			(effects
				(font
					(size 1 1)
					(thickness 0.15)
				)
			)
		)
		(property "Tolerance" "~"
			(at 0 0 0)
			(layer "F.Fab")
			(hide yes)
			(effects
				(font
					(size 1 1)
					(thickness 0.15)
				)
			)
		)
		(property "Val" "0R"
			(at 0 0 0)
			(layer "F.Fab")
			(hide yes)
			(effects
				(font
					(size 1 1)
					(thickness 0.15)
				)
			)
		)
		(sheetname "/Peripherals/")
		(sheetfile "peripherals.kicad_sch")
		(attr smd)
		(fp_rect
			(start -0.925 -0.47)
			(end 0.925 0.47)
			(stroke
				(width 0.05)
				(type default)
			)
			(fill no)
			(layer "F.CrtYd")
		)
		(fp_rect
			(start -0.5 -0.25)
			(end 0.5 0.25)
			(stroke
				(width 0.15)
				(type solid)
			)
			(fill no)
			(layer "F.Fab")
		)
		(fp_text user "${REFERENCE}"
			(at -0.95 3.168 0)
			(layer "F.Fab")
			(effects
				(font
					(size 0.7 0.7)
					(thickness 0.15)
				)
				(justify left bottom)
			)
		)
		(fp_text user "License: Apache-2.0"
			(at -0.95 5.169 0)
			(layer "F.Fab")
			(effects
				(font
					(size 0.7 0.7)
					(thickness 0.15)
				)
				(justify left bottom)
			)
		)
		(fp_text user "Author: Antmicro"
			(at -0.95 4.169 0)
			(layer "F.Fab")
			(effects
				(font
					(size 0.7 0.7)
					(thickness 0.15)
				)
				(justify left bottom)
			)
		)
		(pad "1" smd roundrect
			(at -0.48 0)
			(size 0.59 0.64)
			(layers "F.Cu" "F.Mask" "F.Paste")
			(roundrect_rratio 0.25)
			(net 89 "/Peripherals/FFC1_RESET")
			(pintype "passive")
		)
		(pad "2" smd roundrect
			(at 0.48 0)
			(size 0.59 0.64)
			(layers "F.Cu" "F.Mask" "F.Paste")
			(roundrect_rratio 0.25)
			(net 336 "Net-(J4-Pad33)")
			(pintype "passive")
		)
	)
	(footprint "antmicro-footprints:SOT-23-5"
		(layer "F.Cu")
		(at 143.14 115.45 180)
		(property "Reference" "U9"
			(at -1.49 -2.89 0)
			(layer "F.SilkS")
			(effects
				(font
					(size 0.65 0.65)
					(thickness 0.15)
				)
				(justify right bottom)
			)
		)
		(property "Value" "AP7330-W5-7"
			(at 0.002 2.799 0)
			(layer "F.Fab")
			(hide yes)
			(effects
				(font
					(size 0.7 0.7)
					(thickness 0.15)
				)
				(justify right bottom)
			)
		)
		(property "Datasheet" "https://www.diodes.com/assets/Datasheets/AP7330.pdf"
			(at 0 0 180)
			(layer "F.Fab")
			(hide yes)
			(effects
				(font
					(size 1.27 1.27)
					(thickness 0.15)
				)
			)
		)
		(property "Description" "Voltage regulator"
			(at 0 0 180)
			(layer "F.Fab")
			(hide yes)
			(effects
				(font
					(size 1.27 1.27)
					(thickness 0.15)
				)
			)
		)
		(property "Author" "Antmicro"
			(at 286.28 230.9 0)
			(layer "F.Fab")
			(hide yes)
			(effects
				(font
					(size 1 1)
					(thickness 0.15)
				)
			)
		)
		(property "License" "Apache-2.0"
			(at 286.28 230.9 0)
			(layer "F.Fab")
			(hide yes)
			(effects
				(font
					(size 1 1)
					(thickness 0.15)
				)
			)
		)
		(property "MPN" "AP7330-W5-7"
			(at 286.28 230.9 0)
			(layer "F.Fab")
			(hide yes)
			(effects
				(font
					(size 1 1)
					(thickness 0.15)
				)
			)
		)
		(property "Manufacturer" "Diodes Incorporated"
			(at 286.28 230.9 0)
			(layer "F.Fab")
			(hide yes)
			(effects
				(font
					(size 1 1)
					(thickness 0.15)
				)
			)
		)
		(sheetname "/Power Supply/")
		(sheetfile "supply.kicad_sch")
		(attr smd)
		(fp_line
			(start 0.8 1.599)
			(end 0.549 1.599)
			(stroke
				(width 0.15)
				(type solid)
			)
			(layer "F.SilkS")
		)
		(fp_line
			(start 0.8 1.3)
			(end 0.8 1.599)
			(stroke
				(width 0.15)
				(type solid)
			)
			(layer "F.SilkS")
		)
		(fp_line
			(start 0.8 0.55)
			(end 0.8 -0.55)
			(stroke
				(width 0.15)
				(type solid)
			)
			(layer "F.SilkS")
		)
		(fp_line
			(start 0.8 -1.3)
			(end 0.8 -1.6)
			(stroke
				(width 0.15)
				(type solid)
			)
			(layer "F.SilkS")
		)
		(fp_line
			(start 0.8 -1.6)
			(end 0.5 -1.6)
			(stroke
				(width 0.15)
				(type solid)
			)
			(layer "F.SilkS")
		)
		(fp_line
			(start -0.55 1.6)
			(end -0.85 1.6)
			(stroke
				(width 0.15)
				(type solid)
			)
			(layer "F.SilkS")
		)
		(fp_line
			(start -0.8 -1.6)
			(end -0.5 -1.6)
			(stroke
				(width 0.15)
				(type solid)
			)
			(layer "F.SilkS")
		)
		(fp_line
			(start -0.8 -1.6)
			(end -0.8 -1.3)
			(stroke
				(width 0.15)
				(type solid)
			)
			(layer "F.SilkS")
		)
		(fp_line
			(start -0.85 1.6)
			(end -0.85 1.301)
			(stroke
				(width 0.15)
				(type solid)
			)
			(layer "F.SilkS")
		)
		(fp_circle
			(center -1.25 -1.5)
			(end -1.2 -1.5)
			(stroke
				(width 0.15)
				(type solid)
			)
			(fill yes)
			(layer "F.SilkS")
		)
		(fp_rect
			(start 1.9 -1.76)
			(end -1.9 1.75)
			(stroke
				(width 0.05)
				(type solid)
			)
			(fill no)
			(layer "F.CrtYd")
		)
		(fp_line
			(start -0.398 -1.526)
			(end -0.874 -1.05)
			(stroke
				(width 0.15)
				(type solid)
			)
			(layer "F.Fab")
		)
		(fp_rect
			(start 0.874 1.523)
			(end -0.873 -1.525)
			(stroke
				(width 0.15)
				(type solid)
			)
			(fill no)
			(layer "F.Fab")
		)
		(pad "1" smd rect
			(at -1.351 -0.951 90)
			(size 0.55 1)
			(layers "F.Cu" "F.Mask" "F.Paste")
			(net 265 "Net-(U9-V_{IN})")
			(pinfunction "V_{IN}")
			(pintype "power_in")
		)
		(pad "2" smd rect
			(at -1.351 0 90)
			(size 0.55 1)
			(layers "F.Cu" "F.Mask" "F.Paste")
			(net 1 "GND")
			(pinfunction "GND")
			(pintype "power_in")
		)
		(pad "3" smd rect
			(at -1.351 0.949 90)
			(size 0.55 1)
			(layers "F.Cu" "F.Mask" "F.Paste")
			(net 269 "Net-(U9-EN)")
			(pinfunction "EN")
			(pintype "input")
		)
		(pad "4" smd rect
			(at 1.35 0.949 90)
			(size 0.55 1)
			(layers "F.Cu" "F.Mask" "F.Paste")
			(net 282 "Net-(U9-ADJ)")
			(pinfunction "ADJ")
			(pintype "passive")
		)
		(pad "5" smd rect
			(at 1.35 -0.951 90)
			(size 0.55 1)
			(layers "F.Cu" "F.Mask" "F.Paste")
			(net 279 "Net-(U9-V_{OUT})")
			(pinfunction "V_{OUT}")
			(pintype "power_out")
		)
	)
	(footprint "antmicro-footprints:R_0603_1608Metric"
		(layer "F.Cu")
		(at 158.29 79.7)
		(descr "Resistor SMD 0603")
		(tags "resistor SMD 0603")
		(property "Reference" "R113"
			(at -4.06 0.54 0)
			(layer "F.SilkS")
			(effects
				(font
					(size 0.65 0.65)
					(thickness 0.15)
				)
				(justify left bottom)
			)
		)
		(property "Value" "R_10k_0603"
			(at 0 1.6 0)
			(layer "F.Fab")
			(hide yes)
			(effects
				(font
					(size 0.7 0.7)
					(thickness 0.15)
				)
				(justify left bottom)
			)
		)
		(property "Datasheet" "https://www.bourns.com/docs/product-datasheets/cr.pdf"
			(at 0 0 0)
			(layer "F.Fab")
			(hide yes)
			(effects
				(font
					(size 1.27 1.27)
					(thickness 0.15)
				)
			)
		)
		(property "Description" "SMD Chip Resistor, 10 kohm, ± 1%, 100 mW, 0603 [1608 Metric], Thick Film, General Purpose"
			(at 0 0 0)
			(layer "F.Fab")
			(hide yes)
			(effects
				(font
					(size 1.27 1.27)
					(thickness 0.15)
				)
			)
		)
		(property "Author" "Antmicro"
			(at 0 0 0)
			(layer "F.Fab")
			(hide yes)
			(effects
				(font
					(size 1 1)
					(thickness 0.15)
				)
			)
		)
		(property "License" "Apache-2.0"
			(at 0 0 0)
			(layer "F.Fab")
			(hide yes)
			(effects
				(font
					(size 1 1)
					(thickness 0.15)
				)
			)
		)
		(property "MPN" "CR0603-FX-1002ELF"
			(at 0 0 0)
			(layer "F.Fab")
			(hide yes)
			(effects
				(font
					(size 1 1)
					(thickness 0.15)
				)
			)
		)
		(property "Manufacturer" "Bourns"
			(at 0 0 0)
			(layer "F.Fab")
			(hide yes)
			(effects
				(font
					(size 1 1)
					(thickness 0.15)
				)
			)
		)
		(property "Tolerance" "1%"
			(at 0 0 0)
			(layer "F.Fab")
			(hide yes)
			(effects
				(font
					(size 1 1)
					(thickness 0.15)
				)
			)
		)
		(property "Val" "10k"
			(at 0 0 0)
			(layer "F.Fab")
			(hide yes)
			(effects
				(font
					(size 1 1)
					(thickness 0.15)
				)
			)
		)
		(sheetname "/Peripherals/")
		(sheetfile "peripherals.kicad_sch")
		(attr smd)
		(fp_line
			(start -0.15 -0.4)
			(end 0.15 -0.4)
			(stroke
				(width 0.15)
				(type solid)
			)
			(layer "F.SilkS")
		)
		(fp_line
			(start -0.15 0.4)
			(end 0.15 0.4)
			(stroke
				(width 0.15)
				(type solid)
			)
			(layer "F.SilkS")
		)
		(fp_rect
			(start -1.25 -0.65)
			(end 1.25 0.65)
			(stroke
				(width 0.05)
				(type solid)
			)
			(fill no)
			(layer "F.CrtYd")
		)
		(fp_rect
			(start -0.8 -0.4)
			(end 0.8 0.4)
			(stroke
				(width 0.15)
				(type solid)
			)
			(fill no)
			(layer "F.Fab")
		)
		(fp_text user "Author: Antmicro"
			(at -1.25 4.9 0)
			(layer "F.Fab")
			(effects
				(font
					(size 0.7 0.7)
					(thickness 0.15)
				)
				(justify left bottom)
			)
		)
		(fp_text user "License: Apache-2.0"
			(at -1.25 5.9 0)
			(layer "F.Fab")
			(effects
				(font
					(size 0.7 0.7)
					(thickness 0.15)
				)
				(justify left bottom)
			)
		)
		(fp_text user "${REFERENCE}"
			(at -1.25 3.898 0)
			(layer "F.Fab")
			(effects
				(font
					(size 0.7 0.7)
					(thickness 0.15)
				)
				(justify left bottom)
			)
		)
		(pad "1" smd roundrect
			(at -0.7 0)
			(size 0.8 1)
			(layers "F.Cu" "F.Mask" "F.Paste")
			(roundrect_rratio 0.2)
			(net 2 "+3V3")
			(pintype "passive")
		)
		(pad "2" smd roundrect
			(at 0.7 0)
			(size 0.8 1)
			(layers "F.Cu" "F.Mask" "F.Paste")
			(roundrect_rratio 0.2)
			(net 314 "/Peripherals/QW_FLT")
			(pintype "passive")
		)
	)
	(footprint "antmicro-footprints:C_0402_1005Metric"
		(layer "F.Cu")
		(at 88.5 76.4 180)
		(descr "Capacitor SMD 0402")
		(tags "capacitor SMD 0402")
		(property "Reference" "C54"
			(at 0.42 6.26 0)
			(layer "F.SilkS")
			(effects
				(font
					(size 0.65 0.65)
					(thickness 0.15)
				)
				(justify right bottom)
			)
		)
		(property "Value" "C_1u_0402"
			(at 0 1.4 0)
			(layer "F.Fab")
			(hide yes)
			(effects
				(font
					(size 0.7 0.7)
					(thickness 0.15)
				)
				(justify right bottom)
			)
		)
		(property "Datasheet" "https://product.tdk.com/en/search/capacitor/ceramic/mlcc/info?part_no=C1005X6S1A105K050BC"
			(at 0 0 180)
			(layer "F.Fab")
			(hide yes)
			(effects
				(font
					(size 1.27 1.27)
					(thickness 0.15)
				)
			)
		)
		(property "Description" "SMD Multilayer Ceramic Capacitor, 1 µF, 10 V, 0402 [1005 Metric], ± 10%, X6S, C"
			(at 0 0 180)
			(layer "F.Fab")
			(hide yes)
			(effects
				(font
					(size 1.27 1.27)
					(thickness 0.15)
				)
			)
		)
		(property "Author" "Antmicro"
			(at 177 152.8 0)
			(layer "F.Fab")
			(hide yes)
			(effects
				(font
					(size 1 1)
					(thickness 0.15)
				)
			)
		)
		(property "Dielectric" ""
			(at 177 152.8 0)
			(layer "F.Fab")
			(hide yes)
			(effects
				(font
					(size 1 1)
					(thickness 0.15)
				)
			)
		)
		(property "License" "Apache-2.0"
			(at 177 152.8 0)
			(layer "F.Fab")
			(hide yes)
			(effects
				(font
					(size 1 1)
					(thickness 0.15)
				)
			)
		)
		(property "MPN" "C1005X6S1A105K050BC"
			(at 177 152.8 0)
			(layer "F.Fab")
			(hide yes)
			(effects
				(font
					(size 1 1)
					(thickness 0.15)
				)
			)
		)
		(property "Manufacturer" "TDK"
			(at 177 152.8 0)
			(layer "F.Fab")
			(hide yes)
			(effects
				(font
					(size 1 1)
					(thickness 0.15)
				)
			)
		)
		(property "Val" "1u"
			(at 177 152.8 0)
			(layer "F.Fab")
			(hide yes)
			(effects
				(font
					(size 1 1)
					(thickness 0.15)
				)
			)
		)
		(property "Voltage" ""
			(at 177 152.8 0)
			(layer "F.Fab")
			(hide yes)
			(effects
				(font
					(size 1 1)
					(thickness 0.15)
				)
			)
		)
		(sheetname "/SDI/")
		(sheetfile "sdi.kicad_sch")
		(attr smd)
		(fp_rect
			(start -0.925 -0.47)
			(end 0.925 0.47)
			(stroke
				(width 0.05)
				(type default)
			)
			(fill no)
			(layer "F.CrtYd")
		)
		(fp_line
			(start 0.504 0.248)
			(end -0.494 0.248)
			(stroke
				(width 0.15)
				(type solid)
			)
			(layer "F.Fab")
		)
		(fp_line
			(start 0.504 -0.25)
			(end 0.504 0.248)
			(stroke
				(width 0.15)
				(type solid)
			)
			(layer "F.Fab")
		)
		(fp_line
			(start -0.494 0.248)
			(end -0.494 -0.25)
			(stroke
				(width 0.15)
				(type solid)
			)
			(layer "F.Fab")
		)
		(fp_line
			(start -0.494 -0.25)
			(end 0.504 -0.25)
			(stroke
				(width 0.15)
				(type solid)
			)
			(layer "F.Fab")
		)
		(fp_text user "Author: Antmicro"
			(at -0.939 3.399 180)
			(layer "F.Fab")
			(effects
				(font
					(size 0.7 0.7)
					(thickness 0.15)
				)
				(justify left bottom)
			)
		)
		(fp_text user "License: Apache-2.0"
			(at -0.939 5.799 180)
			(layer "F.Fab")
			(effects
				(font
					(size 0.7 0.7)
					(thickness 0.15)
				)
				(justify left bottom)
			)
		)
		(fp_text user "${REFERENCE}"
			(at -0.939 4.599 180)
			(layer "F.Fab")
			(effects
				(font
					(size 0.7 0.7)
					(thickness 0.15)
				)
				(justify left bottom)
			)
		)
		(pad "1" smd roundrect
			(at -0.48 0 180)
			(size 0.59 0.64)
			(layers "F.Cu" "F.Mask" "F.Paste")
			(roundrect_rratio 0.25)
			(net 8 "/SDI/SDI_N")
			(pintype "passive")
		)
		(pad "2" smd roundrect
			(at 0.48 0 180)
			(size 0.59 0.64)
			(layers "F.Cu" "F.Mask" "F.Paste")
			(roundrect_rratio 0.25)
			(net 293 "/SDI/SDI_N2")
			(pintype "passive")
		)
	)
	(footprint "antmicro-footprints:C_0402_1005Metric"
		(layer "F.Cu")
		(at 160.69 80.585 -90)
		(descr "Capacitor SMD 0402")
		(tags "capacitor SMD 0402")
		(property "Reference" "C113"
			(at 0.855 -0.14 90)
			(layer "F.SilkS")
			(effects
				(font
					(size 0.65 0.65)
					(thickness 0.15)
				)
				(justify right bottom)
			)
		)
		(property "Value" "C_100n_0402"
			(at 0 1.4 90)
			(layer "F.Fab")
			(hide yes)
			(effects
				(font
					(size 0.7 0.7)
					(thickness 0.15)
				)
				(justify right bottom)
			)
		)
		(property "Datasheet" "https://www.murata.com/products/productdetail?partno=GRM155R61H104KE14%23"
			(at 0 0 270)
			(layer "F.Fab")
			(hide yes)
			(effects
				(font
					(size 1.27 1.27)
					(thickness 0.15)
				)
			)
		)
		(property "Description" "SMD Multilayer Ceramic Capacitor, 0.1 µF, 50 V, 0402 [1005 Metric], ± 10%, X5R, GRM Series"
			(at 0 0 270)
			(layer "F.Fab")
			(hide yes)
			(effects
				(font
					(size 1.27 1.27)
					(thickness 0.15)
				)
			)
		)
		(property "Author" "Antmicro"
			(at 80.105 241.275 0)
			(layer "F.Fab")
			(hide yes)
			(effects
				(font
					(size 1 1)
					(thickness 0.15)
				)
			)
		)
		(property "Dielectric" "X5R"
			(at 80.105 241.275 0)
			(layer "F.Fab")
			(hide yes)
			(effects
				(font
					(size 1 1)
					(thickness 0.15)
				)
			)
		)
		(property "License" "Apache-2.0"
			(at 80.105 241.275 0)
			(layer "F.Fab")
			(hide yes)
			(effects
				(font
					(size 1 1)
					(thickness 0.15)
				)
			)
		)
		(property "MPN" "GRM155R61H104KE14D"
			(at 80.105 241.275 0)
			(layer "F.Fab")
			(hide yes)
			(effects
				(font
					(size 1 1)
					(thickness 0.15)
				)
			)
		)
		(property "Manufacturer" "Murata"
			(at 80.105 241.275 0)
			(layer "F.Fab")
			(hide yes)
			(effects
				(font
					(size 1 1)
					(thickness 0.15)
				)
			)
		)
		(property "Val" "100n"
			(at 80.105 241.275 0)
			(layer "F.Fab")
			(hide yes)
			(effects
				(font
					(size 1 1)
					(thickness 0.15)
				)
			)
		)
		(property "Voltage" "50V"
			(at 80.105 241.275 0)
			(layer "F.Fab")
			(hide yes)
			(effects
				(font
					(size 1 1)
					(thickness 0.15)
				)
			)
		)
		(sheetname "/Peripherals/")
		(sheetfile "peripherals.kicad_sch")
		(attr smd)
		(fp_rect
			(start -0.925 -0.47)
			(end 0.925 0.47)
			(stroke
				(width 0.05)
				(type default)
			)
			(fill no)
			(layer "F.CrtYd")
		)
		(fp_line
			(start -0.494 0.248)
			(end -0.494 -0.25)
			(stroke
				(width 0.15)
				(type solid)
			)
			(layer "F.Fab")
		)
		(fp_line
			(start 0.504 0.248)
			(end -0.494 0.248)
			(stroke
				(width 0.15)
				(type solid)
			)
			(layer "F.Fab")
		)
		(fp_line
			(start -0.494 -0.25)
			(end 0.504 -0.25)
			(stroke
				(width 0.15)
				(type solid)
			)
			(layer "F.Fab")
		)
		(fp_line
			(start 0.504 -0.25)
			(end 0.504 0.248)
			(stroke
				(width 0.15)
				(type solid)
			)
			(layer "F.Fab")
		)
		(fp_text user "License: Apache-2.0"
			(at -0.939 5.799 270)
			(layer "F.Fab")
			(effects
				(font
					(size 0.7 0.7)
					(thickness 0.15)
				)
				(justify left bottom)
			)
		)
		(fp_text user "${REFERENCE}"
			(at -0.939 4.599 270)
			(layer "F.Fab")
			(effects
				(font
					(size 0.7 0.7)
					(thickness 0.15)
				)
				(justify left bottom)
			)
		)
		(fp_text user "Author: Antmicro"
			(at -0.939 3.399 270)
			(layer "F.Fab")
			(effects
				(font
					(size 0.7 0.7)
					(thickness 0.15)
				)
				(justify left bottom)
			)
		)
		(pad "1" smd roundrect
			(at -0.48 0 270)
			(size 0.59 0.64)
			(layers "F.Cu" "F.Mask" "F.Paste")
			(roundrect_rratio 0.25)
			(net 1 "GND")
			(pintype "passive")
		)
		(pad "2" smd roundrect
			(at 0.48 0 270)
			(size 0.59 0.64)
			(layers "F.Cu" "F.Mask" "F.Paste")
			(roundrect_rratio 0.25)
			(net 2 "+3V3")
			(pintype "passive")
		)
	)
	(footprint "antmicro-footprints:C_0603_1608Metric"
		(layer "F.Cu")
		(at 145.21 62.52 180)
		(descr "Capacitor SMD 0603")
		(tags "capacitor 0603")
		(property "Reference" "C12"
			(at 0.51 0.5 180)
			(layer "F.SilkS")
			(effects
				(font
					(size 0.65 0.65)
					(thickness 0.15)
				)
				(justify left bottom)
			)
		)
		(property "Value" "C_10u_0603"
			(at 0 1.6 180)
			(layer "F.Fab")
			(hide yes)
			(effects
				(font
					(size 0.7 0.7)
					(thickness 0.15)
				)
				(justify left bottom)
			)
		)
		(property "Datasheet" "https://www.murata.com/products/productdetail?partno=GRM188R61A106KE69%23"
			(at 0 0 180)
			(layer "F.Fab")
			(hide yes)
			(effects
				(font
					(size 1.27 1.27)
					(thickness 0.15)
				)
			)
		)
		(property "Description" "SMD Multilayer Ceramic Capacitor, 10 µF, 10 V, 0603 [1608 Metric], ± 10%, X5R, GRM Series"
			(at 0 0 180)
			(layer "F.Fab")
			(hide yes)
			(effects
				(font
					(size 1.27 1.27)
					(thickness 0.15)
				)
			)
		)
		(property "Author" "Antmicro"
			(at 290.36 124.88 0)
			(layer "F.Fab")
			(hide yes)
			(effects
				(font
					(size 1 1)
					(thickness 0.15)
				)
			)
		)
		(property "License" "Apache-2.0"
			(at 290.36 124.88 0)
			(layer "F.Fab")
			(hide yes)
			(effects
				(font
					(size 1 1)
					(thickness 0.15)
				)
			)
		)
		(property "MPN" "GRM188R61A106KE69D"
			(at 290.36 124.88 0)
			(layer "F.Fab")
			(hide yes)
			(effects
				(font
					(size 1 1)
					(thickness 0.15)
				)
			)
		)
		(property "Manufacturer" "Murata"
			(at 290.36 124.88 0)
			(layer "F.Fab")
			(hide yes)
			(effects
				(font
					(size 1 1)
					(thickness 0.15)
				)
			)
		)
		(property "Val" "10u"
			(at 290.36 124.88 0)
			(layer "F.Fab")
			(hide yes)
			(effects
				(font
					(size 1 1)
					(thickness 0.15)
				)
			)
		)
		(property "Voltage" ""
			(at 290.36 124.88 0)
			(layer "F.Fab")
			(hide yes)
			(effects
				(font
					(size 1 1)
					(thickness 0.15)
				)
			)
		)
		(property "Dielectric" "template_dielectric"
			(at 0 0 180)
			(unlocked yes)
			(layer "F.Fab")
			(hide yes)
			(effects
				(font
					(size 1 1)
					(thickness 0.15)
				)
			)
		)
		(sheetname "/Power Supply/")
		(sheetfile "supply.kicad_sch")
		(attr smd)
		(fp_line
			(start -0.15 0.4)
			(end 0.15 0.4)
			(stroke
				(width 0.15)
				(type solid)
			)
			(layer "F.SilkS")
		)
		(fp_line
			(start -0.15 -0.4)
			(end 0.15 -0.4)
			(stroke
				(width 0.15)
				(type solid)
			)
			(layer "F.SilkS")
		)
		(fp_rect
			(start -1.25 -0.65)
			(end 1.25 0.65)
			(stroke
				(width 0.05)
				(type solid)
			)
			(fill no)
			(layer "F.CrtYd")
		)
		(fp_rect
			(start -0.8 -0.4)
			(end 0.8 0.4)
			(stroke
				(width 0.15)
				(type solid)
			)
			(fill no)
			(layer "F.Fab")
		)
		(fp_text user "${REFERENCE}"
			(at -1.682 3.895 180)
			(layer "F.Fab")
			(effects
				(font
					(size 0.7 0.7)
					(thickness 0.15)
				)
				(justify left bottom)
			)
		)
		(fp_text user "License: Apache-2.0"
			(at -1.682 5.895 180)
			(layer "F.Fab")
			(effects
				(font
					(size 0.7 0.7)
					(thickness 0.15)
				)
				(justify left bottom)
			)
		)
		(fp_text user "Author: Antmicro"
			(at -1.682 4.894 180)
			(layer "F.Fab")
			(effects
				(font
					(size 0.7 0.7)
					(thickness 0.15)
				)
				(justify left bottom)
			)
		)
		(pad "1" smd roundrect
			(at -0.7 0 180)
			(size 0.8 1)
			(layers "F.Cu" "F.Mask" "F.Paste")
			(roundrect_rratio 0.2)
			(net 327 "/Power Supply/5V_1V5_IN")
			(pintype "passive")
		)
		(pad "2" smd roundrect
			(at 0.7 0 180)
			(size 0.8 1)
			(layers "F.Cu" "F.Mask" "F.Paste")
			(roundrect_rratio 0.2)
			(net 1 "GND")
			(pintype "passive")
		)
	)
	(footprint "antmicro-footprints:R_0402_1005Metric"
		(layer "F.Cu")
		(at 110.79 100.4)
		(descr "Resistor SMD 0402")
		(tags "resistor SMD 0402")
		(property "Reference" "R78"
			(at 0.94 0.44 0)
			(layer "F.SilkS")
			(effects
				(font
					(size 0.65 0.65)
					(thickness 0.15)
				)
				(justify left bottom)
			)
		)
		(property "Value" "R_0R_0402"
			(at 0 1.4 0)
			(layer "F.Fab")
			(hide yes)
			(effects
				(font
					(size 0.7 0.7)
					(thickness 0.15)
				)
				(justify left bottom)
			)
		)
		(property "Datasheet" "https://industrial.panasonic.com/cdbs/www-data/pdf/RDA0000/AOA0000C301.pdf"
			(at 0 0 0)
			(layer "F.Fab")
			(hide yes)
			(effects
				(font
					(size 1.27 1.27)
					(thickness 0.15)
				)
			)
		)
		(property "Description" "SMD Chip Resistor, Jumper, 0 ohm, 100 mW, 0402 [1005 Metric], Thick Film, General Purpose"
			(at 0 0 0)
			(layer "F.Fab")
			(hide yes)
			(effects
				(font
					(size 1.27 1.27)
					(thickness 0.15)
				)
			)
		)
		(property "Author" "Antmicro"
			(at 0 0 0)
			(layer "F.Fab")
			(hide yes)
			(effects
				(font
					(size 1 1)
					(thickness 0.15)
				)
			)
		)
		(property "Current" "1A"
			(at 0 0 0)
			(layer "F.Fab")
			(hide yes)
			(effects
				(font
					(size 1 1)
					(thickness 0.15)
				)
			)
		)
		(property "License" "Apache-2.0"
			(at 0 0 0)
			(layer "F.Fab")
			(hide yes)
			(effects
				(font
					(size 1 1)
					(thickness 0.15)
				)
			)
		)
		(property "MPN" "ERJ2GE0R00X"
			(at 0 0 0)
			(layer "F.Fab")
			(hide yes)
			(effects
				(font
					(size 1 1)
					(thickness 0.15)
				)
			)
		)
		(property "Manufacturer" "Panasonic"
			(at 0 0 0)
			(layer "F.Fab")
			(hide yes)
			(effects
				(font
					(size 1 1)
					(thickness 0.15)
				)
			)
		)
		(property "Tolerance" "~"
			(at 0 0 0)
			(layer "F.Fab")
			(hide yes)
			(effects
				(font
					(size 1 1)
					(thickness 0.15)
				)
			)
		)
		(property "Val" "0R"
			(at 0 0 0)
			(layer "F.Fab")
			(hide yes)
			(effects
				(font
					(size 1 1)
					(thickness 0.15)
				)
			)
		)
		(sheetname "/FPGA/")
		(sheetfile "fpga.kicad_sch")
		(attr smd)
		(fp_rect
			(start -0.925 -0.47)
			(end 0.925 0.47)
			(stroke
				(width 0.05)
				(type default)
			)
			(fill no)
			(layer "F.CrtYd")
		)
		(fp_rect
			(start -0.5 -0.25)
			(end 0.5 0.25)
			(stroke
				(width 0.15)
				(type solid)
			)
			(fill no)
			(layer "F.Fab")
		)
		(fp_text user "Author: Antmicro"
			(at -0.95 4.169 0)
			(layer "F.Fab")
			(effects
				(font
					(size 0.7 0.7)
					(thickness 0.15)
				)
				(justify left bottom)
			)
		)
		(fp_text user "${REFERENCE}"
			(at -0.95 3.168 0)
			(layer "F.Fab")
			(effects
				(font
					(size 0.7 0.7)
					(thickness 0.15)
				)
				(justify left bottom)
			)
		)
		(fp_text user "License: Apache-2.0"
			(at -0.95 5.169 0)
			(layer "F.Fab")
			(effects
				(font
					(size 0.7 0.7)
					(thickness 0.15)
				)
				(justify left bottom)
			)
		)
		(pad "1" smd roundrect
			(at -0.48 0)
			(size 0.59 0.64)
			(layers "F.Cu" "F.Mask" "F.Paste")
			(roundrect_rratio 0.25)
			(net 308 "Net-(U17-A2)")
			(pintype "passive")
		)
		(pad "2" smd roundrect
			(at 0.48 0)
			(size 0.59 0.64)
			(layers "F.Cu" "F.Mask" "F.Paste")
			(roundrect_rratio 0.25)
			(net 1 "GND")
			(pintype "passive")
		)
	)
	(footprint "antmicro-footprints:R_0603_1608Metric"
		(layer "F.Cu")
		(at 165.63 116.35 90)
		(descr "Resistor SMD 0603")
		(tags "resistor SMD 0603")
		(property "Reference" "R111"
			(at 1.21 0.4 90)
			(layer "F.SilkS")
			(effects
				(font
					(size 0.65 0.65)
					(thickness 0.15)
				)
				(justify left bottom)
			)
		)
		(property "Value" "R_200R_0603"
			(at 0 1.6 90)
			(layer "F.Fab")
			(hide yes)
			(effects
				(font
					(size 0.7 0.7)
					(thickness 0.15)
				)
				(justify left bottom)
			)
		)
		(property "Datasheet" "https://www.bourns.com/docs/product-datasheets/cr.pdf"
			(at 0 0 90)
			(layer "F.Fab")
			(hide yes)
			(effects
				(font
					(size 1.27 1.27)
					(thickness 0.15)
				)
			)
		)
		(property "Description" "SMD Chip Resistor, 200 ohm, ± 1%, 100 mW, 0603 [1608 Metric], Thick Film, General Purpose"
			(at 0 0 90)
			(layer "F.Fab")
			(hide yes)
			(effects
				(font
					(size 1.27 1.27)
					(thickness 0.15)
				)
			)
		)
		(property "Author" "Antmicro"
			(at 281.98 -49.28 0)
			(layer "F.Fab")
			(hide yes)
			(effects
				(font
					(size 1 1)
					(thickness 0.15)
				)
			)
		)
		(property "License" "Apache-2.0"
			(at 281.98 -49.28 0)
			(layer "F.Fab")
			(hide yes)
			(effects
				(font
					(size 1 1)
					(thickness 0.15)
				)
			)
		)
		(property "MPN" "CR0603-FX-2000ELF"
			(at 281.98 -49.28 0)
			(layer "F.Fab")
			(hide yes)
			(effects
				(font
					(size 1 1)
					(thickness 0.15)
				)
			)
		)
		(property "Manufacturer" "Bourns"
			(at 281.98 -49.28 0)
			(layer "F.Fab")
			(hide yes)
			(effects
				(font
					(size 1 1)
					(thickness 0.15)
				)
			)
		)
		(property "Tolerance" "1%"
			(at 281.98 -49.28 0)
			(layer "F.Fab")
			(hide yes)
			(effects
				(font
					(size 1 1)
					(thickness 0.15)
				)
			)
		)
		(property "Val" "200R"
			(at 281.98 -49.28 0)
			(layer "F.Fab")
			(hide yes)
			(effects
				(font
					(size 1 1)
					(thickness 0.15)
				)
			)
		)
		(sheetname "/Peripherals/")
		(sheetfile "peripherals.kicad_sch")
		(attr smd)
		(fp_line
			(start -0.15 -0.4)
			(end 0.15 -0.4)
			(stroke
				(width 0.15)
				(type solid)
			)
			(layer "F.SilkS")
		)
		(fp_line
			(start -0.15 0.4)
			(end 0.15 0.4)
			(stroke
				(width 0.15)
				(type solid)
			)
			(layer "F.SilkS")
		)
		(fp_rect
			(start -1.25 -0.65)
			(end 1.25 0.65)
			(stroke
				(width 0.05)
				(type solid)
			)
			(fill no)
			(layer "F.CrtYd")
		)
		(fp_rect
			(start -0.8 -0.4)
			(end 0.8 0.4)
			(stroke
				(width 0.15)
				(type solid)
			)
			(fill no)
			(layer "F.Fab")
		)
		(fp_text user "${REFERENCE}"
			(at -1.25 3.898 90)
			(layer "F.Fab")
			(effects
				(font
					(size 0.7 0.7)
					(thickness 0.15)
				)
				(justify left bottom)
			)
		)
		(fp_text user "Author: Antmicro"
			(at -1.25 4.9 90)
			(layer "F.Fab")
			(effects
				(font
					(size 0.7 0.7)
					(thickness 0.15)
				)
				(justify left bottom)
			)
		)
		(fp_text user "License: Apache-2.0"
			(at -1.25 5.9 90)
			(layer "F.Fab")
			(effects
				(font
					(size 0.7 0.7)
					(thickness 0.15)
				)
				(justify left bottom)
			)
		)
		(pad "1" smd roundrect
			(at -0.7 0 90)
			(size 0.8 1)
			(layers "F.Cu" "F.Mask" "F.Paste")
			(roundrect_rratio 0.2)
			(net 63 "Net-(D3-A)")
			(pintype "passive")
		)
		(pad "2" smd roundrect
			(at 0.7 0 90)
			(size 0.8 1)
			(layers "F.Cu" "F.Mask" "F.Paste")
			(roundrect_rratio 0.2)
			(net 34 "LED1")
			(pintype "passive")
		)
	)
	(footprint "antmicro-footprints:R_0603_1608Metric"
		(layer "F.Cu")
		(at 157.03 88.65 -90)
		(descr "Resistor SMD 0603")
		(tags "resistor SMD 0603")
		(property "Reference" "R106"
			(at -1.21 -1.9 270)
			(layer "F.SilkS")
			(effects
				(font
					(size 0.65 0.65)
					(thickness 0.15)
				)
				(justify left bottom)
			)
		)
		(property "Value" "R_10k_0603"
			(at 0 1.6 270)
			(layer "F.Fab")
			(hide yes)
			(effects
				(font
					(size 0.7 0.7)
					(thickness 0.15)
				)
				(justify left bottom)
			)
		)
		(property "Datasheet" "https://www.bourns.com/docs/product-datasheets/cr.pdf"
			(at 0 0 270)
			(layer "F.Fab")
			(hide yes)
			(effects
				(font
					(size 1.27 1.27)
					(thickness 0.15)
				)
			)
		)
		(property "Description" "SMD Chip Resistor, 10 kohm, ± 1%, 100 mW, 0603 [1608 Metric], Thick Film, General Purpose"
			(at 0 0 270)
			(layer "F.Fab")
			(hide yes)
			(effects
				(font
					(size 1.27 1.27)
					(thickness 0.15)
				)
			)
		)
		(property "Author" "Antmicro"
			(at 68.38 245.68 0)
			(layer "F.Fab")
			(hide yes)
			(effects
				(font
					(size 1 1)
					(thickness 0.15)
				)
			)
		)
		(property "License" "Apache-2.0"
			(at 68.38 245.68 0)
			(layer "F.Fab")
			(hide yes)
			(effects
				(font
					(size 1 1)
					(thickness 0.15)
				)
			)
		)
		(property "MPN" "CR0603-FX-1002ELF"
			(at 68.38 245.68 0)
			(layer "F.Fab")
			(hide yes)
			(effects
				(font
					(size 1 1)
					(thickness 0.15)
				)
			)
		)
		(property "Manufacturer" "Bourns"
			(at 68.38 245.68 0)
			(layer "F.Fab")
			(hide yes)
			(effects
				(font
					(size 1 1)
					(thickness 0.15)
				)
			)
		)
		(property "Tolerance" "1%"
			(at 68.38 245.68 0)
			(layer "F.Fab")
			(hide yes)
			(effects
				(font
					(size 1 1)
					(thickness 0.15)
				)
			)
		)
		(property "Val" "10k"
			(at 68.38 245.68 0)
			(layer "F.Fab")
			(hide yes)
			(effects
				(font
					(size 1 1)
					(thickness 0.15)
				)
			)
		)
		(sheetname "/Peripherals/")
		(sheetfile "peripherals.kicad_sch")
		(attr smd exclude_from_pos_files exclude_from_bom dnp)
		(fp_line
			(start -0.15 0.4)
			(end 0.15 0.4)
			(stroke
				(width 0.15)
				(type solid)
			)
			(layer "F.SilkS")
		)
		(fp_line
			(start -0.15 -0.4)
			(end 0.15 -0.4)
			(stroke
				(width 0.15)
				(type solid)
			)
			(layer "F.SilkS")
		)
		(fp_rect
			(start -1.25 -0.65)
			(end 1.25 0.65)
			(stroke
				(width 0.05)
				(type solid)
			)
			(fill no)
			(layer "F.CrtYd")
		)
		(fp_rect
			(start -0.8 -0.4)
			(end 0.8 0.4)
			(stroke
				(width 0.15)
				(type solid)
			)
			(fill no)
			(layer "F.Fab")
		)
		(fp_text user "${REFERENCE}"
			(at -1.25 3.898 270)
			(layer "F.Fab")
			(effects
				(font
					(size 0.7 0.7)
					(thickness 0.15)
				)
				(justify left bottom)
			)
		)
		(fp_text user "License: Apache-2.0"
			(at -1.25 5.9 270)
			(layer "F.Fab")
			(effects
				(font
					(size 0.7 0.7)
					(thickness 0.15)
				)
				(justify left bottom)
			)
		)
		(fp_text user "Author: Antmicro"
			(at -1.25 4.9 270)
			(layer "F.Fab")
			(effects
				(font
					(size 0.7 0.7)
					(thickness 0.15)
				)
				(justify left bottom)
			)
		)
		(pad "1" smd roundrect
			(at -0.7 0 270)
			(size 0.8 1)
			(layers "F.Cu" "F.Mask" "F.Paste")
			(roundrect_rratio 0.2)
			(net 307 "/Peripherals/FFC1_PEN")
			(pintype "passive")
		)
		(pad "2" smd roundrect
			(at 0.7 0 270)
			(size 0.8 1)
			(layers "F.Cu" "F.Mask" "F.Paste")
			(roundrect_rratio 0.2)
			(net 1 "GND")
			(pintype "passive")
		)
	)
	(footprint "antmicro-footprints:TP_SMD_0.75mm"
		(layer "F.Cu")
		(at 158.3 93.65)
		(property "Reference" "TP44"
			(at -1.37 1.39 0)
			(layer "F.SilkS")
			(effects
				(font
					(size 0.65 0.65)
					(thickness 0.15)
				)
				(justify left bottom)
			)
		)
		(property "Value" "TP_0.75mm_SMD"
			(at 0 1.2 0)
			(layer "F.Fab")
			(hide yes)
			(effects
				(font
					(size 0.7 0.7)
					(thickness 0.15)
				)
				(justify left bottom)
			)
		)
		(property "Description" "SMT test point"
			(at 0 0 0)
			(layer "F.Fab")
			(hide yes)
			(effects
				(font
					(size 1.27 1.27)
					(thickness 0.15)
				)
			)
		)
		(property "Author" "Antmicro"
			(at 0 0 0)
			(layer "F.Fab")
			(hide yes)
			(effects
				(font
					(size 1 1)
					(thickness 0.15)
				)
			)
		)
		(property "License" "Apache-2.0"
			(at 0 0 0)
			(layer "F.Fab")
			(hide yes)
			(effects
				(font
					(size 1 1)
					(thickness 0.15)
				)
			)
		)
		(property "MPN" ""
			(at 0 0 0)
			(layer "F.Fab")
			(hide yes)
			(effects
				(font
					(size 1 1)
					(thickness 0.15)
				)
			)
		)
		(property "Manufacturer" ""
			(at 0 0 0)
			(layer "F.Fab")
			(hide yes)
			(effects
				(font
					(size 1 1)
					(thickness 0.15)
				)
			)
		)
		(sheetname "/Peripherals/")
		(sheetfile "peripherals.kicad_sch")
		(attr exclude_from_pos_files)
		(fp_circle
			(center 0 0)
			(end 0.475 0)
			(stroke
				(width 0.05)
				(type default)
			)
			(fill no)
			(layer "F.CrtYd")
		)
		(fp_text user "Author: Antmicro"
			(at -0.4 3.901 0)
			(layer "F.Fab")
			(effects
				(font
					(size 0.7 0.7)
					(thickness 0.15)
				)
				(justify left bottom)
			)
		)
		(fp_text user "License: Apache-2.0"
			(at -0.4 5.101 0)
			(layer "F.Fab")
			(effects
				(font
					(size 0.7 0.7)
					(thickness 0.15)
				)
				(justify left bottom)
			)
		)
		(fp_text user "${REFERENCE}"
			(at -0.4 2.7 0)
			(layer "F.Fab")
			(effects
				(font
					(size 0.7 0.7)
					(thickness 0.15)
				)
				(justify left bottom)
			)
		)
		(pad "1" smd circle
			(at 0 0)
			(size 0.75 0.75)
			(layers "F.Cu" "F.Mask")
			(net 351 "Net-(U13-~{FAULT})")
			(pinfunction "1")
			(pintype "passive")
		)
	)
	(footprint "antmicro-footprints:R_0603_1608Metric"
		(layer "F.Cu")
		(at 106.09 107.2 -90)
		(descr "Resistor SMD 0603")
		(tags "resistor SMD 0603")
		(property "Reference" "R58"
			(at 1.24 -0.34 90)
			(layer "F.SilkS")
			(effects
				(font
					(size 0.65 0.65)
					(thickness 0.15)
				)
				(justify right bottom)
			)
		)
		(property "Value" "R_0R_0603"
			(at 0 1.6 90)
			(layer "F.Fab")
			(hide yes)
			(effects
				(font
					(size 0.7 0.7)
					(thickness 0.15)
				)
				(justify right bottom)
			)
		)
		(property "Datasheet" "https://www.bourns.com/docs/product-datasheets/cr.pdf?sfvrsn=574d41f6_14"
			(at 0 0 270)
			(layer "F.Fab")
			(hide yes)
			(effects
				(font
					(size 1.27 1.27)
					(thickness 0.15)
				)
			)
		)
		(property "Description" "Zero Ohm Resistor, Jumper, 0603 [1608 Metric], Thick Film, 100 mW, 1 A, Surface Mount Device, CR"
			(at 0 0 270)
			(layer "F.Fab")
			(hide yes)
			(effects
				(font
					(size 1.27 1.27)
					(thickness 0.15)
				)
			)
		)
		(property "Author" "Antmicro"
			(at -1.11 213.29 0)
			(layer "F.Fab")
			(hide yes)
			(effects
				(font
					(size 1 1)
					(thickness 0.15)
				)
			)
		)
		(property "Current" "1A"
			(at -1.11 213.29 0)
			(layer "F.Fab")
			(hide yes)
			(effects
				(font
					(size 1 1)
					(thickness 0.15)
				)
			)
		)
		(property "License" "Apache-2.0"
			(at -1.11 213.29 0)
			(layer "F.Fab")
			(hide yes)
			(effects
				(font
					(size 1 1)
					(thickness 0.15)
				)
			)
		)
		(property "MPN" "CR0603-J/-000ELF"
			(at -1.11 213.29 0)
			(layer "F.Fab")
			(hide yes)
			(effects
				(font
					(size 1 1)
					(thickness 0.15)
				)
			)
		)
		(property "Manufacturer" "Bourns"
			(at -1.11 213.29 0)
			(layer "F.Fab")
			(hide yes)
			(effects
				(font
					(size 1 1)
					(thickness 0.15)
				)
			)
		)
		(property "Tolerance" "~"
			(at -1.11 213.29 0)
			(layer "F.Fab")
			(hide yes)
			(effects
				(font
					(size 1 1)
					(thickness 0.15)
				)
			)
		)
		(property "Val" "0R"
			(at -1.11 213.29 0)
			(layer "F.Fab")
			(hide yes)
			(effects
				(font
					(size 1 1)
					(thickness 0.15)
				)
			)
		)
		(sheetname "/FPGA/")
		(sheetfile "fpga.kicad_sch")
		(attr smd)
		(fp_line
			(start -0.15 0.4)
			(end 0.15 0.4)
			(stroke
				(width 0.15)
				(type solid)
			)
			(layer "F.SilkS")
		)
		(fp_line
			(start -0.15 -0.4)
			(end 0.15 -0.4)
			(stroke
				(width 0.15)
				(type solid)
			)
			(layer "F.SilkS")
		)
		(fp_rect
			(start -1.25 -0.65)
			(end 1.25 0.65)
			(stroke
				(width 0.05)
				(type solid)
			)
			(fill no)
			(layer "F.CrtYd")
		)
		(fp_rect
			(start -0.8 -0.4)
			(end 0.8 0.4)
			(stroke
				(width 0.15)
				(type solid)
			)
			(fill no)
			(layer "F.Fab")
		)
		(fp_text user "License: Apache-2.0"
			(at -1.25 5.9 270)
			(layer "F.Fab")
			(effects
				(font
					(size 0.7 0.7)
					(thickness 0.15)
				)
				(justify left bottom)
			)
		)
		(fp_text user "${REFERENCE}"
			(at -1.25 3.898 270)
			(layer "F.Fab")
			(effects
				(font
					(size 0.7 0.7)
					(thickness 0.15)
				)
				(justify left bottom)
			)
		)
		(fp_text user "Author: Antmicro"
			(at -1.25 4.9 270)
			(layer "F.Fab")
			(effects
				(font
					(size 0.7 0.7)
					(thickness 0.15)
				)
				(justify left bottom)
			)
		)
		(pad "1" smd roundrect
			(at -0.7 0 270)
			(size 0.8 1)
			(layers "F.Cu" "F.Mask" "F.Paste")
			(roundrect_rratio 0.2)
			(net 290 "Net-(U17-SDA)")
			(pintype "passive")
		)
		(pad "2" smd roundrect
			(at 0.7 0 270)
			(size 0.8 1)
			(layers "F.Cu" "F.Mask" "F.Paste")
			(roundrect_rratio 0.2)
			(net 101 "SDA")
			(pintype "passive")
		)
	)
	(footprint "antmicro-footprints:L_Coilcraft-XEL4030"
		(layer "F.Cu")
		(at 164.39 62 180)
		(property "Reference" "L3"
			(at -2.44 -1.04 180)
			(layer "F.SilkS")
			(effects
				(font
					(size 0.65 0.65)
					(thickness 0.15)
				)
				(justify left bottom)
			)
		)
		(property "Value" "L_3u3_5.9A_XEL4030"
			(at 0 3.35 180)
			(layer "F.Fab")
			(hide yes)
			(effects
				(font
					(size 0.7 0.7)
					(thickness 0.15)
				)
				(justify left bottom)
			)
		)
		(property "Datasheet" "https://www.coilcraft.com/getmedia/8245f050-f190-4295-8c41-7c03d662ee3d/xel4030.pdf"
			(at 0 0 180)
			(layer "F.Fab")
			(hide yes)
			(effects
				(font
					(size 1.27 1.27)
					(thickness 0.15)
				)
			)
		)
		(property "Description" "Power Inductor (SMT), AEC-Q200, 3.3 µH, 6.6 A, Shielded, 5.9 A, XEL4030"
			(at 0 0 180)
			(layer "F.Fab")
			(hide yes)
			(effects
				(font
					(size 1.27 1.27)
					(thickness 0.15)
				)
			)
		)
		(property "Author" "Antmicro"
			(at 328.78 124 0)
			(layer "F.Fab")
			(hide yes)
			(effects
				(font
					(size 1 1)
					(thickness 0.15)
				)
			)
		)
		(property "IMax" "6.6 A"
			(at 328.78 124 0)
			(layer "F.Fab")
			(hide yes)
			(effects
				(font
					(size 1 1)
					(thickness 0.15)
				)
			)
		)
		(property "ISat" "5.9 A"
			(at 328.78 124 0)
			(layer "F.Fab")
			(hide yes)
			(effects
				(font
					(size 1 1)
					(thickness 0.15)
				)
			)
		)
		(property "License" "Apache-2.0"
			(at 328.78 124 0)
			(layer "F.Fab")
			(hide yes)
			(effects
				(font
					(size 1 1)
					(thickness 0.15)
				)
			)
		)
		(property "MPN" "XEL4030-332MEC"
			(at 328.78 124 0)
			(layer "F.Fab")
			(hide yes)
			(effects
				(font
					(size 1 1)
					(thickness 0.15)
				)
			)
		)
		(property "Manufacturer" "Coilcraft"
			(at 328.78 124 0)
			(layer "F.Fab")
			(hide yes)
			(effects
				(font
					(size 1 1)
					(thickness 0.15)
				)
			)
		)
		(property "Size" "4.0x4.0"
			(at 328.78 124 0)
			(layer "F.Fab")
			(hide yes)
			(effects
				(font
					(size 1 1)
					(thickness 0.15)
				)
			)
		)
		(property "Val" "3u3/6.6A"
			(at 328.78 124 0)
			(layer "F.Fab")
			(hide yes)
			(effects
				(font
					(size 1 1)
					(thickness 0.15)
				)
			)
		)
		(sheetname "/Power Supply/")
		(sheetfile "supply.kicad_sch")
		(attr smd)
		(fp_line
			(start 2.2 2.2)
			(end 2.2 -2.2)
			(stroke
				(width 0.15)
				(type solid)
			)
			(layer "F.SilkS")
		)
		(fp_line
			(start -2.2 2.2)
			(end 2.2 2.2)
			(stroke
				(width 0.15)
				(type solid)
			)
			(layer "F.SilkS")
		)
		(fp_line
			(start -2.2 2.2)
			(end -2.2 -2.2)
			(stroke
				(width 0.15)
				(type solid)
			)
			(layer "F.SilkS")
		)
		(fp_line
			(start -2.2 -2.2)
			(end 2.2 -2.2)
			(stroke
				(width 0.15)
				(type solid)
			)
			(layer "F.SilkS")
		)
		(fp_rect
			(start -2.4 -2.4)
			(end 2.4 2.4)
			(stroke
				(width 0.05)
				(type solid)
			)
			(fill no)
			(layer "F.CrtYd")
		)
		(fp_rect
			(start -2.15 -2.15)
			(end 2.15 2.15)
			(stroke
				(width 0.15)
				(type solid)
			)
			(fill no)
			(layer "F.Fab")
		)
		(fp_text user "Author: Antmicro"
			(at -2.4 5.35 180)
			(layer "F.Fab")
			(effects
				(font
					(size 0.7 0.7)
					(thickness 0.15)
				)
				(justify left bottom)
			)
		)
		(fp_text user "${REFERENCE}"
			(at -2.4 6.55 180)
			(layer "F.Fab")
			(effects
				(font
					(size 0.7 0.7)
					(thickness 0.15)
				)
				(justify left bottom)
			)
		)
		(fp_text user "License: Apache-2.0"
			(at -2.4 7.75 180)
			(layer "F.Fab")
			(effects
				(font
					(size 0.7 0.7)
					(thickness 0.15)
				)
				(justify left bottom)
			)
		)
		(pad "1" smd roundrect
			(at -1.185 0 180)
			(size 0.98 3.4)
			(layers "F.Cu" "F.Mask" "F.Paste")
			(roundrect_rratio 0.1)
			(net 278 "/Power Supply/3V3_SW")
			(pintype "passive")
		)
		(pad "2" smd roundrect
			(at 1.185 0 180)
			(size 0.98 3.4)
			(layers "F.Cu" "F.Mask" "F.Paste")
			(roundrect_rratio 0.1)
			(net 275 "/Power Supply/3V3_OUT")
			(pintype "passive")
		)
	)
	(footprint "antmicro-footprints:R_0603_1608Metric"
		(layer "F.Cu")
		(at 158.29 81.2)
		(descr "Resistor SMD 0603")
		(tags "resistor SMD 0603")
		(property "Reference" "R114"
			(at -4.06 0.54 0)
			(layer "F.SilkS")
			(effects
				(font
					(size 0.65 0.65)
					(thickness 0.15)
				)
				(justify left bottom)
			)
		)
		(property "Value" "R_10k_0603"
			(at 0 1.6 0)
			(layer "F.Fab")
			(hide yes)
			(effects
				(font
					(size 0.7 0.7)
					(thickness 0.15)
				)
				(justify left bottom)
			)
		)
		(property "Datasheet" "https://www.bourns.com/docs/product-datasheets/cr.pdf"
			(at 0 0 0)
			(layer "F.Fab")
			(hide yes)
			(effects
				(font
					(size 1.27 1.27)
					(thickness 0.15)
				)
			)
		)
		(property "Description" "SMD Chip Resistor, 10 kohm, ± 1%, 100 mW, 0603 [1608 Metric], Thick Film, General Purpose"
			(at 0 0 0)
			(layer "F.Fab")
			(hide yes)
			(effects
				(font
					(size 1.27 1.27)
					(thickness 0.15)
				)
			)
		)
		(property "Author" "Antmicro"
			(at 0 0 0)
			(layer "F.Fab")
			(hide yes)
			(effects
				(font
					(size 1 1)
					(thickness 0.15)
				)
			)
		)
		(property "License" "Apache-2.0"
			(at 0 0 0)
			(layer "F.Fab")
			(hide yes)
			(effects
				(font
					(size 1 1)
					(thickness 0.15)
				)
			)
		)
		(property "MPN" "CR0603-FX-1002ELF"
			(at 0 0 0)
			(layer "F.Fab")
			(hide yes)
			(effects
				(font
					(size 1 1)
					(thickness 0.15)
				)
			)
		)
		(property "Manufacturer" "Bourns"
			(at 0 0 0)
			(layer "F.Fab")
			(hide yes)
			(effects
				(font
					(size 1 1)
					(thickness 0.15)
				)
			)
		)
		(property "Tolerance" "1%"
			(at 0 0 0)
			(layer "F.Fab")
			(hide yes)
			(effects
				(font
					(size 1 1)
					(thickness 0.15)
				)
			)
		)
		(property "Val" "10k"
			(at 0 0 0)
			(layer "F.Fab")
			(hide yes)
			(effects
				(font
					(size 1 1)
					(thickness 0.15)
				)
			)
		)
		(sheetname "/Peripherals/")
		(sheetfile "peripherals.kicad_sch")
		(attr smd)
		(fp_line
			(start -0.15 -0.4)
			(end 0.15 -0.4)
			(stroke
				(width 0.15)
				(type solid)
			)
			(layer "F.SilkS")
		)
		(fp_line
			(start -0.15 0.4)
			(end 0.15 0.4)
			(stroke
				(width 0.15)
				(type solid)
			)
			(layer "F.SilkS")
		)
		(fp_rect
			(start -1.25 -0.65)
			(end 1.25 0.65)
			(stroke
				(width 0.05)
				(type solid)
			)
			(fill no)
			(layer "F.CrtYd")
		)
		(fp_rect
			(start -0.8 -0.4)
			(end 0.8 0.4)
			(stroke
				(width 0.15)
				(type solid)
			)
			(fill no)
			(layer "F.Fab")
		)
		(fp_text user "License: Apache-2.0"
			(at -1.25 5.9 0)
			(layer "F.Fab")
			(effects
				(font
					(size 0.7 0.7)
					(thickness 0.15)
				)
				(justify left bottom)
			)
		)
		(fp_text user "${REFERENCE}"
			(at -1.25 3.898 0)
			(layer "F.Fab")
			(effects
				(font
					(size 0.7 0.7)
					(thickness 0.15)
				)
				(justify left bottom)
			)
		)
		(fp_text user "Author: Antmicro"
			(at -1.25 4.9 0)
			(layer "F.Fab")
			(effects
				(font
					(size 0.7 0.7)
					(thickness 0.15)
				)
				(justify left bottom)
			)
		)
		(pad "1" smd roundrect
			(at -0.7 0)
			(size 0.8 1)
			(layers "F.Cu" "F.Mask" "F.Paste")
			(roundrect_rratio 0.2)
			(net 2 "+3V3")
			(pintype "passive")
		)
		(pad "2" smd roundrect
			(at 0.7 0)
			(size 0.8 1)
			(layers "F.Cu" "F.Mask" "F.Paste")
			(roundrect_rratio 0.2)
			(net 315 "/Peripherals/QWIIC_PEN")
			(pintype "passive")
		)
	)
	(footprint "antmicro-footprints:SW_DIP_SPSTx02_Slide_Copal_CVS-02xB_W5.9mm_P1mm"
		(layer "F.Cu")
		(at 158.75 121.15 90)
		(descr "SMD 2x-dip-switch SPST Copal_CVS-02xB, Slide, row spacing 5.9 mm")
		(tags "SMD DIP Switch SPST Slide 5.9mm")
		(property "Reference" "SW1"
			(at 0 -2.08 90)
			(layer "F.SilkS")
			(effects
				(font
					(size 0.65 0.65)
					(thickness 0.15)
				)
				(justify left bottom)
			)
		)
		(property "Value" "SW_CVS-02B"
			(at 0 2.91 90)
			(layer "F.Fab")
			(hide yes)
			(effects
				(font
					(size 0.7 0.7)
					(thickness 0.15)
				)
				(justify left bottom)
			)
		)
		(property "Datasheet" "https://www.mouser.com/datasheet/2/972/cvs-1827291.pdf"
			(at 0 0 90)
			(layer "F.Fab")
			(hide yes)
			(effects
				(font
					(size 1.27 1.27)
					(thickness 0.15)
				)
			)
		)
		(property "Description" "Slide switch, 2-position SMD Slide switch, 2-channel"
			(at 0 0 90)
			(layer "F.Fab")
			(hide yes)
			(effects
				(font
					(size 1.27 1.27)
					(thickness 0.15)
				)
			)
		)
		(property "Author" "Antmicro"
			(at 279.9 -37.6 0)
			(layer "F.Fab")
			(hide yes)
			(effects
				(font
					(size 1 1)
					(thickness 0.15)
				)
			)
		)
		(property "License" "Apache-2.0"
			(at 279.9 -37.6 0)
			(layer "F.Fab")
			(hide yes)
			(effects
				(font
					(size 1 1)
					(thickness 0.15)
				)
			)
		)
		(property "MPN" "CVS-02B"
			(at 279.9 -37.6 0)
			(layer "F.Fab")
			(hide yes)
			(effects
				(font
					(size 1 1)
					(thickness 0.15)
				)
			)
		)
		(property "Manufacturer" "Nidec Components"
			(at 279.9 -37.6 0)
			(layer "F.Fab")
			(hide yes)
			(effects
				(font
					(size 1 1)
					(thickness 0.15)
				)
			)
		)
		(property ki_fp_filters "SW?DIP?x2*")
		(sheetname "/Peripherals/")
		(sheetfile "peripherals.kicad_sch")
		(attr smd)
		(fp_line
			(start -1.561 -1.911)
			(end 1.56 -1.911)
			(stroke
				(width 0.15)
				(type solid)
			)
			(layer "F.SilkS")
		)
		(fp_line
			(start -1.561 1.908)
			(end 1.56 1.908)
			(stroke
				(width 0.15)
				(type solid)
			)
			(layer "F.SilkS")
		)
		(fp_circle
			(center -3.4 -1.1)
			(end -3.35 -1.06)
			(stroke
				(width 0.15)
				(type solid)
			)
			(fill yes)
			(layer "F.SilkS")
		)
		(fp_rect
			(start -3.6 -2)
			(end 3.6 2)
			(stroke
				(width 0.05)
				(type solid)
			)
			(fill no)
			(layer "F.CrtYd")
		)
		(fp_line
			(start 0.998 -0.75)
			(end -1 -0.75)
			(stroke
				(width 0.15)
				(type solid)
			)
			(layer "F.Fab")
		)
		(fp_line
			(start -0.335 -0.75)
			(end -0.335 -0.25)
			(stroke
				(width 0.15)
				(type solid)
			)
			(layer "F.Fab")
		)
		(fp_line
			(start -1 -0.75)
			(end -1 -0.25)
			(stroke
				(width 0.15)
				(type solid)
			)
			(layer "F.Fab")
		)
		(fp_line
			(start -1 -0.652)
			(end -0.335 -0.652)
			(stroke
				(width 0.15)
				(type solid)
			)
			(layer "F.Fab")
		)
		(fp_line
			(start -1 -0.552)
			(end -0.335 -0.552)
			(stroke
				(width 0.15)
				(type solid)
			)
			(layer "F.Fab")
		)
		(fp_line
			(start -2.351 -0.5)
			(end -1.351 -1.5)
			(stroke
				(width 0.15)
				(type solid)
			)
			(layer "F.Fab")
		)
		(fp_line
			(start -1 -0.452)
			(end -0.335 -0.452)
			(stroke
				(width 0.15)
				(type solid)
			)
			(layer "F.Fab")
		)
		(fp_line
			(start -1 -0.351)
			(end -0.335 -0.351)
			(stroke
				(width 0.15)
				(type solid)
			)
			(layer "F.Fab")
		)
		(fp_line
			(start 0.998 -0.25)
			(end 0.998 -0.75)
			(stroke
				(width 0.15)
				(type solid)
			)
			(layer "F.Fab")
		)
		(fp_line
			(start -1 -0.25)
			(end 0.998 -0.25)
			(stroke
				(width 0.15)
				(type solid)
			)
			(layer "F.Fab")
		)
		(fp_line
			(start 0.998 0.248)
			(end -1 0.248)
			(stroke
				(width 0.15)
				(type solid)
			)
			(layer "F.Fab")
		)
		(fp_line
			(start -0.335 0.248)
			(end -0.335 0.748)
			(stroke
				(width 0.15)
				(type solid)
			)
			(layer "F.Fab")
		)
		(fp_line
			(start -1 0.248)
			(end -1 0.748)
			(stroke
				(width 0.15)
				(type solid)
			)
			(layer "F.Fab")
		)
		(fp_line
			(start -1 0.349)
			(end -0.335 0.349)
			(stroke
				(width 0.15)
				(type solid)
			)
			(layer "F.Fab")
		)
		(fp_line
			(start -1 0.45)
			(end -0.335 0.45)
			(stroke
				(width 0.15)
				(type solid)
			)
			(layer "F.Fab")
		)
		(fp_line
			(start -1 0.55)
			(end -0.335 0.55)
			(stroke
				(width 0.15)
				(type solid)
			)
			(layer "F.Fab")
		)
		(fp_line
			(start -1 0.65)
			(end -0.335 0.65)
			(stroke
				(width 0.15)
				(type solid)
			)
			(layer "F.Fab")
		)
		(fp_line
			(start 0.998 0.748)
			(end 0.998 0.248)
			(stroke
				(width 0.15)
				(type solid)
			)
			(layer "F.Fab")
		)
		(fp_line
			(start -1 0.748)
			(end 0.998 0.748)
			(stroke
				(width 0.15)
				(type solid)
			)
			(layer "F.Fab")
		)
		(fp_rect
			(start 2.35 1.499)
			(end -2.351 -1.5)
			(stroke
				(width 0.15)
				(type solid)
			)
			(fill no)
			(layer "F.Fab")
		)
		(fp_text user "License: Apache-2.0"
			(at -3.6 6.908 90)
			(layer "F.Fab")
			(effects
				(font
					(size 0.7 0.7)
					(thickness 0.15)
				)
				(justify left bottom)
			)
		)
		(fp_text user "${REFERENCE}"
			(at -3.6 4.91 90)
			(layer "F.Fab")
			(effects
				(font
					(size 0.7 0.7)
					(thickness 0.15)
				)
				(justify left bottom)
			)
		)
		(fp_text user "on"
			(at -1.5 0.739 0)
			(layer "F.Fab")
			(effects
				(font
					(size 0.7 0.7)
					(thickness 0.15)
				)
				(justify right bottom)
			)
		)
		(fp_text user "Author: Antmicro"
			(at -3.6 5.908 90)
			(layer "F.Fab")
			(effects
				(font
					(size 0.7 0.7)
					(thickness 0.15)
				)
				(justify left bottom)
			)
		)
		(pad "1" smd rect
			(at -2.95 -0.5 90)
			(size 1.2 0.5)
			(layers "F.Cu" "F.Mask" "F.Paste")
			(net 1 "GND")
			(pintype "passive")
		)
		(pad "2" smd rect
			(at -2.95 0.5 90)
			(size 1.2 0.5)
			(layers "F.Cu" "F.Mask" "F.Paste")
			(net 1 "GND")
			(pintype "passive")
		)
		(pad "3" smd rect
			(at 2.95 0.5 90)
			(size 1.2 0.5)
			(layers "F.Cu" "F.Mask" "F.Paste")
			(net 44 "DIP0")
			(pintype "passive")
		)
		(pad "4" smd rect
			(at 2.95 -0.5 90)
			(size 1.2 0.5)
			(layers "F.Cu" "F.Mask" "F.Paste")
			(net 43 "DIP1")
			(pintype "passive")
		)
		(pad "SH" smd rect
			(at -2.15 -1.5 90)
			(size 0.7 0.7)
			(layers "F.Cu" "F.Mask" "F.Paste")
			(net 1 "GND")
			(pinfunction "SH")
			(pintype "power_in")
		)
		(pad "SH" smd rect
			(at -2.15 1.5 90)
			(size 0.7 0.7)
			(layers "F.Cu" "F.Mask" "F.Paste")
			(net 1 "GND")
			(pinfunction "SH")
			(pintype "power_in")
		)
		(pad "SH" smd rect
			(at 2.15 -1.5 90)
			(size 0.7 0.7)
			(layers "F.Cu" "F.Mask" "F.Paste")
			(net 1 "GND")
			(pinfunction "SH")
			(pintype "power_in")
		)
		(pad "SH" smd rect
			(at 2.15 1.5 90)
			(size 0.7 0.7)
			(layers "F.Cu" "F.Mask" "F.Paste")
			(net 1 "GND")
			(pinfunction "SH")
			(pintype "power_in")
		)
	)
	(footprint "antmicro-footprints:R_0402_1005Metric"
		(layer "F.Cu")
		(at 140.57 113.6 -90)
		(descr "Resistor SMD 0402")
		(tags "resistor SMD 0402")
		(property "Reference" "R34"
			(at 0.96 0.36 270)
			(layer "F.SilkS")
			(effects
				(font
					(size 0.65 0.65)
					(thickness 0.15)
				)
				(justify left bottom)
			)
		)
		(property "Value" "R_24k_0402"
			(at 0 1.4 270)
			(layer "F.Fab")
			(hide yes)
			(effects
				(font
					(size 0.7 0.7)
					(thickness 0.15)
				)
				(justify left bottom)
			)
		)
		(property "Datasheet" "https://www.bourns.com/docs/product-datasheets/cr.pdf"
			(at 0 0 270)
			(layer "F.Fab")
			(hide yes)
			(effects
				(font
					(size 1.27 1.27)
					(thickness 0.15)
				)
			)
		)
		(property "Description" "SMD Chip Resistor, 24 kohm, ± 1%, 100 mW, 0402 [1005 Metric], Thick Film, Precision"
			(at 0 0 270)
			(layer "F.Fab")
			(hide yes)
			(effects
				(font
					(size 1.27 1.27)
					(thickness 0.15)
				)
			)
		)
		(property "Author" "Antmicro"
			(at 26.79 253.99 0)
			(layer "F.Fab")
			(hide yes)
			(effects
				(font
					(size 1 1)
					(thickness 0.15)
				)
			)
		)
		(property "License" "Apache-2.0"
			(at 26.79 253.99 0)
			(layer "F.Fab")
			(hide yes)
			(effects
				(font
					(size 1 1)
					(thickness 0.15)
				)
			)
		)
		(property "MPN" "CR0402-FX-2402GLF"
			(at 26.79 253.99 0)
			(layer "F.Fab")
			(hide yes)
			(effects
				(font
					(size 1 1)
					(thickness 0.15)
				)
			)
		)
		(property "Manufacturer" "Bourns"
			(at 26.79 253.99 0)
			(layer "F.Fab")
			(hide yes)
			(effects
				(font
					(size 1 1)
					(thickness 0.15)
				)
			)
		)
		(property "Tolerance" "1%"
			(at 26.79 253.99 0)
			(layer "F.Fab")
			(hide yes)
			(effects
				(font
					(size 1 1)
					(thickness 0.15)
				)
			)
		)
		(property "Val" "24k"
			(at 26.79 253.99 0)
			(layer "F.Fab")
			(hide yes)
			(effects
				(font
					(size 1 1)
					(thickness 0.15)
				)
			)
		)
		(sheetname "/Power Supply/")
		(sheetfile "supply.kicad_sch")
		(attr smd)
		(fp_rect
			(start -0.925 -0.47)
			(end 0.925 0.47)
			(stroke
				(width 0.05)
				(type default)
			)
			(fill no)
			(layer "F.CrtYd")
		)
		(fp_rect
			(start -0.5 -0.25)
			(end 0.5 0.25)
			(stroke
				(width 0.15)
				(type solid)
			)
			(fill no)
			(layer "F.Fab")
		)
		(fp_text user "${REFERENCE}"
			(at -0.95 3.168 270)
			(layer "F.Fab")
			(effects
				(font
					(size 0.7 0.7)
					(thickness 0.15)
				)
				(justify left bottom)
			)
		)
		(fp_text user "Author: Antmicro"
			(at -0.95 4.169 270)
			(layer "F.Fab")
			(effects
				(font
					(size 0.7 0.7)
					(thickness 0.15)
				)
				(justify left bottom)
			)
		)
		(fp_text user "License: Apache-2.0"
			(at -0.95 5.169 270)
			(layer "F.Fab")
			(effects
				(font
					(size 0.7 0.7)
					(thickness 0.15)
				)
				(justify left bottom)
			)
		)
		(pad "1" smd roundrect
			(at -0.48 0 270)
			(size 0.59 0.64)
			(layers "F.Cu" "F.Mask" "F.Paste")
			(roundrect_rratio 0.25)
			(net 1 "GND")
			(pintype "passive")
		)
		(pad "2" smd roundrect
			(at 0.48 0 270)
			(size 0.59 0.64)
			(layers "F.Cu" "F.Mask" "F.Paste")
			(roundrect_rratio 0.25)
			(net 282 "Net-(U9-ADJ)")
			(pintype "passive")
		)
	)
	(footprint "antmicro-footprints:C_0603_1608Metric"
		(layer "F.Cu")
		(at 146.24 106.5 180)
		(descr "Capacitor SMD 0603")
		(tags "capacitor 0603")
		(property "Reference" "C17"
			(at 1.01 0.96 180)
			(layer "F.SilkS")
			(effects
				(font
					(size 0.65 0.65)
					(thickness 0.15)
				)
				(justify left bottom)
			)
		)
		(property "Value" "C_1u_0603"
			(at 0 1.6 180)
			(layer "F.Fab")
			(hide yes)
			(effects
				(font
					(size 0.7 0.7)
					(thickness 0.15)
				)
				(justify left bottom)
			)
		)
		(property "Datasheet" "https://spicat.kyocera-avx.com/product/mlcc/chartview/0603YD105KAT2A/"
			(at 0 0 180)
			(layer "F.Fab")
			(hide yes)
			(effects
				(font
					(size 1.27 1.27)
					(thickness 0.15)
				)
			)
		)
		(property "Description" "SMD Multilayer Ceramic Capacitor, 1 µF, 16 V, 0603 [1608 Metric], ± 10%, X5R, AVX 0603 MLCC"
			(at 0 0 180)
			(layer "F.Fab")
			(hide yes)
			(effects
				(font
					(size 1.27 1.27)
					(thickness 0.15)
				)
			)
		)
		(property "Author" "Antmicro"
			(at 292.48 213 0)
			(layer "F.Fab")
			(hide yes)
			(effects
				(font
					(size 1 1)
					(thickness 0.15)
				)
			)
		)
		(property "Dielectric" ""
			(at 292.48 213 0)
			(layer "F.Fab")
			(hide yes)
			(effects
				(font
					(size 1 1)
					(thickness 0.15)
				)
			)
		)
		(property "License" "Apache-2.0"
			(at 292.48 213 0)
			(layer "F.Fab")
			(hide yes)
			(effects
				(font
					(size 1 1)
					(thickness 0.15)
				)
			)
		)
		(property "MPN" "0603YD105KAT2A"
			(at 292.48 213 0)
			(layer "F.Fab")
			(hide yes)
			(effects
				(font
					(size 1 1)
					(thickness 0.15)
				)
			)
		)
		(property "Manufacturer" "KYOCERA AVX"
			(at 292.48 213 0)
			(layer "F.Fab")
			(hide yes)
			(effects
				(font
					(size 1 1)
					(thickness 0.15)
				)
			)
		)
		(property "Val" "1u"
			(at 292.48 213 0)
			(layer "F.Fab")
			(hide yes)
			(effects
				(font
					(size 1 1)
					(thickness 0.15)
				)
			)
		)
		(property "Voltage" ""
			(at 292.48 213 0)
			(layer "F.Fab")
			(hide yes)
			(effects
				(font
					(size 1 1)
					(thickness 0.15)
				)
			)
		)
		(sheetname "/Power Supply/")
		(sheetfile "supply.kicad_sch")
		(attr smd)
		(fp_line
			(start -0.15 0.4)
			(end 0.15 0.4)
			(stroke
				(width 0.15)
				(type solid)
			)
			(layer "F.SilkS")
		)
		(fp_line
			(start -0.15 -0.4)
			(end 0.15 -0.4)
			(stroke
				(width 0.15)
				(type solid)
			)
			(layer "F.SilkS")
		)
		(fp_rect
			(start -1.25 -0.65)
			(end 1.25 0.65)
			(stroke
				(width 0.05)
				(type solid)
			)
			(fill no)
			(layer "F.CrtYd")
		)
		(fp_rect
			(start -0.8 -0.4)
			(end 0.8 0.4)
			(stroke
				(width 0.15)
				(type solid)
			)
			(fill no)
			(layer "F.Fab")
		)
		(fp_text user "License: Apache-2.0"
			(at -1.682 5.895 180)
			(layer "F.Fab")
			(effects
				(font
					(size 0.7 0.7)
					(thickness 0.15)
				)
				(justify left bottom)
			)
		)
		(fp_text user "${REFERENCE}"
			(at -1.682 3.895 180)
			(layer "F.Fab")
			(effects
				(font
					(size 0.7 0.7)
					(thickness 0.15)
				)
				(justify left bottom)
			)
		)
		(fp_text user "Author: Antmicro"
			(at -1.682 4.894 180)
			(layer "F.Fab")
			(effects
				(font
					(size 0.7 0.7)
					(thickness 0.15)
				)
				(justify left bottom)
			)
		)
		(pad "1" smd roundrect
			(at -0.7 0 180)
			(size 0.8 1)
			(layers "F.Cu" "F.Mask" "F.Paste")
			(roundrect_rratio 0.2)
			(net 2 "+3V3")
			(pintype "passive")
		)
		(pad "2" smd roundrect
			(at 0.7 0 180)
			(size 0.8 1)
			(layers "F.Cu" "F.Mask" "F.Paste")
			(roundrect_rratio 0.2)
			(net 1 "GND")
			(pintype "passive")
		)
	)
	(footprint "antmicro-footprints:TSOT23-6"
		(layer "F.Cu")
		(at 146.58 59.24 90)
		(property "Reference" "U6"
			(at 0.56 2.51 90)
			(layer "F.SilkS")
			(effects
				(font
					(size 0.65 0.65)
					(thickness 0.15)
				)
				(justify left bottom)
			)
		)
		(property "Value" "AP62301WU-7"
			(at -0.005 2.6 90)
			(layer "F.Fab")
			(hide yes)
			(effects
				(font
					(size 0.7 0.7)
					(thickness 0.15)
				)
				(justify left bottom)
			)
		)
		(property "Datasheet" "https://www.diodes.com/assets/Datasheets/AP62300_AP62301_AP62300T.pdf"
			(at 0 0 90)
			(layer "F.Fab")
			(hide yes)
			(effects
				(font
					(size 1.27 1.27)
					(thickness 0.15)
				)
			)
		)
		(property "Description" "DC-DC Switching Synchronous Buck Regulator, Adjustable, 4.2V-18Vin, 0.8V-7V/3A out, TSOT-26-6"
			(at 0 0 90)
			(layer "F.Fab")
			(hide yes)
			(effects
				(font
					(size 1.27 1.27)
					(thickness 0.15)
				)
			)
		)
		(property "Author" "Antmicro"
			(at 0 0 90)
			(layer "F.Fab")
			(hide yes)
			(effects
				(font
					(size 1 1)
					(thickness 0.15)
				)
			)
		)
		(property "License" "Apache-2.0"
			(at 0 0 90)
			(layer "F.Fab")
			(hide yes)
			(effects
				(font
					(size 1 1)
					(thickness 0.15)
				)
			)
		)
		(property "MPN" "AP62301WU-7"
			(at 0 0 90)
			(layer "F.Fab")
			(hide yes)
			(effects
				(font
					(size 1 1)
					(thickness 0.15)
				)
			)
		)
		(property "Manufacturer" "Diodes Incorporated"
			(at 0 0 90)
			(layer "F.Fab")
			(hide yes)
			(effects
				(font
					(size 1 1)
					(thickness 0.15)
				)
			)
		)
		(sheetname "/Power Supply/")
		(sheetfile "supply.kicad_sch")
		(attr smd)
		(fp_line
			(start -1 -1.5)
			(end -1 -1.375)
			(stroke
				(width 0.15)
				(type solid)
			)
			(layer "F.SilkS")
		)
		(fp_line
			(start 1 -1.497)
			(end -1 -1.5)
			(stroke
				(width 0.15)
				(type solid)
			)
			(layer "F.SilkS")
		)
		(fp_line
			(start 1 -1.497)
			(end 1 -1.375)
			(stroke
				(width 0.15)
				(type solid)
			)
			(layer "F.SilkS")
		)
		(fp_line
			(start 1 1.55)
			(end 1 1.4)
			(stroke
				(width 0.15)
				(type solid)
			)
			(layer "F.SilkS")
		)
		(fp_line
			(start 1 1.55)
			(end -1 1.55)
			(stroke
				(width 0.15)
				(type solid)
			)
			(layer "F.SilkS")
		)
		(fp_line
			(start -1 1.55)
			(end -1 1.4)
			(stroke
				(width 0.15)
				(type solid)
			)
			(layer "F.SilkS")
		)
		(fp_circle
			(center -1.44 -1.5)
			(end -1.39 -1.5)
			(stroke
				(width 0.15)
				(type solid)
			)
			(fill yes)
			(layer "F.SilkS")
		)
		(fp_rect
			(start 1.93 -1.7)
			(end -1.93 1.7)
			(stroke
				(width 0.05)
				(type solid)
			)
			(fill no)
			(layer "F.CrtYd")
		)
		(fp_line
			(start -0.45 -1.521)
			(end -0.876 -1.096)
			(stroke
				(width 0.15)
				(type solid)
			)
			(layer "F.Fab")
		)
		(fp_rect
			(start 0.875 1.528)
			(end -0.875 -1.525)
			(stroke
				(width 0.15)
				(type solid)
			)
			(fill no)
			(layer "F.Fab")
		)
		(fp_text user "Author: Antmicro"
			(at -1.93 5 90)
			(layer "F.Fab")
			(effects
				(font
					(size 0.7 0.7)
					(thickness 0.15)
				)
				(justify left bottom)
			)
		)
		(fp_text user "License: Apache-2.0"
			(at -1.93 6.199 90)
			(layer "F.Fab")
			(effects
				(font
					(size 0.7 0.7)
					(thickness 0.15)
				)
				(justify left bottom)
			)
		)
		(fp_text user "${REFERENCE}"
			(at -1.93 3.8 90)
			(layer "F.Fab")
			(effects
				(font
					(size 0.7 0.7)
					(thickness 0.15)
				)
				(justify left bottom)
			)
		)
		(pad "1" smd rect
			(at -1.301 -0.947)
			(size 0.7 1.2)
			(layers "F.Cu" "F.Mask" "F.Paste")
			(net 1 "GND")
			(pinfunction "GND")
			(pintype "power_in")
		)
		(pad "2" smd rect
			(at -1.301 0.004)
			(size 0.7 1.2)
			(layers "F.Cu" "F.Mask" "F.Paste")
			(net 277 "/Power Supply/1V5_SW")
			(pinfunction "SW")
			(pintype "power_out")
		)
		(pad "3" smd rect
			(at -1.301 0.954)
			(size 0.7 1.2)
			(layers "F.Cu" "F.Mask" "F.Paste")
			(net 327 "/Power Supply/5V_1V5_IN")
			(pinfunction "VIN")
			(pintype "power_in")
		)
		(pad "4" smd rect
			(at 1.299 0.954)
			(size 0.7 1.2)
			(layers "F.Cu" "F.Mask" "F.Paste")
			(net 263 "Net-(U6-FB)")
			(pinfunction "FB")
			(pintype "input")
		)
		(pad "5" smd rect
			(at 1.299 0.004)
			(size 0.7 1.2)
			(layers "F.Cu" "F.Mask" "F.Paste")
			(net 374 "Net-(U6-EN)")
			(pinfunction "EN")
			(pintype "input")
		)
		(pad "6" smd rect
			(at 1.299 -0.947)
			(size 0.7 1.2)
			(layers "F.Cu" "F.Mask" "F.Paste")
			(net 65 "Net-(U6-BST)")
			(pinfunction "BST")
			(pintype "output")
		)
	)
	(footprint "antmicro-footprints:LED_0603_1608Metric_G"
		(layer "F.Cu")
		(at 105.6 73.39 90)
		(descr "LED SMD 0603 Green")
		(tags "LED SMD 0603 Green")
		(property "Reference" "D7"
			(at -2.95 -0.27 90)
			(layer "F.SilkS")
			(effects
				(font
					(size 0.65 0.65)
					(thickness 0.15)
				)
				(justify left top)
			)
		)
		(property "Value" "LED_G_0603_LTST-C190GKT"
			(at 0 1.6 90)
			(layer "F.Fab")
			(hide yes)
			(effects
				(font
					(size 0.7 0.7)
					(thickness 0.15)
				)
				(justify left top)
			)
		)
		(property "Datasheet" "https://media.digikey.com/pdf/Data%20Sheets/Lite-On%20PDFs/LTST-C190GKT.pdf"
			(at 0 0 90)
			(layer "F.Fab")
			(hide yes)
			(effects
				(font
					(size 1.27 1.27)
					(thickness 0.15)
				)
			)
		)
		(property "Description" "LED, Green, SMD, 0603, 20 mA, 2.1 V, 569 nm"
			(at 0 0 90)
			(layer "F.Fab")
			(hide yes)
			(effects
				(font
					(size 1.27 1.27)
					(thickness 0.15)
				)
			)
		)
		(property "Author" "Antmicro"
			(at 32.21 178.99 0)
			(layer "F.Fab")
			(hide yes)
			(effects
				(font
					(size 1 1)
					(thickness 0.15)
				)
			)
		)
		(property "License" "Apache-2.0"
			(at 32.21 178.99 0)
			(layer "F.Fab")
			(hide yes)
			(effects
				(font
					(size 1 1)
					(thickness 0.15)
				)
			)
		)
		(property "MPN" "LTST-C190GKT"
			(at 32.21 178.99 0)
			(layer "F.Fab")
			(hide yes)
			(effects
				(font
					(size 1 1)
					(thickness 0.15)
				)
			)
		)
		(property "Manufacturer" "Lite-On"
			(at 32.21 178.99 0)
			(layer "F.Fab")
			(hide yes)
			(effects
				(font
					(size 1 1)
					(thickness 0.15)
				)
			)
		)
		(property "Color" "Green"
			(at 0 0 90)
			(unlocked yes)
			(layer "F.Fab")
			(hide yes)
			(effects
				(font
					(size 1 1)
					(thickness 0.15)
				)
			)
		)
		(sheetname "/SDI/")
		(sheetfile "sdi.kicad_sch")
		(attr smd)
		(fp_line
			(start 0.22 -0.35)
			(end -0.22 -0.35)
			(stroke
				(width 0.15)
				(type solid)
			)
			(layer "F.SilkS")
		)
		(fp_line
			(start -1.18 -0.319)
			(end -1.18 0.321)
			(stroke
				(width 0.15)
				(type solid)
			)
			(layer "F.SilkS")
		)
		(fp_line
			(start 0.105328 0.001008)
			(end 0.24 0.001)
			(stroke
				(width 0.1)
				(type solid)
			)
			(layer "F.SilkS")
		)
		(fp_line
			(start -0.094672 0.001008)
			(end 0.105328 -0.198992)
			(stroke
				(width 0.1)
				(type solid)
			)
			(layer "F.SilkS")
		)
		(fp_line
			(start -0.094672 0.001008)
			(end -0.24 0.001008)
			(stroke
				(width 0.1)
				(type solid)
			)
			(layer "F.SilkS")
		)
		(fp_line
			(start 0.105328 0.201008)
			(end 0.105328 -0.198992)
			(stroke
				(width 0.1)
				(type solid)
			)
			(layer "F.SilkS")
		)
		(fp_line
			(start 0.105328 0.201008)
			(end -0.094672 0.001008)
			(stroke
				(width 0.1)
				(type solid)
			)
			(layer "F.SilkS")
		)
		(fp_line
			(start -0.094672 0.201008)
			(end -0.094672 -0.198992)
			(stroke
				(width 0.1)
				(type solid)
			)
			(layer "F.SilkS")
		)
		(fp_line
			(start 0.22 0.35)
			(end -0.22 0.35)
			(stroke
				(width 0.15)
				(type solid)
			)
			(layer "F.SilkS")
		)
		(fp_rect
			(start 1.25 0.65)
			(end -1.25 -0.65)
			(stroke
				(width 0.05)
				(type solid)
			)
			(fill no)
			(layer "F.CrtYd")
		)
		(fp_line
			(start 0.201 -0.202)
			(end -0.101 0)
			(stroke
				(width 0.15)
				(type solid)
			)
			(layer "F.Fab")
		)
		(fp_line
			(start -0.199 -0.202)
			(end -0.199 0.1)
			(stroke
				(width 0.15)
				(type solid)
			)
			(layer "F.Fab")
		)
		(fp_line
			(start 0.599 0)
			(end 0.201 0)
			(stroke
				(width 0.15)
				(type solid)
			)
			(layer "F.Fab")
		)
		(fp_line
			(start 0.201 0)
			(end 0.201 -0.202)
			(stroke
				(width 0.15)
				(type solid)
			)
			(layer "F.Fab")
		)
		(fp_line
			(start -0.101 0)
			(end 0.201 0.2)
			(stroke
				(width 0.15)
				(type solid)
			)
			(layer "F.Fab")
		)
		(fp_line
			(start -0.199 0)
			(end -0.597 0)
			(stroke
				(width 0.15)
				(type solid)
			)
			(layer "F.Fab")
		)
		(fp_line
			(start 0.201 0.2)
			(end 0.201 0)
			(stroke
				(width 0.15)
				(type solid)
			)
			(layer "F.Fab")
		)
		(fp_line
			(start -0.199 0.2)
			(end -0.199 0.1)
			(stroke
				(width 0.15)
				(type solid)
			)
			(layer "F.Fab")
		)
		(fp_rect
			(start 0.848 0.4)
			(end -0.85 -0.402)
			(stroke
				(width 0.15)
				(type solid)
			)
			(fill no)
			(layer "F.Fab")
		)
		(fp_text user "License: Apache-2.0"
			(at -1.4224 3.599 90)
			(layer "F.Fab")
			(effects
				(font
					(size 0.7 0.7)
					(thickness 0.15)
				)
				(justify left bottom)
			)
		)
		(fp_text user "Author: Antmicro"
			(at -1.4224 4.799 90)
			(layer "F.Fab")
			(effects
				(font
					(size 0.7 0.7)
					(thickness 0.15)
				)
				(justify left bottom)
			)
		)
		(fp_text user "${REFERENCE}"
			(at -1.4224 5.999 90)
			(layer "F.Fab")
			(effects
				(font
					(size 0.7 0.7)
					(thickness 0.15)
				)
				(justify left bottom)
			)
		)
		(pad "1" smd roundrect
			(at -0.7 0 270)
			(size 0.8 1)
			(layers "F.Cu" "F.Mask" "F.Paste")
			(roundrect_rratio 0.2)
			(net 1 "GND")
			(pinfunction "C")
			(pintype "passive")
		)
		(pad "2" smd roundrect
			(at 0.7 0 270)
			(size 0.8 1)
			(layers "F.Cu" "F.Mask" "F.Paste")
			(roundrect_rratio 0.2)
			(net 246 "Net-(D7-A)")
			(pinfunction "A")
			(pintype "passive")
		)
	)
	(footprint "antmicro-footprints:TP_SMD_0.75mm"
		(layer "F.Cu")
		(at 106.25 90.37 -90)
		(property "Reference" "TP16"
			(at -2.92 0.34 90)
			(layer "F.SilkS")
			(effects
				(font
					(size 0.65 0.65)
					(thickness 0.15)
				)
				(justify right top)
			)
		)
		(property "Value" "TP_0.75mm_SMD"
			(at 0 1.2 90)
			(layer "F.Fab")
			(hide yes)
			(effects
				(font
					(size 0.7 0.7)
					(thickness 0.15)
				)
				(justify right top)
			)
		)
		(property "Description" "SMT test point"
			(at 0 0 90)
			(layer "F.Fab")
			(hide yes)
			(effects
				(font
					(size 1.27 1.27)
					(thickness 0.15)
				)
			)
		)
		(property "Author" "Antmicro"
			(at 165.8 346.6 0)
			(layer "F.Fab")
			(hide yes)
			(effects
				(font
					(size 1 1)
					(thickness 0.15)
				)
			)
		)
		(property "License" "Apache-2.0"
			(at 165.8 346.6 0)
			(layer "F.Fab")
			(hide yes)
			(effects
				(font
					(size 1 1)
					(thickness 0.15)
				)
			)
		)
		(property "MPN" ""
			(at 165.8 346.6 0)
			(layer "F.Fab")
			(hide yes)
			(effects
				(font
					(size 1 1)
					(thickness 0.15)
				)
			)
		)
		(property "Manufacturer" ""
			(at 165.8 346.6 0)
			(layer "F.Fab")
			(hide yes)
			(effects
				(font
					(size 1 1)
					(thickness 0.15)
				)
			)
		)
		(sheetname "/FPGA/")
		(sheetfile "fpga.kicad_sch")
		(attr exclude_from_pos_files)
		(fp_circle
			(center 0 0)
			(end 0.475 0)
			(stroke
				(width 0.05)
				(type default)
			)
			(fill no)
			(layer "F.CrtYd")
		)
		(fp_text user "License: Apache-2.0"
			(at -0.4 5.101 90)
			(layer "F.Fab")
			(effects
				(font
					(size 0.7 0.7)
					(thickness 0.15)
				)
				(justify right top)
			)
		)
		(fp_text user "Author: Antmicro"
			(at -0.4 3.901 90)
			(layer "F.Fab")
			(effects
				(font
					(size 0.7 0.7)
					(thickness 0.15)
				)
				(justify right top)
			)
		)
		(fp_text user "${REFERENCE}"
			(at -0.4 2.7 90)
			(layer "F.Fab")
			(effects
				(font
					(size 0.7 0.7)
					(thickness 0.15)
				)
				(justify right top)
			)
		)
		(pad "1" smd circle
			(at 0 0 270)
			(size 0.75 0.75)
			(layers "F.Cu" "F.Mask")
			(net 301 "Net-(U18-SO{slash}IO1)")
			(pinfunction "1")
			(pintype "passive")
		)
	)
	(footprint "antmicro-footprints:R_0805_2012Metric"
		(layer "F.Cu")
		(at 161.19 57.54 90)
		(property "Reference" "R40"
			(at 0.26 -1.11 90)
			(layer "F.SilkS")
			(effects
				(font
					(size 0.65 0.65)
					(thickness 0.15)
				)
				(justify left bottom)
			)
		)
		(property "Value" "R_0R_0805"
			(at 0 1.8 90)
			(layer "F.Fab")
			(hide yes)
			(effects
				(font
					(size 0.7 0.7)
					(thickness 0.15)
				)
				(justify left bottom)
			)
		)
		(property "Datasheet" "https://www.vishay.com/docs/20035/dcrcwe3.pdf"
			(at 0 0 90)
			(layer "F.Fab")
			(hide yes)
			(effects
				(font
					(size 1.27 1.27)
					(thickness 0.15)
				)
			)
		)
		(property "Description" "Zero Ohm Resistor, Jumper, 0805 [2012 Metric], Thick Film, 125 mW, 2.5 A, Surface Mount Device"
			(at 0 0 90)
			(layer "F.Fab")
			(hide yes)
			(effects
				(font
					(size 1.27 1.27)
					(thickness 0.15)
				)
			)
		)
		(property "Author" "Antmicro"
			(at 218.79 -103.59 0)
			(layer "F.Fab")
			(hide yes)
			(effects
				(font
					(size 1 1)
					(thickness 0.15)
				)
			)
		)
		(property "Current" "2.5A"
			(at 218.79 -103.59 0)
			(layer "F.Fab")
			(hide yes)
			(effects
				(font
					(size 1 1)
					(thickness 0.15)
				)
			)
		)
		(property "License" "Apache-2.0"
			(at 218.79 -103.59 0)
			(layer "F.Fab")
			(hide yes)
			(effects
				(font
					(size 1 1)
					(thickness 0.15)
				)
			)
		)
		(property "MPN" "CRCW08050000Z0EA"
			(at 218.79 -103.59 0)
			(layer "F.Fab")
			(hide yes)
			(effects
				(font
					(size 1 1)
					(thickness 0.15)
				)
			)
		)
		(property "Manufacturer" "Vishay"
			(at 218.79 -103.59 0)
			(layer "F.Fab")
			(hide yes)
			(effects
				(font
					(size 1 1)
					(thickness 0.15)
				)
			)
		)
		(property "Tolerance" "~"
			(at 218.79 -103.59 0)
			(layer "F.Fab")
			(hide yes)
			(effects
				(font
					(size 1 1)
					(thickness 0.15)
				)
			)
		)
		(property "Val" "0R"
			(at 218.79 -103.59 0)
			(layer "F.Fab")
			(hide yes)
			(effects
				(font
					(size 1 1)
					(thickness 0.15)
				)
			)
		)
		(sheetname "/Power Supply/")
		(sheetfile "supply.kicad_sch")
		(attr smd)
		(fp_line
			(start -0.3 -0.701)
			(end 0.298 -0.701)
			(stroke
				(width 0.15)
				(type solid)
			)
			(layer "F.SilkS")
		)
		(fp_line
			(start -0.32 0.699)
			(end 0.28 0.699)
			(stroke
				(width 0.15)
				(type solid)
			)
			(layer "F.SilkS")
		)
		(fp_rect
			(start 1.95 -0.9)
			(end -1.95 0.9)
			(stroke
				(width 0.05)
				(type default)
			)
			(fill no)
			(layer "F.CrtYd")
		)
		(fp_line
			(start -0.951 -0.682)
			(end 0.949 -0.682)
			(stroke
				(width 0.15)
				(type solid)
			)
			(layer "F.Fab")
		)
		(fp_line
			(start 0.949 -0.677)
			(end 0.949 0.675)
			(stroke
				(width 0.15)
				(type solid)
			)
			(layer "F.Fab")
		)
		(fp_line
			(start -0.951 -0.677)
			(end -0.951 0.675)
			(stroke
				(width 0.15)
				(type solid)
			)
			(layer "F.Fab")
		)
		(fp_line
			(start -0.951 0.68)
			(end 0.949 0.68)
			(stroke
				(width 0.15)
				(type solid)
			)
			(layer "F.Fab")
		)
		(fp_text user "License: Apache-2.0"
			(at -1.9 5.75 90)
			(layer "F.Fab")
			(effects
				(font
					(size 0.7 0.7)
					(thickness 0.15)
				)
				(justify left bottom)
			)
		)
		(fp_text user "Author: Antmicro"
			(at -1.9 4.4 90)
			(layer "F.Fab")
			(effects
				(font
					(size 0.7 0.7)
					(thickness 0.15)
				)
				(justify left bottom)
			)
		)
		(fp_text user "${REFERENCE}"
			(at -1.9 3.1 90)
			(layer "F.Fab")
			(effects
				(font
					(size 0.7 0.7)
					(thickness 0.15)
				)
				(justify left bottom)
			)
		)
		(pad "1" smd roundrect
			(at -1.1 0 90)
			(size 1.2 1.3)
			(layers "F.Cu" "F.Mask" "F.Paste")
			(roundrect_rratio 0.25)
			(net 275 "/Power Supply/3V3_OUT")
			(pintype "passive")
		)
		(pad "2" smd roundrect
			(at 1.1 0 90)
			(size 1.2 1.3)
			(layers "F.Cu" "F.Mask" "F.Paste")
			(roundrect_rratio 0.25)
			(net 2 "+3V3")
			(pintype "passive")
		)
	)
	(footprint "antmicro-footprints:antmicro-logo_scaled_30mm"
		(layer "F.Cu")
		(at 100.900345 61.139847)
		(property "Reference" "G***"
			(at -7.7 -10.3 0)
			(layer "F.SilkS")
			(hide yes)
			(effects
				(font
					(size 0.65 0.65)
					(thickness 0.1625)
				)
			)
		)
		(property "Value" "LOGO"
			(at -5.3 10.1 0)
			(layer "F.SilkS")
			(hide yes)
			(effects
				(font
					(size 1.524 1.524)
					(thickness 0.3)
				)
			)
		)
		(attr exclude_from_pos_files exclude_from_bom allow_soldermask_bridges)
		(fp_poly
			(pts
				(xy 6.912132 1.55682) (xy 6.345204 1.55682) (xy 6.345204 -1.797504) (xy 6.912132 -1.797504) (xy 6.912132 1.55682)
			)
			(stroke
				(width 0.00279)
				(type solid)
			)
			(fill yes)
			(layer "F.Cu")
		)
		(fp_poly
			(pts
				(xy 11.340704 -1.841043) (xy 11.383146 -1.835075) (xy 11.399626 -1.825218) (xy 11.400312 -1.821945)
				(xy 11.393617 -1.787258) (xy 11.375745 -1.719809) (xy 11.35001 -1.631803) (xy 11.338272 -1.593625)
				(xy 11.306574 -1.497032) (xy 11.282387 -1.438676) (xy 11.261494 -1.411028) (xy 11.239676 -1.40656)
				(xy 11.234259 -1.407963) (xy 11.087402 -1.439293) (xy 10.923404 -1.449612) (xy 10.760846 -1.43919)
				(xy 10.618313 -1.408295) (xy 10.591259 -1.398688) (xy 10.526298 -1.373477) (xy 10.526298 1.55682)
				(xy 9.95937 1.55682) (xy 9.95937 -1.627357) (xy 10.130629 -1.688724) (xy 10.279454 -1.738722) (xy 10.415589 -1.775887)
				(xy 10.552002 -1.802432) (xy 10.701659 -1.820566) (xy 10.877526 -1.832501) (xy 11.004644 -1.837729)
				(xy 11.156748 -1.842159) (xy 11.267003 -1.843334) (xy 11.340704 -1.841043)
			)
			(stroke
				(width 0.00279)
				(type solid)
			)
			(fill yes)
			(layer "F.Cu")
		)
		(fp_poly
			(pts
				(xy 0.286882 -2.696334) (xy 0.291195 -2.633826) (xy 0.294644 -2.538397) (xy 0.296982 -2.41721) (xy 0.297958 -2.277426)
				(xy 0.297972 -2.258133) (xy 0.297972 -1.797504) (xy 0.8649 -1.797504) (xy 0.8649 -1.419552) (xy 0.297972 -1.419552)
				(xy 0.297972 0.887973) (xy 0.35171 0.989594) (xy 0.420809 1.086396) (xy 0.509669 1.146307) (xy 0.625356 1.172892)
				(xy 0.717312 1.174035) (xy 0.864999 1.167057) (xy 0.864949 1.348733) (xy 0.860772 1.460716) (xy 0.84846 1.528604)
				(xy 0.835373 1.548939) (xy 0.800261 1.557487) (xy 0.729644 1.565503) (xy 0.635257 1.571858) (xy 0.569625 1.57448)
				(xy 0.440081 1.575664) (xy 0.342385 1.569249) (xy 0.261533 1.553675) (xy 0.208325 1.536992) (xy 0.064544 1.469148)
				(xy -0.049904 1.37486) (xy -0.144592 1.245474) (xy -0.174468 1.191014) (xy -0.257145 1.030172) (xy -0.26386 -0.19469)
				(xy -0.270574 -1.419552) (xy -0.646908 -1.419552) (xy -0.646908 -1.797504) (xy -0.268956 -1.797504)
				(xy -0.268956 -2.551783) (xy -0.001508 -2.635272) (xy 0.104164 -2.667861) (xy 0.192964 -2.694497)
				(xy 0.255428 -2.712391) (xy 0.281956 -2.718762) (xy 0.286882 -2.696334)
			)
			(stroke
				(width 0.00279)
				(type solid)
			)
			(fill yes)
			(layer "F.Cu")
		)
		(fp_poly
			(pts
				(xy -2.136607 -1.83175) (xy -2.010904 -1.828463) (xy -1.914265 -1.822037) (xy -1.837617 -1.811764)
				(xy -1.771885 -1.796939) (xy -1.74634 -1.789492) (xy -1.532158 -1.70751) (xy -1.359129 -1.605683)
				(xy -1.224749 -1.482223) (xy -1.136379 -1.354088) (xy -1.108163 -1.301039) (xy -1.084174 -1.250965)
				(xy -1.064068 -1.19968) (xy -1.047504 -1.142994) (xy -1.034138 -1.076717) (xy -1.023628 -0.996662)
				(xy -1.015631 -0.89864) (xy -1.009804 -0.778462) (xy -1.005806 -0.63194) (xy -1.003292 -0.454884)
				(xy -1.001922 -0.243105) (xy -1.001351 0.007584) (xy -1.001238 0.298006) (xy -1.001238 1.55682)
				(xy -1.568166 1.55682) (xy -1.568166 0.309141) (xy -1.568286 0.015459) (xy -1.56889 -0.234942) (xy -1.570346 -0.44602)
				(xy -1.573022 -0.621739) (xy -1.577286 -0.766058) (xy -1.583506 -0.882939) (xy -1.592049 -0.976344)
				(xy -1.603283 -1.050233) (xy -1.617577 -1.108567) (xy -1.635297 -1.155309) (xy -1.656812 -1.194418)
				(xy -1.682489 -1.229857) (xy -1.712696 -1.265585) (xy -1.714581 -1.267734) (xy -1.812287 -1.355903)
				(xy -1.931432 -1.417802) (xy -2.082042 -1.458151) (xy -2.138368 -1.46726) (xy -2.29674 -1.477433)
				(xy -2.472019 -1.46882) (xy -2.642327 -1.443409) (xy -2.766455 -1.410218) (xy -2.855565 -1.37937)
				(xy -2.861649 0.088725) (xy -2.867734 1.55682) (xy -3.434304 1.55682) (xy -3.434304 -1.626184) (xy -3.215801 -1.697862)
				(xy -3.065439 -1.745385) (xy -2.937666 -1.780369) (xy -2.819819 -1.804679) (xy -2.699238 -1.820176)
				(xy -2.563261 -1.828726) (xy -2.399228 -1.832192) (xy -2.300448 -1.832603) (xy -2.136607 -1.83175)
			)
			(stroke
				(width 0.00279)
				(type solid)
			)
			(fill yes)
			(layer "F.Cu")
		)
		(fp_poly
			(pts
				(xy 4.729063 -1.8271) (xy 4.959571 -1.776882) (xy 5.157893 -1.693771) (xy 5.323148 -1.578206) (xy 5.454451 -1.43062)
				(xy 5.517493 -1.325064) (xy 5.542461 -1.274165) (xy 5.563676 -1.22495) (xy 5.581442 -1.173239) (xy 5.596064 -1.114853)
				(xy 5.607848 -1.045613) (xy 5.617099 -0.96134) (xy 5.624121 -0.857855) (xy 5.629219 -0.730978) (xy 5.632699 -0.576531)
				(xy 5.634866 -0.390333) (xy 5.636025 -0.168207) (xy 5.63648 0.094028) (xy 5.636544 0.306017) (xy 5.636544 1.55682)
				(xy 5.071143 1.55682) (xy 5.064474 0.251704) (xy 5.057805 -1.053411) (xy 4.988868 -1.177834) (xy 4.895109 -1.301546)
				(xy 4.773134 -1.393175) (xy 4.629913 -1.452165) (xy 4.472416 -1.477959) (xy 4.307613 -1.470001)
				(xy 4.142475 -1.427734) (xy 3.98397 -1.350603) (xy 3.870799 -1.267078) (xy 3.770406 -1.179651) (xy 3.770406 1.55682)
				(xy 3.203478 1.55682) (xy 3.203478 0.278067) (xy 3.203064 -0.042779) (xy 3.201801 -0.31793) (xy 3.19966 -0.548927)
				(xy 3.196609 -0.737311) (xy 3.192619 -0.884624) (xy 3.187659 -0.992408) (xy 3.181699 -1.062204)
				(xy 3.176515 -1.09068) (xy 3.113168 -1.224355) (xy 3.012925 -1.331319) (xy 2.878719 -1.410269) (xy 2.713483 -1.459907)
				(xy 2.52015 -1.478929) (xy 2.324287 -1.468768) (xy 2.217475 -1.455784) (xy 2.140831 -1.44347) (xy 2.077483 -1.428123)
				(xy 2.010555 -1.406041) (xy 1.969229 -1.39085) (xy 1.904268 -1.366577) (xy 1.904268 1.55682) (xy 1.360962 1.55682)
				(xy 1.360962 -1.629932) (xy 1.585996 -1.702017) (xy 1.839432 -1.773628) (xy 2.076192 -1.818337)
				(xy 2.316338 -1.838944) (xy 2.565684 -1.838752) (xy 2.765772 -1.826957) (xy 2.929729 -1.804535)
				(xy 3.068058 -1.768421) (xy 3.191262 -1.715547) (xy 3.309844 -1.64285) (xy 3.35863 -1.60731) (xy 3.513772 -1.489884)
				(xy 3.612561 -1.570037) (xy 3.803824 -1.696423) (xy 4.018585 -1.783662) (xy 4.258747 -1.832362)
				(xy 4.467255 -1.843989) (xy 4.729063 -1.8271)
			)
			(stroke
				(width 0.00279)
				(type solid)
			)
			(fill yes)
			(layer "F.Cu")
		)
		(fp_poly
			(pts
				(xy 13.011 -1.828598) (xy 13.222157 -1.780519) (xy 13.409082 -1.697802) (xy 13.577941 -1.578087)
				(xy 13.656079 -1.505081) (xy 13.8057 -1.322147) (xy 13.924227 -1.106958) (xy 14.012192 -0.85815)
				(xy 14.070128 -0.574357) (xy 14.090393 -0.390545) (xy 14.101846 -0.06018) (xy 14.082517 0.248736)
				(xy 14.033408 0.533287) (xy 13.955524 0.790553) (xy 13.849866 1.017617) (xy 13.717438 1.211561)
				(xy 13.559243 1.369467) (xy 13.461074 1.440241) (xy 13.306254 1.517112) (xy 13.121999 1.574401)
				(xy 12.922961 1.609506) (xy 12.723792 1.619827) (xy 12.542357 1.603344) (xy 12.30932 1.539496) (xy 12.102782 1.436939)
				(xy 11.923619 1.296654) (xy 11.772705 1.119624) (xy 11.650914 0.906828) (xy 11.559121 0.659249)
				(xy 11.509091 0.443636) (xy 11.467044 0.123703) (xy 11.458222 -0.133265) (xy 12.022913 -0.133265)
				(xy 12.033208 0.130412) (xy 12.06476 0.384026) (xy 12.117594 0.617116) (xy 12.189245 0.813805) (xy 12.281708 0.968837)
				(xy 12.398869 1.090076) (xy 12.534807 1.175098) (xy 12.683598 1.221477) (xy 12.839322 1.226788)
				(xy 12.996055 1.188608) (xy 13.048162 1.165468) (xy 13.180842 1.078195) (xy 13.290857 0.958674)
				(xy 13.37932 0.804507) (xy 13.447344 0.613298) (xy 13.496041 0.382646) (xy 13.524253 0.1395) (xy 13.536499 -0.156891)
				(xy 13.524426 -0.432929) (xy 13.488984 -0.684487) (xy 13.431119 -0.907435) (xy 13.351781 -1.097642)
				(xy 13.251917 -1.250979) (xy 13.189895 -1.316899) (xy 13.054995 -1.412386) (xy 12.90868 -1.465731)
				(xy 12.757488 -1.478493) (xy 12.607953 -1.452231) (xy 12.466612 -1.388504) (xy 12.340002 -1.288871)
				(xy 12.234658 -1.15489) (xy 12.193793 -1.079317) (xy 12.119314 -0.880028) (xy 12.065991 -0.648948)
				(xy 12.033849 -0.396539) (xy 12.022913 -0.133265) (xy 11.458222 -0.133265) (xy 11.456366 -0.187331)
				(xy 11.476106 -0.484529) (xy 11.525315 -0.762953) (xy 11.603043 -1.017667) (xy 11.70834 -1.243733)
				(xy 11.840256 -1.436213) (xy 11.879302 -1.480693) (xy 12.04917 -1.632047) (xy 12.241107 -1.742502)
				(xy 12.456488 -1.812618) (xy 12.696687 -1.842957) (xy 12.769446 -1.844399) (xy 13.011 -1.828598)
			)
			(stroke
				(width 0.00279)
				(type solid)
			)
			(fill yes)
			(layer "F.Cu")
		)
		(fp_poly
			(pts
				(xy 8.814213 -1.840483) (xy 8.969759 -1.825412) (xy 9.056281 -1.809134) (xy 9.145452 -1.783461)
				(xy 9.241206 -1.748594) (xy 9.331151 -1.709938) (xy 9.402898 -1.672901) (xy 9.444054 -1.642889)
				(xy 9.447346 -1.638505) (xy 9.444801 -1.609133) (xy 9.427786 -1.551422) (xy 9.401635 -1.478945)
				(xy 9.371683 -1.405273) (xy 9.343265 -1.343977) (xy 9.321716 -1.308629) (xy 9.316165 -1.304791)
				(xy 9.28701 -1.3133) (xy 9.228967 -1.336582) (xy 9.170199 -1.362544) (xy 8.989584 -1.425274) (xy 8.810705 -1.449653)
				(xy 8.641862 -1.435423) (xy 8.493873 -1.383637) (xy 8.370199 -1.295153) (xy 8.256869 -1.165361)
				(xy 8.157444 -0.999709) (xy 8.075486 -0.803644) (xy 8.04073 -0.690661) (xy 8.0133 -0.551431) (xy 7.995672 -0.37999)
				(xy 7.987846 -0.190341) (xy 7.989822 0.003512) (xy 8.001598 0.187565) (xy 8.023174 0.347814) (xy 8.040794 0.426604)
				(xy 8.120911 0.661281) (xy 8.221774 0.853813) (xy 8.343673 1.00464) (xy 8.4869 1.114204) (xy 8.498013 1.120496)
				(xy 8.570319 1.157192) (xy 8.633963 1.178299) (xy 8.70729 1.187849) (xy 8.808641 1.18987) (xy 8.813703 1.189851)
				(xy 8.920044 1.185178) (xy 9.013384 1.169314) (xy 9.108059 1.137943) (xy 9.218407 1.086747) (xy 9.300948 1.043176)
				(xy 9.311241 1.049795) (xy 9.329071 1.080783) (xy 9.356659 1.141006) (xy 9.396222 1.235333) (xy 9.449978 1.368632)
				(xy 9.455034 1.381317) (xy 9.441745 1.40673) (xy 9.393674 1.442381) (xy 9.32065 1.48296) (xy 9.232503 1.523157)
				(xy 9.139062 1.557662) (xy 9.114694 1.565169) (xy 8.987614 1.592214) (xy 8.834546 1.609553) (xy 8.675805 1.616006)
				(xy 8.531704 1.610388) (xy 8.471184 1.602631) (xy 8.382682 1.580174) (xy 8.27615 1.542853) (xy 8.175909 1.499329)
				(xy 7.979839 1.377324) (xy 7.810569 1.217033) (xy 7.668836 1.019577) (xy 7.555379 0.786076) (xy 7.470937 0.517652)
				(xy 7.442822 0.386949) (xy 7.422315 0.232254) (xy 7.411523 0.048978) (xy 7.410053 -0.149598) (xy 7.417508 -0.350189)
				(xy 7.433495 -0.539511) (xy 7.457618 -0.704283) (xy 7.477921 -0.793551) (xy 7.569718 -1.055031)
				(xy 7.690906 -1.282895) (xy 7.839972 -1.475439) (xy 8.015408 -1.630955) (xy 8.215702 -1.747738)
				(xy 8.375078 -1.807062) (xy 8.499369 -1.831256) (xy 8.651582 -1.842414) (xy 8.814213 -1.840483)
			)
			(stroke
				(width 0.00279)
				(type solid)
			)
			(fill yes)
			(layer "F.Cu")
		)
		(fp_poly
			(pts
				(xy -5.050123 -1.828751) (xy -4.900576 -1.800755) (xy -4.730837 -1.748715) (xy -4.593875 -1.684132)
				(xy -4.475494 -1.599519) (xy -4.417289 -1.545833) (xy -4.33145 -1.438632) (xy -4.25438 -1.301382)
				(xy -4.194656 -1.151275) (xy -4.167075 -1.044179) (xy -4.161601 -0.991002) (xy -4.156686 -0.894515)
				(xy -4.152404 -0.758651) (xy -4.14883 -0.587342) (xy -4.146038 -0.38452) (xy -4.144102 -0.154118)
				(xy -4.143096 0.099932) (xy -4.142964 0.236107) (xy -4.142964 1.389255) (xy -4.253676 1.438228)
				(xy -4.451908 1.509446) (xy -4.681546 1.56447) (xy -4.929024 1.601579) (xy -5.180775 1.61905) (xy -5.423232 1.615164)
				(xy -5.551117 1.602857) (xy -5.801683 1.552934) (xy -6.015853 1.473578) (xy -6.193196 1.365257)
				(xy -6.33328 1.228443) (xy -6.435674 1.063605) (xy -6.499947 0.871213) (xy -6.525669 0.651739) (xy -6.524424 0.541559)
				(xy -6.521414 0.520731) (xy -5.980195 0.520731) (xy -5.975801 0.716157) (xy -5.933333 0.885059)
				(xy -5.853697 1.026031) (xy -5.737804 1.137664) (xy -5.58656 1.218552) (xy -5.514208 1.242597) (xy -5.421778 1.258401)
				(xy -5.297997 1.265595) (xy -5.157857 1.264744) (xy -5.016352 1.25641) (xy -4.888475 1.241159) (xy -4.789219 1.219554)
				(xy -4.774853 1.214784) (xy -4.662648 1.174427) (xy -4.662648 -0.312718) (xy -4.798474 -0.29633)
				(xy -4.885159 -0.282693) (xy -4.997384 -0.260692) (xy -5.115103 -0.234352) (xy -5.152116 -0.225299)
				(xy -5.394278 -0.150849) (xy -5.593128 -0.059371) (xy -5.749805 0.050162) (xy -5.865449 0.178776)
				(xy -5.941198 0.327497) (xy -5.978194 0.497353) (xy -5.980195 0.520731) (xy -6.521414 0.520731)
				(xy -6.493668 0.328754) (xy -6.422351 0.139568) (xy -6.30958 -0.028039) (xy -6.245225 -0.096814)
				(xy -6.103026 -0.209801) (xy -5.920199 -0.31379) (xy -5.702882 -0.406508) (xy -5.457208 -0.48568)
				(xy -5.189315 -0.549035) (xy -4.905337 -0.594299) (xy -4.901094 -0.594815) (xy -4.656202 -0.624496)
				(xy -4.67036 -0.825112) (xy -4.697756 -1.014305) (xy -4.7521 -1.166118) (xy -4.835845 -1.283573)
				(xy -4.951447 -1.369689) (xy -5.101362 -1.427488) (xy -5.173118 -1.443664) (xy -5.368453 -1.460676)
				(xy -5.585568 -1.444404) (xy -5.814301 -1.396375) (xy -6.044491 -1.318113) (xy -6.064756 -1.309714)
				(xy -6.137401 -1.280895) (xy -6.190621 -1.263081) (xy -6.21177 -1.260016) (xy -6.223817 -1.284953)
				(xy -6.246487 -1.340557) (xy -6.274545 -1.412991) (xy -6.30276 -1.488418) (xy -6.325898 -1.553)
				(xy -6.338724 -1.592902) (xy -6.33981 -1.598556) (xy -6.320033 -1.613975) (xy -6.268692 -1.64124)
				(xy -6.210986 -1.6681) (xy -5.998934 -1.744812) (xy -5.763807 -1.80055) (xy -5.51862 -1.833998)
				(xy -5.276387 -1.843837) (xy -5.050123 -1.828751)
			)
			(stroke
				(width 0.00279)
				(type solid)
			)
			(fill yes)
			(layer "F.Cu")
		)
		(fp_poly
			(pts
				(xy -11.634962 -4.909269) (xy -11.537229 -4.886866) (xy -11.535595 -4.886192) (xy -11.504855 -4.870152)
				(xy -11.436833 -4.832523) (xy -11.335138 -4.775379) (xy -11.203377 -4.700793) (xy -11.045161 -4.610843)
				(xy -10.864096 -4.507601) (xy -10.663791 -4.393143) (xy -10.447855 -4.269542) (xy -10.219896 -4.138875)
				(xy -9.983523 -4.003215) (xy -9.742343 -3.864638) (xy -9.499965 -3.725217) (xy -9.259997 -3.587029)
				(xy -9.026048 -3.452146) (xy -8.801727 -3.322644) (xy -8.590641 -3.200598) (xy -8.396399 -3.088082)
				(xy -8.222609 -2.98717) (xy -8.07288 -2.899939) (xy -7.950819 -2.828462) (xy -7.860036 -2.774814)
				(xy -7.804139 -2.741069) (xy -7.797751 -2.737074) (xy -7.697553 -2.654792) (xy -7.620586 -2.556391)
				(xy -7.556343 -2.447109) (xy -7.549972 -0.195459) (xy -7.549017 0.235367) (xy -7.548701 0.6241)
				(xy -7.549022 0.970152) (xy -7.549975 1.272938) (xy -7.551555 1.53187) (xy -7.553759 1.746362) (xy -7.556581 1.915829)
				(xy -7.560017 2.039683) (xy -7.564064 2.117338) (xy -7.567619 2.145384) (xy -7.577264 2.180947)
				(xy -7.587545 2.213383) (xy -7.600916 2.244325) (xy -7.619829 2.275406) (xy -7.646736 2.30826) (xy -7.684091 2.344521)
				(xy -7.734346 2.385822) (xy -7.799953 2.433797) (xy -7.883366 2.49008) (xy -7.987037 2.556303) (xy -8.113418 2.634101)
				(xy -8.264963 2.725108) (xy -8.444124 2.830956) (xy -8.653354 2.953279) (xy -8.895105 3.093711)
				(xy -9.17183 3.253885) (xy -9.485981 3.435436) (xy -9.625797 3.516214) (xy -11.524839 4.613405)
				(xy -11.702004 4.622509) (xy -11.879169 4.631612) (xy -12.576018 4.230845) (xy -13.002735 3.985469)
				(xy -13.390442 3.762529) (xy -13.741039 3.560827) (xy -14.056425 3.379165) (xy -14.338499 3.216347)
				(xy -14.589159 3.071175) (xy -14.810305 2.942451) (xy -15.003836 2.828979) (xy -15.171651 2.729561)
				(xy -15.315648 2.643) (xy -15.437727 2.568099) (xy -15.539787 2.503659) (xy -15.623728 2.448485)
				(xy -15.691447 2.401378) (xy -15.744844 2.361141) (xy -15.785818 2.326577) (xy -15.816268 2.296489)
				(xy -15.838093 2.269678) (xy -15.853192 2.244949) (xy -15.863464 2.221104) (xy -15.870808 2.196945)
				(xy -15.877123 2.171275) (xy -15.883619 2.145435) (xy -15.888143 2.103987) (xy -15.892058 2.015869)
				(xy -15.895361 1.881652) (xy -15.898047 1.701907) (xy -15.900112 1.477205) (xy -15.901551 1.208115)
				(xy -15.902361 0.89521) (xy -15.902536 0.539059) (xy -15.902073 0.140233) (xy -15.901402 -0.143964)
				(xy -14.442156 -0.143964) (xy -14.442124 0.163081) (xy -14.441853 0.426492) (xy -14.441076 0.649878)
				(xy -14.439527 0.836849) (xy -14.436941 0.991014) (xy -14.433052 1.115983) (xy -14.427595 1.215365)
				(xy -14.420304 1.292771) (xy -14.410912 1.351809) (xy -14.399155 1.39609) (xy -14.384767 1.429223)
				(xy -14.367482 1.454817) (xy -14.347035 1.476482) (xy -14.323159 1.497828) (xy -14.321185 1.49955)
				(xy -14.289536 1.521118) (xy -14.221441 1.563277) (xy -14.121348 1.623467) (xy -13.993705 1.699126)
				(xy -13.842963 1.787694) (xy -13.67357 1.88661) (xy -13.489974 1.993314) (xy -13.296625 2.105246)
				(xy -13.097972 2.219844) (xy -12.898464 2.334548) (xy -12.702549 2.446797) (xy -12.514678 2.554031)
				(xy -12.339297 2.653689) (xy -12.180857 2.74321) (xy -12.043807 2.820035) (xy -11.932595 2.881601)
				(xy -11.85167 2.92535) (xy -11.805481 2.948719) (xy -11.798239 2.951643) (xy -11.739669 2.967611)
				(xy -11.698729 2.968556) (xy -11.650207 2.952973) (xy -11.621431 2.941108) (xy -11.582082 2.921398)
				(xy -11.507211 2.880786) (xy -11.401295 2.821862) (xy -11.26881 2.747214) (xy -11.114234 2.659433)
				(xy -10.942044 2.561108) (xy -10.756716 2.454828) (xy -10.562727 2.343182) (xy -10.364553 2.228759)
				(xy -10.166673 2.11415) (xy -9.973562 2.001942) (xy -9.789697 1.894726) (xy -9.619556 1.795091)
				(xy -9.467615 1.705626) (xy -9.338351 1.628921) (xy -9.236241 1.567564) (xy -9.165761 1.524145)
				(xy -9.131389 1.501254) (xy -9.130067 1.500156) (xy -9.105914 1.478431) (xy -9.08521 1.456719) (xy -9.06769 1.431407)
				(xy -9.053089 1.398882) (xy -9.04114 1.355531) (xy -9.031578 1.297741) (xy -9.024136 1.221898) (xy -9.01855 1.12439)
				(xy -9.014552 1.001603) (xy -9.011878 0.849924) (xy -9.010261 0.665741) (xy -9.009436 0.445438)
				(xy -9.009136 0.185404) (xy -9.009096 -0.117974) (xy -9.009096 -0.143964) (xy -9.0091 -0.452362)
				(xy -9.009321 -0.717103) (xy -9.010073 -0.941774) (xy -9.01167 -1.129961) (xy -9.014425 -1.285251)
				(xy -9.018653 -1.411232) (xy -9.024668 -1.511489) (xy -9.032783 -1.58961) (xy -9.043312 -1.649182)
				(xy -9.056569 -1.69379) (xy -9.072868 -1.727023) (xy -9.092523 -1.752467) (xy -9.115847 -1.773708)
				(xy -9.143156 -1.794333) (xy -9.154227 -1.80245) (xy -9.188912 -1.824767) (xy -9.260658 -1.868304)
				(xy -9.365548 -1.930764) (xy -9.499667 -2.009853) (xy -9.659099 -2.103275) (xy -9.839929 -2.208734)
				(xy -10.038241 -2.323934) (xy -10.250119 -2.44658) (xy -10.42874 -2.549657) (xy -10.683967 -2.696551)
				(xy -10.901677 -2.821355) (xy -11.085146 -2.925812) (xy -11.237649 -3.011663) (xy -11.362461 -3.080652)
				(xy -11.462857 -3.134521) (xy -11.542113 -3.175015) (xy -11.603503 -3.203875) (xy -11.650303 -3.222844)
				(xy -11.685788 -3.233665) (xy -11.713233 -3.238082) (xy -11.723096 -3.238446) (xy -11.747788 -3.236214)
				(xy -11.779117 -3.228375) (xy -11.820299 -3.213209) (xy -11.87455 -3.189) (xy -11.945086 -3.154031)
				(xy -12.035122 -3.106582) (xy -12.147874 -3.044939) (xy -12.286558 -2.967382) (xy -12.45439 -2.872194)
				(xy -12.654587 -2.757658) (xy -12.890362 -2.622057) (xy -13.055415 -2.526885) (xy -13.277555 -2.398503)
				(xy -13.488307 -2.276303) (xy -13.683963 -2.162462) (xy -13.860818 -2.059154) (xy -14.015167 -1.968555)
				(xy -14.143302 -1.892839) (xy -14.241518 -1.834183) (xy -14.30611 -1.79476) (xy -14.333212 -1.776887)
				(xy -14.354964 -1.757361) (xy -14.373609 -1.736701) (xy -14.389386 -1.711319) (xy -14.402536 -1.677626)
				(xy -14.413297 -1.632035) (xy -14.421909 -1.570958) (xy -14.428611 -1.490807) (xy -14.433642 -1.387994)
				(xy -14.437243 -1.258931) (xy -14.439651 -1.100029) (xy -14.441108 -0.907702) (xy -14.441851 -0.678361)
				(xy -14.44212 -0.408418) (xy -14.442156 -0.143964) (xy -15.901402 -0.143964) (xy -15.90128 -0.195459)
				(xy -15.900261 -0.578211) (xy -15.899381 -0.916603) (xy -15.898458 -1.213517) (xy -15.89731 -1.471836)
				(xy -15.895755 -1.694444) (xy -15.893611 -1.884222) (xy -15.890696 -2.044053) (xy -15.886827 -2.176821)
				(xy -15.881824 -2.285408) (xy -15.875504 -2.372697) (xy -15.867686 -2.441569) (xy -15.858186 -2.49491)
				(xy -15.846824 -2.535599) (xy -15.833418 -2.566522) (xy -15.817785 -2.59056) (xy -15.799743 -2.610596)
				(xy -15.779112 -2.629513) (xy -15.755708 -2.650193) (xy -15.745777 -2.659371) (xy -15.715671 -2.680398)
				(xy -15.647598 -2.723193) (xy -15.544554 -2.785985) (xy -15.409536 -2.867005) (xy -15.245541 -2.964486)
				(xy -15.055566 -3.076657) (xy -14.842607 -3.20175) (xy -14.609663 -3.337996) (xy -14.359728 -3.483626)
				(xy -14.0958 -3.636872) (xy -13.820877 -3.795963) (xy -13.791539 -3.812909) (xy -13.471051 -3.997959)
				(xy -13.18881 -4.160791) (xy -12.942164 -4.302841) (xy -12.728464 -4.425542) (xy -12.545058 -4.530328)
				(xy -12.389295 -4.618633) (xy -12.258526 -4.691893) (xy -12.150098 -4.751541) (xy -12.061361 -4.799011)
				(xy -11.989665 -4.835738) (xy -11.932359 -4.863157) (xy -11.886792 -4.8827) (xy -11.850312 -4.895803)
				(xy -11.820271 -4.9039) (xy -11.794016 -4.908426) (xy -11.768896 -4.910813) (xy -11.761531 -4.911305)
				(xy -11.634962 -4.909269)
			)
			(stroke
				(width 0.00279)
				(type solid)
			)
			(fill yes)
			(layer "F.Cu")
		)
		(fp_poly
			(pts
				(xy -11.598428 -2.080424) (xy -11.57723 -2.072066) (xy -11.468751 -2.001658) (xy -11.389638 -1.901364)
				(xy -11.34533 -1.781817) (xy -11.341267 -1.653648) (xy -11.347026 -1.622167) (xy -11.393935 -1.501154)
				(xy -11.47506 -1.410426) (xy -11.556887 -1.360523) (xy -11.65476 -1.313304) (xy -11.65476 -0.758136)
				(xy -11.242486 -0.758136) (xy -11.072717 -0.926772) (xy -10.902947 -1.095409) (xy -10.91549 -1.216935)
				(xy -10.915635 -1.219488) (xy -10.755191 -1.219488) (xy -10.728778 -1.164434) (xy -10.673757 -1.138779)
				(xy -10.607221 -1.144244) (xy -10.558024 -1.173208) (xy -10.524273 -1.228567) (xy -10.536119 -1.285278)
				(xy -10.568148 -1.325064) (xy -10.613088 -1.363188) (xy -10.650323 -1.366995) (xy -10.700942 -1.338104)
				(xy -10.704624 -1.335536) (xy -10.746388 -1.283194) (xy -10.755191 -1.219488) (xy -10.915635 -1.219488)
				(xy -10.919936 -1.294799) (xy -10.9095 -1.347615) (xy -10.878693 -1.396634) (xy -10.864682 -1.413748)
				(xy -10.778844 -1.486331) (xy -10.684406 -1.519496) (xy -10.589344 -1.517602) (xy -10.501633 -1.485007)
				(xy -10.429249 -1.426066) (xy -10.380166 -1.34514) (xy -10.36236 -1.246585) (xy -10.379014 -1.148379)
				(xy -10.432246 -1.055367) (xy -10.517668 -0.995483) (xy -10.631547 -0.971164) (xy -10.650843 -0.970734)
				(xy -10.700173 -0.969021) (xy -10.741166 -0.960188) (xy -10.782998 -0.93869) (xy -10.834845 -0.898984)
				(xy -10.905884 -0.835526) (xy -10.96366 -0.781758) (xy -11.165642 -0.592782) (xy -11.65476 -0.592782)
				(xy -11.65476 -0.21483) (xy -10.758337 -0.21483) (xy -10.723338 -0.282511) (xy -10.659408 -0.359534)
				(xy -10.571221 -0.40564) (xy -10.47149 -0.419331) (xy -10.372929 -0.399105) (xy -10.288248 -0.343464)
				(xy -10.280045 -0.334805) (xy -10.218985 -0.239159) (xy -10.198673 -0.141594) (xy -10.213428 -0.048914)
				(xy -10.257567 0.032077) (xy -10.325406 0.094573) (xy -10.411263 0.13177) (xy -10.509456 0.136864)
				(xy -10.614302 0.103049) (xy -10.63563 0.090981) (xy -10.690298 0.048218) (xy -10.724151 0.004288)
				(xy -10.726968 -0.003419) (xy -10.733524 -0.019303) (xy -10.747921 -0.031049) (xy -10.776503 -0.03928)
				(xy -10.825609 -0.044615) (xy -10.901582 -0.047677) (xy -11.010765 -0.049088) (xy -11.159498 -0.049469)
				(xy -11.196886 -0.049476) (xy -11.65476 -0.049476) (xy -11.65476 0.304854) (xy -11.169466 0.304854)
				(xy -10.777215 0.699153) (xy -10.666776 0.689665) (xy -10.54838 0.697916) (xy -10.45636 0.743895)
				(xy -10.393666 0.825779) (xy -10.377361 0.868512) (xy -10.361371 0.981493) (xy -10.388493 1.07909)
				(xy -10.447693 1.156536) (xy -10.539198 1.220541) (xy -10.636418 1.243765) (xy -10.730888 1.23049)
				(xy -10.81414 1.185001) (xy -10.877707 1.111581) (xy -10.913123 1.014512) (xy -10.914674 0.943593)
				(xy -10.75263 0.943593) (xy -10.744939 1.002359) (xy -10.722338 1.036421) (xy -10.668584 1.077858)
				(xy -10.616765 1.074443) (xy -10.568148 1.037136) (xy -10.527141 0.979502) (xy -10.530991 0.9279)
				(xy -10.5662 0.885356) (xy -10.625941 0.854578) (xy -10.683408 0.860296) (xy -10.728879 0.893103)
				(xy -10.75263 0.943593) (xy -10.914674 0.943593) (xy -10.91519 0.920035) (xy -10.901974 0.808447)
				(xy -11.242486 0.470208) (xy -11.65476 0.470208) (xy -11.65476 1.029961) (xy -11.557366 1.073879)
				(xy -11.455133 1.142987) (xy -11.384628 1.237535) (xy -11.346116 1.348001) (xy -11.33986 1.464867)
				(xy -11.366124 1.578613) (xy -11.42517 1.679718) (xy -11.517263 1.758662) (xy -11.538089 1.770152)
				(xy -11.661781 1.808862) (xy -11.793522 1.808868) (xy -11.91585 1.770223) (xy -11.918197 1.768995)
				(xy -12.015055 1.693955) (xy -12.078707 1.595232) (xy -12.109487 1.482413) (xy -12.108656 1.426899)
				(xy -11.947673 1.426899) (xy -11.938086 1.497165) (xy -11.90202 1.553977) (xy -11.87171 1.583435)
				(xy -11.784326 1.639137) (xy -11.698287 1.647711) (xy -11.61162 1.609158) (xy -11.579542 1.583435)
				(xy -11.526679 1.525013) (xy -11.505614 1.464095) (xy -11.503579 1.426899) (xy -11.524839 1.341071)
				(xy -11.580199 1.266709) (xy -11.65703 1.216575) (xy -11.725626 1.20249) (xy -11.81055 1.223976)
				(xy -11.88413 1.279925) (xy -11.933736 1.357574) (xy -11.947673 1.426899) (xy -12.108656 1.426899)
				(xy -12.107731 1.365086) (xy -12.073774 1.252838) (xy -12.007952 1.155256) (xy -11.9106 1.081929)
				(xy -11.893886 1.073879) (xy -11.796492 1.029961) (xy -11.796492 0.470208) (xy -12.208766 0.470208)
				(xy -12.549278 0.808447) (xy -12.536062 0.920035) (xy -12.541999 1.033334) (xy -12.583046 1.126506)
				(xy -12.650738 1.195267) (xy -12.736606 1.235334) (xy -12.832185 1.242424) (xy -12.929008 1.212252)
				(xy -13.003559 1.156536) (xy -13.069237 1.066034) (xy -13.090194 0.96674) (xy -13.085366 0.937646)
				(xy -12.92434 0.937646) (xy -12.919831 0.989652) (xy -12.883104 1.037136) (xy -12.825593 1.07811)
				(xy -12.774031 1.074247) (xy -12.730422 1.038088) (xy -12.700833 0.977326) (xy -12.708615 0.915658)
				(xy -12.749494 0.869261) (xy -12.778117 0.857531) (xy -12.847796 0.860939) (xy -12.884056 0.884454)
				(xy -12.92434 0.937646) (xy -13.085366 0.937646) (xy -13.073891 0.868512) (xy -13.02385 0.772676)
				(xy -12.943292 0.712009) (xy -12.83517 0.688335) (xy -12.784476 0.689665) (xy -12.674037 0.699153)
				(xy -12.281786 0.304854) (xy -11.796492 0.304854) (xy -11.796492 -0.049476) (xy -12.255529 -0.049476)
				(xy -12.413558 -0.049274) (xy -12.530739 -0.04823) (xy -12.613468 -0.045683) (xy -12.668141 -0.040976)
				(xy -12.701154 -0.033451) (xy -12.718903 -0.022447) (xy -12.727784 -0.007307) (xy -12.730078 -0.000602)
				(xy -12.768179 0.053795) (xy -12.836662 0.101408) (xy -12.918753 0.132562) (xy -12.97286 0.139412)
				(xy -13.081927 0.119662) (xy -13.16716 0.066135) (xy -13.224798 -0.01218) (xy -13.251082 -0.106295)
				(xy -13.248267 -0.138461) (xy -13.092435 -0.138461) (xy -13.085594 -0.104362) (xy -13.06173 -0.074712)
				(xy -12.999893 -0.032025) (xy -12.936774 -0.035011) (xy -12.896602 -0.062974) (xy -12.862603 -0.123872)
				(xy -12.869847 -0.163375) (xy -10.58825 -0.163375) (xy -10.579305 -0.097122) (xy -10.55465 -0.062974)
				(xy -10.494098 -0.028987) (xy -10.430729 -0.040964) (xy -10.389522 -0.074712) (xy -10.360749 -0.113869)
				(xy -10.362101 -0.149471) (xy -10.380745 -0.186917) (xy -10.430735 -0.241425) (xy -10.490836 -0.256827)
				(xy -10.549013 -0.230385) (xy -10.553393 -0.226211) (xy -10.58825 -0.163375) (xy -12.869847 -0.163375)
				(xy -12.874232 -0.187285) (xy -12.904968 -0.225051) (xy -12.965739 -0.256682) (xy -13.023234 -0.242178)
				(xy -13.070485 -0.18675) (xy -13.092435 -0.138461) (xy -13.248267 -0.138461) (xy -13.24225 -0.20722)
				(xy -13.194545 -0.305966) (xy -13.171207 -0.334805) (xy -13.086844 -0.396657) (xy -12.988403 -0.420452)
				(xy -12.887861 -0.407544) (xy -12.797197 -0.359286) (xy -12.733093 -0.285314) (xy -12.691457 -0.21483)
				(xy -11.796492 -0.21483) (xy -11.796492 -0.592782) (xy -12.28561 -0.592782) (xy -12.487592 -0.781758)
				(xy -12.574784 -0.862522) (xy -12.637071 -0.916226) (xy -12.683768 -0.948383) (xy -12.724188 -0.964507)
				(xy -12.767644 -0.970114) (xy -12.806775 -0.970734) (xy -12.922899 -0.987671) (xy -13.00786 -1.039568)
				(xy -13.063979 -1.128054) (xy -13.074609 -1.158837) (xy -13.084885 -1.244074) (xy -12.930348 -1.244074)
				(xy -12.910031 -1.190176) (xy -12.860199 -1.152565) (xy -12.797538 -1.137632) (xy -12.738728 -1.15177)
				(xy -12.722474 -1.164434) (xy -12.695969 -1.22018) (xy -12.705149 -1.283867) (xy -12.746628 -1.335536)
				(xy -12.791873 -1.362923) (xy -12.817494 -1.372308) (xy -12.851732 -1.3546) (xy -12.892344 -1.313705)
				(xy -12.923186 -1.267968) (xy -12.930348 -1.244074) (xy -13.084885 -1.244074) (xy -13.087974 -1.269701)
				(xy -13.063381 -1.365651) (xy -13.008888 -1.442479) (xy -12.932552 -1.495976) (xy -12.842431 -1.521934)
				(xy -12.746584 -1.516145) (xy -12.653067 -1.474399) (xy -12.58657 -1.413748) (xy -12.548594 -1.36173)
				(xy -12.532631 -1.312282) (xy -12.533195 -1.24415) (xy -12.535762 -1.216935) (xy -12.548305 -1.095409)
				(xy -12.378536 -0.926772) (xy -12.208766 -0.758136) (xy -11.796492 -0.758136) (xy -11.796492 -1.315972)
				(xy -11.890413 -1.35741) (xy -12.000362 -1.428554) (xy -12.074751 -1.530309) (xy -12.103547 -1.608413)
				(xy -12.114691 -1.719427) (xy -11.953136 -1.719427) (xy -11.944244 -1.665249) (xy -11.927218 -1.625373)
				(xy -11.866718 -1.543897) (xy -11.786289 -1.49957) (xy -11.696376 -1.495069) (xy -11.607427 -1.533073)
				(xy -11.597127 -1.540764) (xy -11.527435 -1.615972) (xy -11.503765 -1.69764) (xy -11.522499 -1.783736)
				(xy -11.579788 -1.872176) (xy -11.655413 -1.92277) (xy -11.739655 -1.935681) (xy -11.822795 -1.911076)
				(xy -11.895117 -1.849121) (xy -11.937073 -1.77666) (xy -11.953136 -1.719427) (xy -12.114691 -1.719427)
				(xy -12.116284 -1.735287) (xy -12.089238 -1.852462) (xy -12.0293 -1.953869) (xy -11.943361 -2.033438)
				(xy -11.838308 -2.0851) (xy -11.721034 -2.102786) (xy -11.598428 -2.080424)
			)
			(stroke
				(width 0.00279)
				(type solid)
			)
			(fill yes)
			(layer "F.Cu")
		)
		(fp_poly
			(pts
				(xy 6.912132 1.55682) (xy 6.345204 1.55682) (xy 6.345204 -1.797504) (xy 6.912132 -1.797504) (xy 6.912132 1.55682)
			)
			(stroke
				(width 0.00279)
				(type solid)
			)
			(fill yes)
			(layer "F.Mask")
		)
		(fp_poly
			(pts
				(xy 11.340704 -1.841043) (xy 11.383146 -1.835075) (xy 11.399626 -1.825218) (xy 11.400312 -1.821945)
				(xy 11.393617 -1.787258) (xy 11.375745 -1.719809) (xy 11.35001 -1.631803) (xy 11.338272 -1.593625)
				(xy 11.306574 -1.497032) (xy 11.282387 -1.438676) (xy 11.261494 -1.411028) (xy 11.239676 -1.40656)
				(xy 11.234259 -1.407963) (xy 11.087402 -1.439293) (xy 10.923404 -1.449612) (xy 10.760846 -1.43919)
				(xy 10.618313 -1.408295) (xy 10.591259 -1.398688) (xy 10.526298 -1.373477) (xy 10.526298 1.55682)
				(xy 9.95937 1.55682) (xy 9.95937 -1.627357) (xy 10.130629 -1.688724) (xy 10.279454 -1.738722) (xy 10.415589 -1.775887)
				(xy 10.552002 -1.802432) (xy 10.701659 -1.820566) (xy 10.877526 -1.832501) (xy 11.004644 -1.837729)
				(xy 11.156748 -1.842159) (xy 11.267003 -1.843334) (xy 11.340704 -1.841043)
			)
			(stroke
				(width 0.00279)
				(type solid)
			)
			(fill yes)
			(layer "F.Mask")
		)
		(fp_poly
			(pts
				(xy 0.286882 -2.696334) (xy 0.291195 -2.633826) (xy 0.294644 -2.538397) (xy 0.296982 -2.41721) (xy 0.297958 -2.277426)
				(xy 0.297972 -2.258133) (xy 0.297972 -1.797504) (xy 0.8649 -1.797504) (xy 0.8649 -1.419552) (xy 0.297972 -1.419552)
				(xy 0.297972 0.887973) (xy 0.35171 0.989594) (xy 0.420809 1.086396) (xy 0.509669 1.146307) (xy 0.625356 1.172892)
				(xy 0.717312 1.174035) (xy 0.864999 1.167057) (xy 0.864949 1.348733) (xy 0.860772 1.460716) (xy 0.84846 1.528604)
				(xy 0.835373 1.548939) (xy 0.800261 1.557487) (xy 0.729644 1.565503) (xy 0.635257 1.571858) (xy 0.569625 1.57448)
				(xy 0.440081 1.575664) (xy 0.342385 1.569249) (xy 0.261533 1.553675) (xy 0.208325 1.536992) (xy 0.064544 1.469148)
				(xy -0.049904 1.37486) (xy -0.144592 1.245474) (xy -0.174468 1.191014) (xy -0.257145 1.030172) (xy -0.26386 -0.19469)
				(xy -0.270574 -1.419552) (xy -0.646908 -1.419552) (xy -0.646908 -1.797504) (xy -0.268956 -1.797504)
				(xy -0.268956 -2.551783) (xy -0.001508 -2.635272) (xy 0.104164 -2.667861) (xy 0.192964 -2.694497)
				(xy 0.255428 -2.712391) (xy 0.281956 -2.718762) (xy 0.286882 -2.696334)
			)
			(stroke
				(width 0.00279)
				(type solid)
			)
			(fill yes)
			(layer "F.Mask")
		)
		(fp_poly
			(pts
				(xy -2.136607 -1.83175) (xy -2.010904 -1.828463) (xy -1.914265 -1.822037) (xy -1.837617 -1.811764)
				(xy -1.771885 -1.796939) (xy -1.74634 -1.789492) (xy -1.532158 -1.70751) (xy -1.359129 -1.605683)
				(xy -1.224749 -1.482223) (xy -1.136379 -1.354088) (xy -1.108163 -1.301039) (xy -1.084174 -1.250965)
				(xy -1.064068 -1.19968) (xy -1.047504 -1.142994) (xy -1.034138 -1.076717) (xy -1.023628 -0.996662)
				(xy -1.015631 -0.89864) (xy -1.009804 -0.778462) (xy -1.005806 -0.63194) (xy -1.003292 -0.454884)
				(xy -1.001922 -0.243105) (xy -1.001351 0.007584) (xy -1.001238 0.298006) (xy -1.001238 1.55682)
				(xy -1.568166 1.55682) (xy -1.568166 0.309141) (xy -1.568286 0.015459) (xy -1.56889 -0.234942) (xy -1.570346 -0.44602)
				(xy -1.573022 -0.621739) (xy -1.577286 -0.766058) (xy -1.583506 -0.882939) (xy -1.592049 -0.976344)
				(xy -1.603283 -1.050233) (xy -1.617577 -1.108567) (xy -1.635297 -1.155309) (xy -1.656812 -1.194418)
				(xy -1.682489 -1.229857) (xy -1.712696 -1.265585) (xy -1.714581 -1.267734) (xy -1.812287 -1.355903)
				(xy -1.931432 -1.417802) (xy -2.082042 -1.458151) (xy -2.138368 -1.46726) (xy -2.29674 -1.477433)
				(xy -2.472019 -1.46882) (xy -2.642327 -1.443409) (xy -2.766455 -1.410218) (xy -2.855565 -1.37937)
				(xy -2.861649 0.088725) (xy -2.867734 1.55682) (xy -3.434304 1.55682) (xy -3.434304 -1.626184) (xy -3.215801 -1.697862)
				(xy -3.065439 -1.745385) (xy -2.937666 -1.780369) (xy -2.819819 -1.804679) (xy -2.699238 -1.820176)
				(xy -2.563261 -1.828726) (xy -2.399228 -1.832192) (xy -2.300448 -1.832603) (xy -2.136607 -1.83175)
			)
			(stroke
				(width 0.00279)
				(type solid)
			)
			(fill yes)
			(layer "F.Mask")
		)
		(fp_poly
			(pts
				(xy 4.729063 -1.8271) (xy 4.959571 -1.776882) (xy 5.157893 -1.693771) (xy 5.323148 -1.578206) (xy 5.454451 -1.43062)
				(xy 5.517493 -1.325064) (xy 5.542461 -1.274165) (xy 5.563676 -1.22495) (xy 5.581442 -1.173239) (xy 5.596064 -1.114853)
				(xy 5.607848 -1.045613) (xy 5.617099 -0.96134) (xy 5.624121 -0.857855) (xy 5.629219 -0.730978) (xy 5.632699 -0.576531)
				(xy 5.634866 -0.390333) (xy 5.636025 -0.168207) (xy 5.63648 0.094028) (xy 5.636544 0.306017) (xy 5.636544 1.55682)
				(xy 5.071143 1.55682) (xy 5.064474 0.251704) (xy 5.057805 -1.053411) (xy 4.988868 -1.177834) (xy 4.895109 -1.301546)
				(xy 4.773134 -1.393175) (xy 4.629913 -1.452165) (xy 4.472416 -1.477959) (xy 4.307613 -1.470001)
				(xy 4.142475 -1.427734) (xy 3.98397 -1.350603) (xy 3.870799 -1.267078) (xy 3.770406 -1.179651) (xy 3.770406 1.55682)
				(xy 3.203478 1.55682) (xy 3.203478 0.278067) (xy 3.203064 -0.042779) (xy 3.201801 -0.31793) (xy 3.19966 -0.548927)
				(xy 3.196609 -0.737311) (xy 3.192619 -0.884624) (xy 3.187659 -0.992408) (xy 3.181699 -1.062204)
				(xy 3.176515 -1.09068) (xy 3.113168 -1.224355) (xy 3.012925 -1.331319) (xy 2.878719 -1.410269) (xy 2.713483 -1.459907)
				(xy 2.52015 -1.478929) (xy 2.324287 -1.468768) (xy 2.217475 -1.455784) (xy 2.140831 -1.44347) (xy 2.077483 -1.428123)
				(xy 2.010555 -1.406041) (xy 1.969229 -1.39085) (xy 1.904268 -1.366577) (xy 1.904268 1.55682) (xy 1.360962 1.55682)
				(xy 1.360962 -1.629932) (xy 1.585996 -1.702017) (xy 1.839432 -1.773628) (xy 2.076192 -1.818337)
				(xy 2.316338 -1.838944) (xy 2.565684 -1.838752) (xy 2.765772 -1.826957) (xy 2.929729 -1.804535)
				(xy 3.068058 -1.768421) (xy 3.191262 -1.715547) (xy 3.309844 -1.64285) (xy 3.35863 -1.60731) (xy 3.513772 -1.489884)
				(xy 3.612561 -1.570037) (xy 3.803824 -1.696423) (xy 4.018585 -1.783662) (xy 4.258747 -1.832362)
				(xy 4.467255 -1.843989) (xy 4.729063 -1.8271)
			)
			(stroke
				(width 0.00279)
				(type solid)
			)
			(fill yes)
			(layer "F.Mask")
		)
		(fp_poly
			(pts
				(xy 13.011 -1.828598) (xy 13.222157 -1.780519) (xy 13.409082 -1.697802) (xy 13.577941 -1.578087)
				(xy 13.656079 -1.505081) (xy 13.8057 -1.322147) (xy 13.924227 -1.106958) (xy 14.012192 -0.85815)
				(xy 14.070128 -0.574357) (xy 14.090393 -0.390545) (xy 14.101846 -0.06018) (xy 14.082517 0.248736)
				(xy 14.033408 0.533287) (xy 13.955524 0.790553) (xy 13.849866 1.017617) (xy 13.717438 1.211561)
				(xy 13.559243 1.369467) (xy 13.461074 1.440241) (xy 13.306254 1.517112) (xy 13.121999 1.574401)
				(xy 12.922961 1.609506) (xy 12.723792 1.619827) (xy 12.542357 1.603344) (xy 12.30932 1.539496) (xy 12.102782 1.436939)
				(xy 11.923619 1.296654) (xy 11.772705 1.119624) (xy 11.650914 0.906828) (xy 11.559121 0.659249)
				(xy 11.509091 0.443636) (xy 11.467044 0.123703) (xy 11.458222 -0.133265) (xy 12.022913 -0.133265)
				(xy 12.033208 0.130412) (xy 12.06476 0.384026) (xy 12.117594 0.617116) (xy 12.189245 0.813805) (xy 12.281708 0.968837)
				(xy 12.398869 1.090076) (xy 12.534807 1.175098) (xy 12.683598 1.221477) (xy 12.839322 1.226788)
				(xy 12.996055 1.188608) (xy 13.048162 1.165468) (xy 13.180842 1.078195) (xy 13.290857 0.958674)
				(xy 13.37932 0.804507) (xy 13.447344 0.613298) (xy 13.496041 0.382646) (xy 13.524253 0.1395) (xy 13.536499 -0.156891)
				(xy 13.524426 -0.432929) (xy 13.488984 -0.684487) (xy 13.431119 -0.907435) (xy 13.351781 -1.097642)
				(xy 13.251917 -1.250979) (xy 13.189895 -1.316899) (xy 13.054995 -1.412386) (xy 12.90868 -1.465731)
				(xy 12.757488 -1.478493) (xy 12.607953 -1.452231) (xy 12.466612 -1.388504) (xy 12.340002 -1.288871)
				(xy 12.234658 -1.15489) (xy 12.193793 -1.079317) (xy 12.119314 -0.880028) (xy 12.065991 -0.648948)
				(xy 12.033849 -0.396539) (xy 12.022913 -0.133265) (xy 11.458222 -0.133265) (xy 11.456366 -0.187331)
				(xy 11.476106 -0.484529) (xy 11.525315 -0.762953) (xy 11.603043 -1.017667) (xy 11.70834 -1.243733)
				(xy 11.840256 -1.436213) (xy 11.879302 -1.480693) (xy 12.04917 -1.632047) (xy 12.241107 -1.742502)
				(xy 12.456488 -1.812618) (xy 12.696687 -1.842957) (xy 12.769446 -1.844399) (xy 13.011 -1.828598)
			)
			(stroke
				(width 0.00279)
				(type solid)
			)
			(fill yes)
			(layer "F.Mask")
		)
		(fp_poly
			(pts
				(xy 8.814213 -1.840483) (xy 8.969759 -1.825412) (xy 9.056281 -1.809134) (xy 9.145452 -1.783461)
				(xy 9.241206 -1.748594) (xy 9.331151 -1.709938) (xy 9.402898 -1.672901) (xy 9.444054 -1.642889)
				(xy 9.447346 -1.638505) (xy 9.444801 -1.609133) (xy 9.427786 -1.551422) (xy 9.401635 -1.478945)
				(xy 9.371683 -1.405273) (xy 9.343265 -1.343977) (xy 9.321716 -1.308629) (xy 9.316165 -1.304791)
				(xy 9.28701 -1.3133) (xy 9.228967 -1.336582) (xy 9.170199 -1.362544) (xy 8.989584 -1.425274) (xy 8.810705 -1.449653)
				(xy 8.641862 -1.435423) (xy 8.493873 -1.383637) (xy 8.370199 -1.295153) (xy 8.256869 -1.165361)
				(xy 8.157444 -0.999709) (xy 8.075486 -0.803644) (xy 8.04073 -0.690661) (xy 8.0133 -0.551431) (xy 7.995672 -0.37999)
				(xy 7.987846 -0.190341) (xy 7.989822 0.003512) (xy 8.001598 0.187565) (xy 8.023174 0.347814) (xy 8.040794 0.426604)
				(xy 8.120911 0.661281) (xy 8.221774 0.853813) (xy 8.343673 1.00464) (xy 8.4869 1.114204) (xy 8.498013 1.120496)
				(xy 8.570319 1.157192) (xy 8.633963 1.178299) (xy 8.70729 1.187849) (xy 8.808641 1.18987) (xy 8.813703 1.189851)
				(xy 8.920044 1.185178) (xy 9.013384 1.169314) (xy 9.108059 1.137943) (xy 9.218407 1.086747) (xy 9.300948 1.043176)
				(xy 9.311241 1.049795) (xy 9.329071 1.080783) (xy 9.356659 1.141006) (xy 9.396222 1.235333) (xy 9.449978 1.368632)
				(xy 9.455034 1.381317) (xy 9.441745 1.40673) (xy 9.393674 1.442381) (xy 9.32065 1.48296) (xy 9.232503 1.523157)
				(xy 9.139062 1.557662) (xy 9.114694 1.565169) (xy 8.987614 1.592214) (xy 8.834546 1.609553) (xy 8.675805 1.616006)
				(xy 8.531704 1.610388) (xy 8.471184 1.602631) (xy 8.382682 1.580174) (xy 8.27615 1.542853) (xy 8.175909 1.499329)
				(xy 7.979839 1.377324) (xy 7.810569 1.217033) (xy 7.668836 1.019577) (xy 7.555379 0.786076) (xy 7.470937 0.517652)
				(xy 7.442822 0.386949) (xy 7.422315 0.232254) (xy 7.411523 0.048978) (xy 7.410053 -0.149598) (xy 7.417508 -0.350189)
				(xy 7.433495 -0.539511) (xy 7.457618 -0.704283) (xy 7.477921 -0.793551) (xy 7.569718 -1.055031)
				(xy 7.690906 -1.282895) (xy 7.839972 -1.475439) (xy 8.015408 -1.630955) (xy 8.215702 -1.747738)
				(xy 8.375078 -1.807062) (xy 8.499369 -1.831256) (xy 8.651582 -1.842414) (xy 8.814213 -1.840483)
			)
			(stroke
				(width 0.00279)
				(type solid)
			)
			(fill yes)
			(layer "F.Mask")
		)
		(fp_poly
			(pts
				(xy -5.050123 -1.828751) (xy -4.900576 -1.800755) (xy -4.730837 -1.748715) (xy -4.593875 -1.684132)
				(xy -4.475494 -1.599519) (xy -4.417289 -1.545833) (xy -4.33145 -1.438632) (xy -4.25438 -1.301382)
				(xy -4.194656 -1.151275) (xy -4.167075 -1.044179) (xy -4.161601 -0.991002) (xy -4.156686 -0.894515)
				(xy -4.152404 -0.758651) (xy -4.14883 -0.587342) (xy -4.146038 -0.38452) (xy -4.144102 -0.154118)
				(xy -4.143096 0.099932) (xy -4.142964 0.236107) (xy -4.142964 1.389255) (xy -4.253676 1.438228)
				(xy -4.451908 1.509446) (xy -4.681546 1.56447) (xy -4.929024 1.601579) (xy -5.180775 1.61905) (xy -5.423232 1.615164)
				(xy -5.551117 1.602857) (xy -5.801683 1.552934) (xy -6.015853 1.473578) (xy -6.193196 1.365257)
				(xy -6.33328 1.228443) (xy -6.435674 1.063605) (xy -6.499947 0.871213) (xy -6.525669 0.651739) (xy -6.524424 0.541559)
				(xy -6.521414 0.520731) (xy -5.980195 0.520731) (xy -5.975801 0.716157) (xy -5.933333 0.885059)
				(xy -5.853697 1.026031) (xy -5.737804 1.137664) (xy -5.58656 1.218552) (xy -5.514208 1.242597) (xy -5.421778 1.258401)
				(xy -5.297997 1.265595) (xy -5.157857 1.264744) (xy -5.016352 1.25641) (xy -4.888475 1.241159) (xy -4.789219 1.219554)
				(xy -4.774853 1.214784) (xy -4.662648 1.174427) (xy -4.662648 -0.312718) (xy -4.798474 -0.29633)
				(xy -4.885159 -0.282693) (xy -4.997384 -0.260692) (xy -5.115103 -0.234352) (xy -5.152116 -0.225299)
				(xy -5.394278 -0.150849) (xy -5.593128 -0.059371) (xy -5.749805 0.050162) (xy -5.865449 0.178776)
				(xy -5.941198 0.327497) (xy -5.978194 0.497353) (xy -5.980195 0.520731) (xy -6.521414 0.520731)
				(xy -6.493668 0.328754) (xy -6.422351 0.139568) (xy -6.30958 -0.028039) (xy -6.245225 -0.096814)
				(xy -6.103026 -0.209801) (xy -5.920199 -0.31379) (xy -5.702882 -0.406508) (xy -5.457208 -0.48568)
				(xy -5.189315 -0.549035) (xy -4.905337 -0.594299) (xy -4.901094 -0.594815) (xy -4.656202 -0.624496)
				(xy -4.67036 -0.825112) (xy -4.697756 -1.014305) (xy -4.7521 -1.166118) (xy -4.835845 -1.283573)
				(xy -4.951447 -1.369689) (xy -5.101362 -1.427488) (xy -5.173118 -1.443664) (xy -5.368453 -1.460676)
				(xy -5.585568 -1.444404) (xy -5.814301 -1.396375) (xy -6.044491 -1.318113) (xy -6.064756 -1.309714)
				(xy -6.137401 -1.280895) (xy -6.190621 -1.263081) (xy -6.21177 -1.260016) (xy -6.223817 -1.284953)
				(xy -6.246487 -1.340557) (xy -6.274545 -1.412991) (xy -6.30276 -1.488418) (xy -6.325898 -1.553)
				(xy -6.338724 -1.592902) (xy -6.33981 -1.598556) (xy -6.320033 -1.613975) (xy -6.268692 -1.64124)
				(xy -6.210986 -1.6681) (xy -5.998934 -1.744812) (xy -5.763807 -1.80055) (xy -5.51862 -1.833998)
				(xy -5.276387 -1.843837) (xy -5.050123 -1.828751)
			)
			(stroke
				(width 0.00279)
				(type solid)
			)
			(fill yes)
			(layer "F.Mask")
		)
		(fp_poly
			(pts
				(xy -11.634962 -4.909269) (xy -11.537229 -4.886866) (xy -11.535595 -4.886192) (xy -11.504855 -4.870152)
				(xy -11.436833 -4.832523) (xy -11.335138 -4.775379) (xy -11.203377 -4.700793) (xy -11.045161 -4.610843)
				(xy -10.864096 -4.507601) (xy -10.663791 -4.393143) (xy -10.447855 -4.269542) (xy -10.219896 -4.138875)
				(xy -9.983523 -4.003215) (xy -9.742343 -3.864638) (xy -9.499965 -3.725217) (xy -9.259997 -3.587029)
				(xy -9.026048 -3.452146) (xy -8.801727 -3.322644) (xy -8.590641 -3.200598) (xy -8.396399 -3.088082)
				(xy -8.222609 -2.98717) (xy -8.07288 -2.899939) (xy -7.950819 -2.828462) (xy -7.860036 -2.774814)
				(xy -7.804139 -2.741069) (xy -7.797751 -2.737074) (xy -7.697553 -2.654792) (xy -7.620586 -2.556391)
				(xy -7.556343 -2.447109) (xy -7.549972 -0.195459) (xy -7.549017 0.235367) (xy -7.548701 0.6241)
				(xy -7.549022 0.970152) (xy -7.549975 1.272938) (xy -7.551555 1.53187) (xy -7.553759 1.746362) (xy -7.556581 1.915829)
				(xy -7.560017 2.039683) (xy -7.564064 2.117338) (xy -7.567619 2.145384) (xy -7.577264 2.180947)
				(xy -7.587545 2.213383) (xy -7.600916 2.244325) (xy -7.619829 2.275406) (xy -7.646736 2.30826) (xy -7.684091 2.344521)
				(xy -7.734346 2.385822) (xy -7.799953 2.433797) (xy -7.883366 2.49008) (xy -7.987037 2.556303) (xy -8.113418 2.634101)
				(xy -8.264963 2.725108) (xy -8.444124 2.830956) (xy -8.653354 2.953279) (xy -8.895105 3.093711)
				(xy -9.17183 3.253885) (xy -9.485981 3.435436) (xy -9.625797 3.516214) (xy -11.524839 4.613405)
				(xy -11.702004 4.622509) (xy -11.879169 4.631612) (xy -12.576018 4.230845) (xy -13.002735 3.985469)
				(xy -13.390442 3.762529) (xy -13.741039 3.560827) (xy -14.056425 3.379165) (xy -14.338499 3.216347)
				(xy -14.589159 3.071175) (xy -14.810305 2.942451) (xy -15.003836 2.828979) (xy -15.171651 2.729561)
				(xy -15.315648 2.643) (xy -15.437727 2.568099) (xy -15.539787 2.503659) (xy -15.623728 2.448485)
				(xy -15.691447 2.401378) (xy -15.744844 2.361141) (xy -15.785818 2.326577) (xy -15.816268 2.296489)
				(xy -15.838093 2.269678) (xy -15.853192 2.244949) (xy -15.863464 2.221104) (xy -15.870808 2.196945)
				(xy -15.877123 2.171275) (xy -15.883619 2.145435) (xy -15.888143 2.103987) (xy -15.892058 2.015869)
				(xy -15.895361 1.881652) (xy -15.898047 1.701907) (xy -15.900112 1.477205) (xy -15.901551 1.208115)
				(xy -15.902361 0.89521) (xy -15.902536 0.539059) (xy -15.902073 0.140233) (xy -15.901402 -0.143964)
				(xy -14.442156 -0.143964) (xy -14.442124 0.163081) (xy -14.441853 0.426492) (xy -14.441076 0.649878)
				(xy -14.439527 0.836849) (xy -14.436941 0.991014) (xy -14.433052 1.115983) (xy -14.427595 1.215365)
				(xy -14.420304 1.292771) (xy -14.410912 1.351809) (xy -14.399155 1.39609) (xy -14.384767 1.429223)
				(xy -14.367482 1.454817) (xy -14.347035 1.476482) (xy -14.323159 1.497828) (xy -14.321185 1.49955)
				(xy -14.289536 1.521118) (xy -14.221441 1.563277) (xy -14.121348 1.623467) (xy -13.993705 1.699126)
				(xy -13.842963 1.787694) (xy -13.67357 1.88661) (xy -13.489974 1.993314) (xy -13.296625 2.105246)
				(xy -13.097972 2.219844) (xy -12.898464 2.334548) (xy -12.702549 2.446797) (xy -12.514678 2.554031)
				(xy -12.339297 2.653689) (xy -12.180857 2.74321) (xy -12.043807 2.820035) (xy -11.932595 2.881601)
				(xy -11.85167 2.92535) (xy -11.805481 2.948719) (xy -11.798239 2.951643) (xy -11.739669 2.967611)
				(xy -11.698729 2.968556) (xy -11.650207 2.952973) (xy -11.621431 2.941108) (xy -11.582082 2.921398)
				(xy -11.507211 2.880786) (xy -11.401295 2.821862) (xy -11.26881 2.747214) (xy -11.114234 2.659433)
				(xy -10.942044 2.561108) (xy -10.756716 2.454828) (xy -10.562727 2.343182) (xy -10.364553 2.228759)
				(xy -10.166673 2.11415) (xy -9.973562 2.001942) (xy -9.789697 1.894726) (xy -9.619556 1.795091)
				(xy -9.467615 1.705626) (xy -9.338351 1.628921) (xy -9.236241 1.567564) (xy -9.165761 1.524145)
				(xy -9.131389 1.501254) (xy -9.130067 1.500156) (xy -9.105914 1.478431) (xy -9.08521 1.456719) (xy -9.06769 1.431407)
				(xy -9.053089 1.398882) (xy -9.04114 1.355531) (xy -9.031578 1.297741) (xy -9.024136 1.221898) (xy -9.01855 1.12439)
				(xy -9.014552 1.001603) (xy -9.011878 0.849924) (xy -9.010261 0.665741) (xy -9.009436 0.445438)
				(xy -9.009136 0.185404) (xy -9.009096 -0.117974) (xy -9.009096 -0.143964) (xy -9.0091 -0.452362)
				(xy -9.009321 -0.717103) (xy -9.010073 -0.941774) (xy -9.01167 -1.129961) (xy -9.014425 -1.285251)
				(xy -9.018653 -1.411232) (xy -9.024668 -1.511489) (xy -9.032783 -1.58961) (xy -9.043312 -1.649182)
				(xy -9.056569 -1.69379) (xy -9.072868 -1.727023) (xy -9.092523 -1.752467) (xy -9.115847 -1.773708)
				(xy -9.143156 -1.794333) (xy -9.154227 -1.80245) (xy -9.188912 -1.824767) (xy -9.260658 -1.868304)
				(xy -9.365548 -1.930764) (xy -9.499667 -2.009853) (xy -9.659099 -2.103275) (xy -9.839929 -2.208734)
				(xy -10.038241 -2.323934) (xy -10.250119 -2.44658) (xy -10.42874 -2.549657) (xy -10.683967 -2.696551)
				(xy -10.901677 -2.821355) (xy -11.085146 -2.925812) (xy -11.237649 -3.011663) (xy -11.362461 -3.080652)
				(xy -11.462857 -3.134521) (xy -11.542113 -3.175015) (xy -11.603503 -3.203875) (xy -11.650303 -3.222844)
				(xy -11.685788 -3.233665) (xy -11.713233 -3.238082) (xy -11.723096 -3.238446) (xy -11.747788 -3.236214)
				(xy -11.779117 -3.228375) (xy -11.820299 -3.213209) (xy -11.87455 -3.189) (xy -11.945086 -3.154031)
				(xy -12.035122 -3.106582) (xy -12.147874 -3.044939) (xy -12.286558 -2.967382) (xy -12.45439 -2.872194)
				(xy -12.654587 -2.757658) (xy -12.890362 -2.622057) (xy -13.055415 -2.526885) (xy -13.277555 -2.398503)
				(xy -13.488307 -2.276303) (xy -13.683963 -2.162462) (xy -13.860818 -2.059154) (xy -14.015167 -1.968555)
				(xy -14.143302 -1.892839) (xy -14.241518 -1.834183) (xy -14.30611 -1.79476) (xy -14.333212 -1.776887)
				(xy -14.354964 -1.757361) (xy -14.373609 -1.736701) (xy -14.389386 -1.711319) (xy -14.402536 -1.677626)
				(xy -14.413297 -1.632035) (xy -14.421909 -1.570958) (xy -14.428611 -1.490807) (xy -14.433642 -1.387994)
				(xy -14.437243 -1.258931) (xy -14.439651 -1.100029) (xy -14.441108 -0.907702) (xy -14.441851 -0.678361)
				(xy -14.44212 -0.408418) (xy -14.442156 -0.143964) (xy -15.901402 -0.143964) (xy -15.90128 -0.195459)
				(xy -15.900261 -0.578211) (xy -15.899381 -0.916603) (xy -15.898458 -1.213517) (xy -15.89731 -1.471836)
				(xy -15.895755 -1.694444) (xy -15.893611 -1.884222) (xy -15.890696 -2.044053) (xy -15.886827 -2.176821)
				(xy -15.881824 -2.285408) (xy -15.875504 -2.372697) (xy -15.867686 -2.441569) (xy -15.858186 -2.49491)
				(xy -15.846824 -2.535599) (xy -15.833418 -2.566522) (xy -15.817785 -2.59056) (xy -15.799743 -2.610596)
				(xy -15.779112 -2.629513) (xy -15.755708 -2.650193) (xy -15.745777 -2.659371) (xy -15.715671 -2.680398)
				(xy -15.647598 -2.723193) (xy -15.544554 -2.785985) (xy -15.409536 -2.867005) (xy -15.245541 -2.964486)
				(xy -15.055566 -3.076657) (xy -14.842607 -3.20175) (xy -14.609663 -3.337996) (xy -14.359728 -3.483626)
				(xy -14.0958 -3.636872) (xy -13.820877 -3.795963) (xy -13.791539 -3.812909) (xy -13.471051 -3.997959)
				(xy -13.18881 -4.160791) (xy -12.942164 -4.302841) (xy -12.728464 -4.425542) (xy -12.545058 -4.530328)
				(xy -12.389295 -4.618633) (xy -12.258526 -4.691893) (xy -12.150098 -4.751541) (xy -12.061361 -4.799011)
				(xy -11.989665 -4.835738) (xy -11.932359 -4.863157) (xy -11.886792 -4.8827) (xy -11.850312 -4.895803)
				(xy -11.820271 -4.9039) (xy -11.794016 -4.908426) (xy -11.768896 -4.910813) (xy -11.761531 -4.911305)
				(xy -11.634962 -4.909269)
			)
			(stroke
				(width 0.00279)
				(type solid)
			)
			(fill yes)
			(layer "F.Mask")
		)
		(fp_poly
			(pts
				(xy -11.598428 -2.080424) (xy -11.57723 -2.072066) (xy -11.468751 -2.001658) (xy -11.389638 -1.901364)
				(xy -11.34533 -1.781817) (xy -11.341267 -1.653648) (xy -11.347026 -1.622167) (xy -11.393935 -1.501154)
				(xy -11.47506 -1.410426) (xy -11.556887 -1.360523) (xy -11.65476 -1.313304) (xy -11.65476 -0.758136)
				(xy -11.242486 -0.758136) (xy -11.072717 -0.926772) (xy -10.902947 -1.095409) (xy -10.91549 -1.216935)
				(xy -10.915635 -1.219488) (xy -10.755191 -1.219488) (xy -10.728778 -1.164434) (xy -10.673757 -1.138779)
				(xy -10.607221 -1.144244) (xy -10.558024 -1.173208) (xy -10.524273 -1.228567) (xy -10.536119 -1.285278)
				(xy -10.568148 -1.325064) (xy -10.613088 -1.363188) (xy -10.650323 -1.366995) (xy -10.700942 -1.338104)
				(xy -10.704624 -1.335536) (xy -10.746388 -1.283194) (xy -10.755191 -1.219488) (xy -10.915635 -1.219488)
				(xy -10.919936 -1.294799) (xy -10.9095 -1.347615) (xy -10.878693 -1.396634) (xy -10.864682 -1.413748)
				(xy -10.778844 -1.486331) (xy -10.684406 -1.519496) (xy -10.589344 -1.517602) (xy -10.501633 -1.485007)
				(xy -10.429249 -1.426066) (xy -10.380166 -1.34514) (xy -10.36236 -1.246585) (xy -10.379014 -1.148379)
				(xy -10.432246 -1.055367) (xy -10.517668 -0.995483) (xy -10.631547 -0.971164) (xy -10.650843 -0.970734)
				(xy -10.700173 -0.969021) (xy -10.741166 -0.960188) (xy -10.782998 -0.93869) (xy -10.834845 -0.898984)
				(xy -10.905884 -0.835526) (xy -10.96366 -0.781758) (xy -11.165642 -0.592782) (xy -11.65476 -0.592782)
				(xy -11.65476 -0.21483) (xy -10.758337 -0.21483) (xy -10.723338 -0.282511) (xy -10.659408 -0.359534)
				(xy -10.571221 -0.40564) (xy -10.47149 -0.419331) (xy -10.372929 -0.399105) (xy -10.288248 -0.343464)
				(xy -10.280045 -0.334805) (xy -10.218985 -0.239159) (xy -10.198673 -0.141594) (xy -10.213428 -0.048914)
				(xy -10.257567 0.032077) (xy -10.325406 0.094573) (xy -10.411263 0.13177) (xy -10.509456 0.136864)
				(xy -10.614302 0.103049) (xy -10.63563 0.090981) (xy -10.690298 0.048218) (xy -10.724151 0.004288)
				(xy -10.726968 -0.003419) (xy -10.733524 -0.019303) (xy -10.747921 -0.031049) (xy -10.776503 -0.03928)
				(xy -10.825609 -0.044615) (xy -10.901582 -0.047677) (xy -11.010765 -0.049088) (xy -11.159498 -0.049469)
				(xy -11.196886 -0.049476) (xy -11.65476 -0.049476) (xy -11.65476 0.304854) (xy -11.169466 0.304854)
				(xy -10.777215 0.699153) (xy -10.666776 0.689665) (xy -10.54838 0.697916) (xy -10.45636 0.743895)
				(xy -10.393666 0.825779) (xy -10.377361 0.868512) (xy -10.361371 0.981493) (xy -10.388493 1.07909)
				(xy -10.447693 1.156536) (xy -10.539198 1.220541) (xy -10.636418 1.243765) (xy -10.730888 1.23049)
				(xy -10.81414 1.185001) (xy -10.877707 1.111581) (xy -10.913123 1.014512) (xy -10.914674 0.943593)
				(xy -10.75263 0.943593) (xy -10.744939 1.002359) (xy -10.722338 1.036421) (xy -10.668584 1.077858)
				(xy -10.616765 1.074443) (xy -10.568148 1.037136) (xy -10.527141 0.979502) (xy -10.530991 0.9279)
				(xy -10.5662 0.885356) (xy -10.625941 0.854578) (xy -10.683408 0.860296) (xy -10.728879 0.893103)
				(xy -10.75263 0.943593) (xy -10.914674 0.943593) (xy -10.91519 0.920035) (xy -10.901974 0.808447)
				(xy -11.242486 0.470208) (xy -11.65476 0.470208) (xy -11.65476 1.029961) (xy -11.557366 1.073879)
				(xy -11.455133 1.142987) (xy -11.384628 1.237535) (xy -11.346116 1.348001) (xy -11.33986 1.464867)
				(xy -11.366124 1.578613) (xy -11.42517 1.679718) (xy -11.517263 1.758662) (xy -11.538089 1.770152)
				(xy -11.661781 1.808862) (xy -11.793522 1.808868) (xy -11.91585 1.770223) (xy -11.918197 1.768995)
				(xy -12.015055 1.693955) (xy -12.078707 1.595232) (xy -12.109487 1.482413) (xy -12.108656 1.426899)
				(xy -11.947673 1.426899) (xy -11.938086 1.497165) (xy -11.90202 1.553977) (xy -11.87171 1.583435)
				(xy -11.784326 1.639137) (xy -11.698287 1.647711) (xy -11.61162 1.609158) (xy -11.579542 1.583435)
				(xy -11.526679 1.525013) (xy -11.505614 1.464095) (xy -11.503579 1.426899) (xy -11.524839 1.341071)
				(xy -11.580199 1.266709) (xy -11.65703 1.216575) (xy -11.725626 1.20249) (xy -11.81055 1.223976)
				(xy -11.88413 1.279925) (xy -11.933736 1.357574) (xy -11.947673 1.426899) (xy -12.108656 1.426899)
				(xy -12.107731 1.365086) (xy -12.073774 1.252838) (xy -12.007952 1.155256) (xy -11.9106 1.081929)
				(xy -11.893886 1.073879) (xy -11.796492 1.029961) (xy -11.796492 0.470208) (xy -12.208766 0.470208)
				(xy -12.549278 0.808447) (xy -12.536062 0.920035) (xy -12.541999 1.033334) (xy -12.583046 1.126506)
				(xy -12.650738 1.195267) (xy -12.736606 1.235334) (xy -12.832185 1.242424) (xy -12.929008 1.212252)
				(xy -13.003559 1.156536) (xy -13.069237 1.066034) (xy -13.090194 0.96674) (xy -13.085366 0.937646)
				(xy -12.92434 0.937646) (xy -12.919831 0.989652) (xy -12.883104 1.037136) (xy -12.825593 1.07811)
				(xy -12.774031 1.074247) (xy -12.730422 1.038088) (xy -12.700833 0.977326) (xy -12.708615 0.915658)
				(xy -12.749494 0.869261) (xy -12.778117 0.857531) (xy -12.847796 0.860939) (xy -12.884056 0.884454)
				(xy -12.92434 0.937646) (xy -13.085366 0.937646) (xy -13.073891 0.868512) (xy -13.02385 0.772676)
				(xy -12.943292 0.712009) (xy -12.83517 0.688335) (xy -12.784476 0.689665) (xy -12.674037 0.699153)
				(xy -12.281786 0.304854) (xy -11.796492 0.304854) (xy -11.796492 -0.049476) (xy -12.255529 -0.049476)
				(xy -12.413558 -0.049274) (xy -12.530739 -0.04823) (xy -12.613468 -0.045683) (xy -12.668141 -0.040976)
				(xy -12.701154 -0.033451) (xy -12.718903 -0.022447) (xy -12.727784 -0.007307) (xy -12.730078 -0.000602)
				(xy -12.768179 0.053795) (xy -12.836662 0.101408) (xy -12.918753 0.132562) (xy -12.97286 0.139412)
				(xy -13.081927 0.119662) (xy -13.16716 0.066135) (xy -13.224798 -0.01218) (xy -13.251082 -0.106295)
				(xy -13.248267 -0.138461) (xy -13.092435 -0.138461) (xy -13.085594 -0.104362) (xy -13.06173 -0.074712)
				(xy -12.999893 -0.032025) (xy -12.936774 -0.035011) (xy -12.896602 -0.062974) (xy -12.862603 -0.123872)
				(xy -12.869847 -0.163375) (xy -10.58825 -0.163375) (xy -10.579305 -0.097122) (xy -10.55465 -0.062974)
				(xy -10.494098 -0.028987) (xy -10.430729 -0.040964) (xy -10.389522 -0.074712) (xy -10.360749 -0.113869)
				(xy -10.362101 -0.149471) (xy -10.380745 -0.186917) (xy -10.430735 -0.241425) (xy -10.490836 -0.256827)
				(xy -10.549013 -0.230385) (xy -10.553393 -0.226211) (xy -10.58825 -0.163375) (xy -12.869847 -0.163375)
				(xy -12.874232 -0.187285) (xy -12.904968 -0.225051) (xy -12.965739 -0.256682) (xy -13.023234 -0.242178)
				(xy -13.070485 -0.18675) (xy -13.092435 -0.138461) (xy -13.248267 -0.138461) (xy -13.24225 -0.20722)
				(xy -13.194545 -0.305966) (xy -13.171207 -0.334805) (xy -13.086844 -0.396657) (xy -12.988403 -0.420452)
				(xy -12.887861 -0.407544) (xy -12.797197 -0.359286) (xy -12.733093 -0.285314) (xy -12.691457 -0.21483)
				(xy -11.796492 -0.21483) (xy -11.796492 -0.592782) (xy -12.28561 -0.592782) (xy -12.487592 -0.781758)
				(xy -12.574784 -0.862522) (xy -12.637071 -0.916226) (xy -12.683768 -0.948383) (xy -12.724188 -0.964507)
				(xy -12.767644 -0.970114) (xy -12.806775 -0.970734) (xy -12.922899 -0.987671) (xy -13.00786 -1.039568)
				(xy -13.063979 -1.128054) (xy -13.074609 -1.158837) (xy -13.084885 -1.244074) (xy -12.930348 -1.244074)
				(xy -12.910031 -1.190176) (xy -12.860199 -1.152565) (xy -12.797538 -1.137632) (xy -12.738728 -1.15177)
				(xy -12.722474 -1.164434) (xy -12.695969 -1.22018) (xy -12.705149 -1.283867) (xy -12.746628 -1.335536)
				(xy -12.791873 -1.362923) (xy -12.817494 -1.372308) (xy -12.851732 -1.3546) (xy -12.892344 -1.313705)
				(xy -12.923186 -1.267968) (xy -12.930348 -1.244074) (xy -13.084885 -1.244074) (xy -13.087974 -1.269701)
				(xy -13.063381 -1.365651) (xy -13.008888 -1.442479) (xy -12.932552 -1.495976) (xy -12.842431 -1.521934)
				(xy -12.746584 -1.516145) (xy -12.653067 -1.474399) (xy -12.58657 -1.413748) (xy -12.548594 -1.36173)
				(xy -12.532631 -1.312282) (xy -12.533195 -1.24415) (xy -12.535762 -1.216935) (xy -12.548305 -1.095409)
				(xy -12.378536 -0.926772) (xy -12.208766 -0.758136) (xy -11.796492 -0.758136) (xy -11.796492 -1.315972)
				(xy -11.890413 -1.35741) (xy -12.000362 -1.428554) (xy -12.074751 -1.530309) (xy -12.103547 -1.608413)
				(xy -12.114691 -1.719427) (xy -11.953136 -1.719427) (xy -11.944244 -1.665249) (xy -11.927218 -1.625373)
				(xy -11.866718 -1.543897) (xy -11.786289 -1.49957) (xy -11.696376 -1.495069) (xy -11.607427 -1.533073)
				(xy -11.597127 -1.540764) (xy -11.527435 -1.615972) (xy -11.503765 -1.69764) (xy -11.522499 -1.783736)
				(xy -11.579788 -1.872176) (xy -11.655413 -1.92277) (xy -11.739655 -1.935681) (xy -11.822795 -1.911076)
				(xy -11.895117 -1.849121) (xy -11.937073 -1.77666) (xy -11.953136 -1.719427) (xy -12.114691 -1.719427)
				(xy -12.116284 -1.735287) (xy -12.089238 -1.852462) (xy -12.0293 -1.953869) (xy -11.943361 -2.033438)
				(xy -11.838308 -2.0851) (xy -11.721034 -2.102786) (xy -11.598428 -2.080424)
			)
			(stroke
				(width 0.00279)
				(type solid)
			)
			(fill yes)
			(layer "F.Mask")
		)
		(fp_rect
			(start -19.374 -8.384)
			(end 17.584 8.104)
			(stroke
				(width 0.05)
				(type default)
			)
			(fill no)
			(layer "F.CrtYd")
		)
	)
	(footprint "antmicro-footprints:R_0402_1005Metric"
		(layer "F.Cu")
		(at 85.2 105.15 180)
		(descr "Resistor SMD 0402")
		(tags "resistor SMD 0402")
		(property "Reference" "R61"
			(at -4.23 7.91 0)
			(layer "F.SilkS")
			(effects
				(font
					(size 0.65 0.65)
					(thickness 0.15)
				)
				(justify right bottom)
			)
		)
		(property "Value" "R_75R_0402"
			(at 0 1.4 0)
			(layer "F.Fab")
			(hide yes)
			(effects
				(font
					(size 0.7 0.7)
					(thickness 0.15)
				)
				(justify right bottom)
			)
		)
		(property "Datasheet" "https://www.bourns.com/docs/product-datasheets/cr.pdf"
			(at 0 0 180)
			(layer "F.Fab")
			(hide yes)
			(effects
				(font
					(size 1.27 1.27)
					(thickness 0.15)
				)
			)
		)
		(property "Description" "SMD Chip Resistor, 75 ohm, ± 1%, 62.5 mW, 0402 [1005 Metric], Thick Film, General Purpose"
			(at 0 0 180)
			(layer "F.Fab")
			(hide yes)
			(effects
				(font
					(size 1.27 1.27)
					(thickness 0.15)
				)
			)
		)
		(property "Author" "Antmicro"
			(at 170.4 210.3 0)
			(layer "F.Fab")
			(hide yes)
			(effects
				(font
					(size 1 1)
					(thickness 0.15)
				)
			)
		)
		(property "License" "Apache-2.0"
			(at 170.4 210.3 0)
			(layer "F.Fab")
			(hide yes)
			(effects
				(font
					(size 1 1)
					(thickness 0.15)
				)
			)
		)
		(property "MPN" "CR0402-FX-75R0GLF"
			(at 170.4 210.3 0)
			(layer "F.Fab")
			(hide yes)
			(effects
				(font
					(size 1 1)
					(thickness 0.15)
				)
			)
		)
		(property "Manufacturer" "Bourns"
			(at 170.4 210.3 0)
			(layer "F.Fab")
			(hide yes)
			(effects
				(font
					(size 1 1)
					(thickness 0.15)
				)
			)
		)
		(property "Tolerance" "1%"
			(at 170.4 210.3 0)
			(layer "F.Fab")
			(hide yes)
			(effects
				(font
					(size 1 1)
					(thickness 0.15)
				)
			)
		)
		(property "Val" "75R"
			(at 170.4 210.3 0)
			(layer "F.Fab")
			(hide yes)
			(effects
				(font
					(size 1 1)
					(thickness 0.15)
				)
			)
		)
		(sheetname "/SDI/")
		(sheetfile "sdi.kicad_sch")
		(attr smd)
		(fp_rect
			(start -0.925 -0.47)
			(end 0.925 0.47)
			(stroke
				(width 0.05)
				(type default)
			)
			(fill no)
			(layer "F.CrtYd")
		)
		(fp_rect
			(start -0.5 -0.25)
			(end 0.5 0.25)
			(stroke
				(width 0.15)
				(type solid)
			)
			(fill no)
			(layer "F.Fab")
		)
		(fp_text user "Author: Antmicro"
			(at -0.95 4.169 180)
			(layer "F.Fab")
			(effects
				(font
					(size 0.7 0.7)
					(thickness 0.15)
				)
				(justify left bottom)
			)
		)
		(fp_text user "${REFERENCE}"
			(at -0.95 3.168 180)
			(layer "F.Fab")
			(effects
				(font
					(size 0.7 0.7)
					(thickness 0.15)
				)
				(justify left bottom)
			)
		)
		(fp_text user "License: Apache-2.0"
			(at -0.95 5.169 180)
			(layer "F.Fab")
			(effects
				(font
					(size 0.7 0.7)
					(thickness 0.15)
				)
				(justify left bottom)
			)
		)
		(pad "1" smd roundrect
			(at -0.48 0 180)
			(size 0.59 0.64)
			(layers "F.Cu" "F.Mask" "F.Paste")
			(roundrect_rratio 0.25)
			(net 254 "/SDI/SDI_OUT_N")
			(pintype "passive")
		)
		(pad "2" smd roundrect
			(at 0.48 0 180)
			(size 0.59 0.64)
			(layers "F.Cu" "F.Mask" "F.Paste")
			(roundrect_rratio 0.25)
			(net 251 "/SDI/SDI_OUT_F2")
			(pintype "passive")
		)
	)
	(footprint "antmicro-footprints:R_0402_1005Metric"
		(layer "F.Cu")
		(at 86.1 77.9 90)
		(descr "Resistor SMD 0402")
		(tags "resistor SMD 0402")
		(property "Reference" "R52"
			(at 5.51 -1.27 90)
			(layer "F.SilkS")
			(effects
				(font
					(size 0.65 0.65)
					(thickness 0.15)
				)
				(justify left bottom)
			)
		)
		(property "Value" "R_75R_0402"
			(at 0 1.4 90)
			(layer "F.Fab")
			(hide yes)
			(effects
				(font
					(size 0.7 0.7)
					(thickness 0.15)
				)
				(justify left bottom)
			)
		)
		(property "Datasheet" "https://www.bourns.com/docs/product-datasheets/cr.pdf"
			(at 0 0 90)
			(layer "F.Fab")
			(hide yes)
			(effects
				(font
					(size 1.27 1.27)
					(thickness 0.15)
				)
			)
		)
		(property "Description" "SMD Chip Resistor, 75 ohm, ± 1%, 62.5 mW, 0402 [1005 Metric], Thick Film, General Purpose"
			(at 0 0 90)
			(layer "F.Fab")
			(hide yes)
			(effects
				(font
					(size 1.27 1.27)
					(thickness 0.15)
				)
			)
		)
		(property "Author" "Antmicro"
			(at 164 -8.2 0)
			(layer "F.Fab")
			(hide yes)
			(effects
				(font
					(size 1 1)
					(thickness 0.15)
				)
			)
		)
		(property "License" "Apache-2.0"
			(at 164 -8.2 0)
			(layer "F.Fab")
			(hide yes)
			(effects
				(font
					(size 1 1)
					(thickness 0.15)
				)
			)
		)
		(property "MPN" "CR0402-FX-75R0GLF"
			(at 164 -8.2 0)
			(layer "F.Fab")
			(hide yes)
			(effects
				(font
					(size 1 1)
					(thickness 0.15)
				)
			)
		)
		(property "Manufacturer" "Bourns"
			(at 164 -8.2 0)
			(layer "F.Fab")
			(hide yes)
			(effects
				(font
					(size 1 1)
					(thickness 0.15)
				)
			)
		)
		(property "Tolerance" "1%"
			(at 164 -8.2 0)
			(layer "F.Fab")
			(hide yes)
			(effects
				(font
					(size 1 1)
					(thickness 0.15)
				)
			)
		)
		(property "Val" "75R"
			(at 164 -8.2 0)
			(layer "F.Fab")
			(hide yes)
			(effects
				(font
					(size 1 1)
					(thickness 0.15)
				)
			)
		)
		(sheetname "/SDI/")
		(sheetfile "sdi.kicad_sch")
		(attr smd)
		(fp_rect
			(start -0.925 -0.47)
			(end 0.925 0.47)
			(stroke
				(width 0.05)
				(type default)
			)
			(fill no)
			(layer "F.CrtYd")
		)
		(fp_rect
			(start -0.5 -0.25)
			(end 0.5 0.25)
			(stroke
				(width 0.15)
				(type solid)
			)
			(fill no)
			(layer "F.Fab")
		)
		(fp_text user "Author: Antmicro"
			(at -0.95 4.169 90)
			(layer "F.Fab")
			(effects
				(font
					(size 0.7 0.7)
					(thickness 0.15)
				)
				(justify left bottom)
			)
		)
		(fp_text user "License: Apache-2.0"
			(at -0.95 5.169 90)
			(layer "F.Fab")
			(effects
				(font
					(size 0.7 0.7)
					(thickness 0.15)
				)
				(justify left bottom)
			)
		)
		(fp_text user "${REFERENCE}"
			(at -0.95 3.168 90)
			(layer "F.Fab")
			(effects
				(font
					(size 0.7 0.7)
					(thickness 0.15)
				)
				(justify left bottom)
			)
		)
		(pad "1" smd roundrect
			(at -0.48 0 90)
			(size 0.59 0.64)
			(layers "F.Cu" "F.Mask" "F.Paste")
			(roundrect_rratio 0.25)
			(net 1 "GND")
			(pintype "passive")
		)
		(pad "2" smd roundrect
			(at 0.48 0 90)
			(size 0.59 0.64)
			(layers "F.Cu" "F.Mask" "F.Paste")
			(roundrect_rratio 0.25)
			(net 243 "/SDI/SDI_IN_F")
			(pintype "passive")
		)
	)
	(footprint "antmicro-footprints:TP_SMD_0.75mm"
		(layer "F.Cu")
		(at 148.09 106.5 90)
		(property "Reference" "TP3"
			(at 0.76 0.34 90)
			(layer "F.SilkS")
			(effects
				(font
					(size 0.65 0.65)
					(thickness 0.15)
				)
				(justify left bottom)
			)
		)
		(property "Value" "TP_0.75mm_SMD"
			(at 0 1.2 90)
			(layer "F.Fab")
			(hide yes)
			(effects
				(font
					(size 0.7 0.7)
					(thickness 0.15)
				)
				(justify left bottom)
			)
		)
		(property "Description" "SMT test point"
			(at 0 0 90)
			(layer "F.Fab")
			(hide yes)
			(effects
				(font
					(size 1.27 1.27)
					(thickness 0.15)
				)
			)
		)
		(property "Author" "Antmicro"
			(at 254.59 -41.59 0)
			(layer "F.Fab")
			(hide yes)
			(effects
				(font
					(size 1 1)
					(thickness 0.15)
				)
			)
		)
		(property "License" "Apache-2.0"
			(at 254.59 -41.59 0)
			(layer "F.Fab")
			(hide yes)
			(effects
				(font
					(size 1 1)
					(thickness 0.15)
				)
			)
		)
		(property "MPN" ""
			(at 254.59 -41.59 0)
			(layer "F.Fab")
			(hide yes)
			(effects
				(font
					(size 1 1)
					(thickness 0.15)
				)
			)
		)
		(property "Manufacturer" ""
			(at 254.59 -41.59 0)
			(layer "F.Fab")
			(hide yes)
			(effects
				(font
					(size 1 1)
					(thickness 0.15)
				)
			)
		)
		(sheetname "/Power Supply/")
		(sheetfile "supply.kicad_sch")
		(attr exclude_from_pos_files)
		(fp_circle
			(center 0 0)
			(end 0.475 0)
			(stroke
				(width 0.05)
				(type default)
			)
			(fill no)
			(layer "F.CrtYd")
		)
		(fp_text user "Author: Antmicro"
			(at -0.4 3.901 90)
			(layer "F.Fab")
			(effects
				(font
					(size 0.7 0.7)
					(thickness 0.15)
				)
				(justify left bottom)
			)
		)
		(fp_text user "License: Apache-2.0"
			(at -0.4 5.101 90)
			(layer "F.Fab")
			(effects
				(font
					(size 0.7 0.7)
					(thickness 0.15)
				)
				(justify left bottom)
			)
		)
		(fp_text user "${REFERENCE}"
			(at -0.4 2.7 90)
			(layer "F.Fab")
			(effects
				(font
					(size 0.7 0.7)
					(thickness 0.15)
				)
				(justify left bottom)
			)
		)
		(pad "1" smd circle
			(at 0 0 90)
			(size 0.75 0.75)
			(layers "F.Cu" "F.Mask")
			(net 2 "+3V3")
			(pinfunction "1")
			(pintype "passive")
		)
	)
	(footprint "antmicro-footprints:R_0402_1005Metric"
		(layer "F.Cu")
		(at 123.46 106.16 180)
		(descr "Resistor SMD 0402")
		(tags "resistor SMD 0402")
		(property "Reference" "R97"
			(at 0.88 -0.38 0)
			(layer "F.SilkS")
			(effects
				(font
					(size 0.65 0.65)
					(thickness 0.15)
				)
				(justify right bottom)
			)
		)
		(property "Value" "R_10k_0402"
			(at 0 1.4 0)
			(layer "F.Fab")
			(hide yes)
			(effects
				(font
					(size 0.7 0.7)
					(thickness 0.15)
				)
				(justify right bottom)
			)
		)
		(property "Datasheet" "https://www.bourns.com/docs/product-datasheets/cr.pdf"
			(at 0 0 180)
			(layer "F.Fab")
			(hide yes)
			(effects
				(font
					(size 1.27 1.27)
					(thickness 0.15)
				)
			)
		)
		(property "Description" "SMD Chip Resistor, 10 kohm, ± 1%, 62.5 mW, 0402 [1005 Metric], Thick Film, General Purpose"
			(at 0 0 180)
			(layer "F.Fab")
			(hide yes)
			(effects
				(font
					(size 1.27 1.27)
					(thickness 0.15)
				)
			)
		)
		(property "Author" "Antmicro"
			(at 246.92 212.32 0)
			(layer "F.Fab")
			(hide yes)
			(effects
				(font
					(size 1 1)
					(thickness 0.15)
				)
			)
		)
		(property "License" "Apache-2.0"
			(at 246.92 212.32 0)
			(layer "F.Fab")
			(hide yes)
			(effects
				(font
					(size 1 1)
					(thickness 0.15)
				)
			)
		)
		(property "MPN" "CR0402-FX-1002GLF"
			(at 246.92 212.32 0)
			(layer "F.Fab")
			(hide yes)
			(effects
				(font
					(size 1 1)
					(thickness 0.15)
				)
			)
		)
		(property "Manufacturer" "Bourns"
			(at 246.92 212.32 0)
			(layer "F.Fab")
			(hide yes)
			(effects
				(font
					(size 1 1)
					(thickness 0.15)
				)
			)
		)
		(property "Tolerance" "1%"
			(at 246.92 212.32 0)
			(layer "F.Fab")
			(hide yes)
			(effects
				(font
					(size 1 1)
					(thickness 0.15)
				)
			)
		)
		(property "Val" "10k"
			(at 246.92 212.32 0)
			(layer "F.Fab")
			(hide yes)
			(effects
				(font
					(size 1 1)
					(thickness 0.15)
				)
			)
		)
		(sheetname "/FPGA/")
		(sheetfile "fpga.kicad_sch")
		(attr smd)
		(fp_rect
			(start -0.925 -0.47)
			(end 0.925 0.47)
			(stroke
				(width 0.05)
				(type default)
			)
			(fill no)
			(layer "F.CrtYd")
		)
		(fp_rect
			(start -0.5 -0.25)
			(end 0.5 0.25)
			(stroke
				(width 0.15)
				(type solid)
			)
			(fill no)
			(layer "F.Fab")
		)
		(fp_text user "${REFERENCE}"
			(at -0.95 3.168 180)
			(layer "F.Fab")
			(effects
				(font
					(size 0.7 0.7)
					(thickness 0.15)
				)
				(justify left bottom)
			)
		)
		(fp_text user "License: Apache-2.0"
			(at -0.95 5.169 180)
			(layer "F.Fab")
			(effects
				(font
					(size 0.7 0.7)
					(thickness 0.15)
				)
				(justify left bottom)
			)
		)
		(fp_text user "Author: Antmicro"
			(at -0.95 4.169 180)
			(layer "F.Fab")
			(effects
				(font
					(size 0.7 0.7)
					(thickness 0.15)
				)
				(justify left bottom)
			)
		)
		(pad "1" smd roundrect
			(at -0.48 0 180)
			(size 0.59 0.64)
			(layers "F.Cu" "F.Mask" "F.Paste")
			(roundrect_rratio 0.25)
			(net 1 "GND")
			(pintype "passive")
		)
		(pad "2" smd roundrect
			(at 0.48 0 180)
			(size 0.59 0.64)
			(layers "F.Cu" "F.Mask" "F.Paste")
			(roundrect_rratio 0.25)
			(net 173 "JTAG_EN")
			(pintype "passive")
		)
	)
	(footprint "antmicro-footprints:MP_Pad5.4mm_Drill2.7mm"
		(layer "F.Cu")
		(at 80.03 120.15)
		(descr "Mounting Hole 2.7mm, M2.5")
		(tags "mounting hole 2.7mm m2.5")
		(property "Reference" "MP2"
			(at 0 -2.9 0)
			(layer "F.SilkS")
			(hide yes)
			(effects
				(font
					(size 0.7 0.7)
					(thickness 0.15)
				)
				(justify left bottom)
			)
		)
		(property "Value" "MP_Pad5.4mm_Drill2.7mm"
			(at 0 3.6 0)
			(layer "F.Fab")
			(effects
				(font
					(size 0.7 0.7)
					(thickness 0.15)
				)
				(justify left bottom)
			)
		)
		(property "Description" "Mechanical part"
			(at 0 0 0)
			(layer "F.Fab")
			(hide yes)
			(effects
				(font
					(size 1.27 1.27)
					(thickness 0.15)
				)
			)
		)
		(property "Author" "Antmicro"
			(at 0 0 0)
			(unlocked yes)
			(layer "F.Fab")
			(hide yes)
			(effects
				(font
					(size 1 1)
					(thickness 0.15)
				)
			)
		)
		(property "License" "Apache-2.0"
			(at 0 0 0)
			(unlocked yes)
			(layer "F.Fab")
			(hide yes)
			(effects
				(font
					(size 1 1)
					(thickness 0.15)
				)
			)
		)
		(sheetname "/")
		(sheetfile "sdi-mipi-video-converter.kicad_sch")
		(attr exclude_from_pos_files exclude_from_bom)
		(fp_circle
			(center 0 0)
			(end 2.95 0)
			(stroke
				(width 0.05)
				(type default)
			)
			(fill no)
			(layer "F.CrtYd")
		)
		(fp_text user "Author: Antmicro"
			(at -8.4 7.2 0)
			(layer "F.Fab")
			(effects
				(font
					(size 0.7 0.7)
					(thickness 0.15)
				)
				(justify left bottom)
			)
		)
		(fp_text user "License: Apache-2.0"
			(at -8.4 8.4 0)
			(layer "F.Fab")
			(effects
				(font
					(size 0.7 0.7)
					(thickness 0.15)
				)
				(justify left bottom)
			)
		)
		(fp_text user "${REFERENCE}"
			(at -8.4 6 0)
			(layer "F.Fab")
			(effects
				(font
					(size 0.7 0.7)
					(thickness 0.15)
				)
				(justify left bottom)
			)
		)
		(pad "1" thru_hole circle
			(at 0 0)
			(size 5.4 5.4)
			(drill 2.7)
			(layers "*.Cu" "*.Mask")
			(remove_unused_layers no)
			(net 399 "unconnected-(MP2-Pad1)")
			(pintype "passive+no_connect")
			(solder_paste_margin_ratio -1)
		)
	)
	(footprint "antmicro-footprints:R_0402_1005Metric"
		(layer "F.Cu")
		(at 139.53 57.34 90)
		(descr "Resistor SMD 0402")
		(tags "resistor SMD 0402")
		(property "Reference" "R12"
			(at -1.1 -0.7 90)
			(layer "F.SilkS")
			(effects
				(font
					(size 0.65 0.65)
					(thickness 0.15)
				)
				(justify left bottom)
			)
		)
		(property "Value" "R_1k5_0402"
			(at 0 1.4 90)
			(layer "F.Fab")
			(hide yes)
			(effects
				(font
					(size 0.7 0.7)
					(thickness 0.15)
				)
				(justify left bottom)
			)
		)
		(property "Datasheet" "https://www.bourns.com/docs/product-datasheets/cr.pdf"
			(at 0 0 90)
			(layer "F.Fab")
			(hide yes)
			(effects
				(font
					(size 1.27 1.27)
					(thickness 0.15)
				)
			)
		)
		(property "Description" "SMD Chip Resistor, 1.5 kohm, ± 1%, 62.5 mW, 0402 [1005 Metric], Thick Film, General Purpose"
			(at 0 0 90)
			(layer "F.Fab")
			(hide yes)
			(effects
				(font
					(size 1.27 1.27)
					(thickness 0.15)
				)
			)
		)
		(property "Author" "Antmicro"
			(at 196.87 -82.19 0)
			(layer "F.Fab")
			(hide yes)
			(effects
				(font
					(size 1 1)
					(thickness 0.15)
				)
			)
		)
		(property "License" "Apache-2.0"
			(at 196.87 -82.19 0)
			(layer "F.Fab")
			(hide yes)
			(effects
				(font
					(size 1 1)
					(thickness 0.15)
				)
			)
		)
		(property "MPN" "CR0402-FX-1501GLF"
			(at 196.87 -82.19 0)
			(layer "F.Fab")
			(hide yes)
			(effects
				(font
					(size 1 1)
					(thickness 0.15)
				)
			)
		)
		(property "Manufacturer" "Bourns"
			(at 196.87 -82.19 0)
			(layer "F.Fab")
			(hide yes)
			(effects
				(font
					(size 1 1)
					(thickness 0.15)
				)
			)
		)
		(property "Tolerance" "1%"
			(at 196.87 -82.19 0)
			(layer "F.Fab")
			(hide yes)
			(effects
				(font
					(size 1 1)
					(thickness 0.15)
				)
			)
		)
		(property "Val" "1k5"
			(at 196.87 -82.19 0)
			(layer "F.Fab")
			(hide yes)
			(effects
				(font
					(size 1 1)
					(thickness 0.15)
				)
			)
		)
		(sheetname "/Power Supply/")
		(sheetfile "supply.kicad_sch")
		(attr smd)
		(fp_rect
			(start -0.925 -0.47)
			(end 0.925 0.47)
			(stroke
				(width 0.05)
				(type default)
			)
			(fill no)
			(layer "F.CrtYd")
		)
		(fp_rect
			(start -0.5 -0.25)
			(end 0.5 0.25)
			(stroke
				(width 0.15)
				(type solid)
			)
			(fill no)
			(layer "F.Fab")
		)
		(fp_text user "${REFERENCE}"
			(at -0.95 3.168 90)
			(layer "F.Fab")
			(effects
				(font
					(size 0.7 0.7)
					(thickness 0.15)
				)
				(justify left bottom)
			)
		)
		(fp_text user "License: Apache-2.0"
			(at -0.95 5.169 90)
			(layer "F.Fab")
			(effects
				(font
					(size 0.7 0.7)
					(thickness 0.15)
				)
				(justify left bottom)
			)
		)
		(fp_text user "Author: Antmicro"
			(at -0.95 4.169 90)
			(layer "F.Fab")
			(effects
				(font
					(size 0.7 0.7)
					(thickness 0.15)
				)
				(justify left bottom)
			)
		)
		(pad "1" smd roundrect
			(at -0.48 0 90)
			(size 0.59 0.64)
			(layers "F.Cu" "F.Mask" "F.Paste")
			(roundrect_rratio 0.25)
			(net 263 "Net-(U6-FB)")
			(pintype "passive")
		)
		(pad "2" smd roundrect
			(at 0.48 0 90)
			(size 0.59 0.64)
			(layers "F.Cu" "F.Mask" "F.Paste")
			(roundrect_rratio 0.25)
			(net 1 "GND")
			(pintype "passive")
		)
	)
	(footprint "antmicro-footprints:Resonator_SMD_Abracon_ABM7_6x3.5x1.4mm"
		(layer "F.Cu")
		(at 97.18 86.8)
		(property "Reference" "Y1"
			(at -4.55 -1.02 0)
			(layer "F.SilkS")
			(effects
				(font
					(size 0.65 0.65)
					(thickness 0.15)
				)
				(justify left bottom)
			)
		)
		(property "Value" "Oscillator_SMD_27MHz_ABM7"
			(at -3 3 0)
			(layer "F.Fab")
			(hide yes)
			(effects
				(font
					(size 0.7 0.7)
					(thickness 0.15)
				)
				(justify left bottom)
			)
		)
		(property "Datasheet" "https://abracon.com/Resonators/abm7.pdf"
			(at 0 0 0)
			(layer "F.Fab")
			(hide yes)
			(effects
				(font
					(size 1.27 1.27)
					(thickness 0.15)
				)
			)
		)
		(property "Description" "Crystal, 27 MHz, SMD, 6mm x 3.5mm, 30 ppm, 18 pF, 20 ppm, ABM7"
			(at 0 0 0)
			(layer "F.Fab")
			(hide yes)
			(effects
				(font
					(size 1.27 1.27)
					(thickness 0.15)
				)
			)
		)
		(property "Author" "Antmicro"
			(at 0 0 0)
			(layer "F.Fab")
			(hide yes)
			(effects
				(font
					(size 1 1)
					(thickness 0.15)
				)
			)
		)
		(property "License" "Apache-2.0"
			(at 0 0 0)
			(layer "F.Fab")
			(hide yes)
			(effects
				(font
					(size 1 1)
					(thickness 0.15)
				)
			)
		)
		(property "MPN" "ABM7-27.000MHZ-D2Y-T"
			(at 0 0 0)
			(layer "F.Fab")
			(hide yes)
			(effects
				(font
					(size 1 1)
					(thickness 0.15)
				)
			)
		)
		(property "Manufacturer" "Abracon"
			(at 0 0 0)
			(layer "F.Fab")
			(hide yes)
			(effects
				(font
					(size 1 1)
					(thickness 0.15)
				)
			)
		)
		(property "Val" "27 MHz"
			(at 0 0 0)
			(unlocked yes)
			(layer "F.Fab")
			(hide yes)
			(effects
				(font
					(size 1 1)
					(thickness 0.15)
				)
			)
		)
		(sheetname "/SDI/")
		(sheetfile "sdi.kicad_sch")
		(attr smd)
		(fp_line
			(start -3.102 -1.4745)
			(end -2.803 -1.7755)
			(stroke
				(width 0.15)
				(type solid)
			)
			(layer "F.SilkS")
		)
		(fp_line
			(start -3.102 1.499)
			(end -2.801 1.8)
			(stroke
				(width 0.15)
				(type solid)
			)
			(layer "F.SilkS")
		)
		(fp_line
			(start -2.803 -1.7755)
			(end 2.798 -1.7755)
			(stroke
				(width 0.15)
				(type solid)
			)
			(layer "F.SilkS")
		)
		(fp_line
			(start 2.8 1.8)
			(end -2.801 1.8)
			(stroke
				(width 0.15)
				(type solid)
			)
			(layer "F.SilkS")
		)
		(fp_line
			(start 3.099 -1.4745)
			(end 2.798 -1.7755)
			(stroke
				(width 0.15)
				(type solid)
			)
			(layer "F.SilkS")
		)
		(fp_line
			(start 3.099 1.499)
			(end 2.8 1.8)
			(stroke
				(width 0.15)
				(type solid)
			)
			(layer "F.SilkS")
		)
		(fp_rect
			(start -3.251 -1.95)
			(end 3.248 1.949)
			(stroke
				(width 0.05)
				(type solid)
			)
			(fill no)
			(layer "F.CrtYd")
		)
		(pad "1" smd rect
			(at -2.15 0)
			(size 1.9 2.6)
			(layers "F.Cu" "F.Mask" "F.Paste")
			(net 45 "/SDI/XTAL1")
			(pintype "passive")
		)
		(pad "2" smd rect
			(at 2.148 0)
			(size 1.9 2.6)
			(layers "F.Cu" "F.Mask" "F.Paste")
			(net 46 "/SDI/XTAL2")
			(pintype "passive")
		)
	)
	(footprint "antmicro-footprints:R_0402_1005Metric"
		(layer "F.Cu")
		(at 128.75 116.75 -90)
		(descr "Resistor SMD 0402")
		(tags "resistor SMD 0402")
		(property "Reference" "R129"
			(at -0.81 -0.28 270)
			(layer "F.SilkS")
			(effects
				(font
					(size 0.65 0.65)
					(thickness 0.15)
				)
				(justify left bottom)
			)
		)
		(property "Value" "R_0R_0402"
			(at 0 1.4 270)
			(layer "F.Fab")
			(hide yes)
			(effects
				(font
					(size 0.7 0.7)
					(thickness 0.15)
				)
				(justify left bottom)
			)
		)
		(property "Datasheet" "https://industrial.panasonic.com/cdbs/www-data/pdf/RDA0000/AOA0000C301.pdf"
			(at 0 0 270)
			(layer "F.Fab")
			(hide yes)
			(effects
				(font
					(size 1.27 1.27)
					(thickness 0.15)
				)
			)
		)
		(property "Description" "SMD Chip Resistor, Jumper, 0 ohm, 100 mW, 0402 [1005 Metric], Thick Film, General Purpose"
			(at 0 0 270)
			(layer "F.Fab")
			(hide yes)
			(effects
				(font
					(size 1.27 1.27)
					(thickness 0.15)
				)
			)
		)
		(property "Author" "Antmicro"
			(at 12 245.5 0)
			(layer "F.Fab")
			(hide yes)
			(effects
				(font
					(size 1 1)
					(thickness 0.15)
				)
			)
		)
		(property "Current" "1A"
			(at 12 245.5 0)
			(layer "F.Fab")
			(hide yes)
			(effects
				(font
					(size 1 1)
					(thickness 0.15)
				)
			)
		)
		(property "License" "Apache-2.0"
			(at 12 245.5 0)
			(layer "F.Fab")
			(hide yes)
			(effects
				(font
					(size 1 1)
					(thickness 0.15)
				)
			)
		)
		(property "MPN" "ERJ2GE0R00X"
			(at 12 245.5 0)
			(layer "F.Fab")
			(hide yes)
			(effects
				(font
					(size 1 1)
					(thickness 0.15)
				)
			)
		)
		(property "Manufacturer" "Panasonic"
			(at 12 245.5 0)
			(layer "F.Fab")
			(hide yes)
			(effects
				(font
					(size 1 1)
					(thickness 0.15)
				)
			)
		)
		(property "Tolerance" "~"
			(at 12 245.5 0)
			(layer "F.Fab")
			(hide yes)
			(effects
				(font
					(size 1 1)
					(thickness 0.15)
				)
			)
		)
		(property "Val" "0R"
			(at 12 245.5 0)
			(layer "F.Fab")
			(hide yes)
			(effects
				(font
					(size 1 1)
					(thickness 0.15)
				)
			)
		)
		(sheetname "/Peripherals/")
		(sheetfile "peripherals.kicad_sch")
		(attr smd)
		(fp_rect
			(start -0.925 -0.47)
			(end 0.925 0.47)
			(stroke
				(width 0.05)
				(type default)
			)
			(fill no)
			(layer "F.CrtYd")
		)
		(fp_rect
			(start -0.5 -0.25)
			(end 0.5 0.25)
			(stroke
				(width 0.15)
				(type solid)
			)
			(fill no)
			(layer "F.Fab")
		)
		(fp_text user "Author: Antmicro"
			(at -0.95 4.169 270)
			(layer "F.Fab")
			(effects
				(font
					(size 0.7 0.7)
					(thickness 0.15)
				)
				(justify left bottom)
			)
		)
		(fp_text user "${REFERENCE}"
			(at -0.95 3.168 270)
			(layer "F.Fab")
			(effects
				(font
					(size 0.7 0.7)
					(thickness 0.15)
				)
				(justify left bottom)
			)
		)
		(fp_text user "License: Apache-2.0"
			(at -0.95 5.169 270)
			(layer "F.Fab")
			(effects
				(font
					(size 0.7 0.7)
					(thickness 0.15)
				)
				(justify left bottom)
			)
		)
		(pad "1" smd roundrect
			(at -0.48 0 270)
			(size 0.59 0.64)
			(layers "F.Cu" "F.Mask" "F.Paste")
			(roundrect_rratio 0.25)
			(net 107 "/Peripherals/FFC2_RESET")
			(pintype "passive")
		)
		(pad "2" smd roundrect
			(at 0.48 0 270)
			(size 0.59 0.64)
			(layers "F.Cu" "F.Mask" "F.Paste")
			(roundrect_rratio 0.25)
			(net 344 "Net-(J6-Pad33)")
			(pintype "passive")
		)
	)
	(footprint "antmicro-footprints:R_0402_1005Metric"
		(layer "F.Cu")
		(at 107.4 107.2 -90)
		(descr "Resistor SMD 0402")
		(tags "resistor SMD 0402")
		(property "Reference" "R142"
			(at 1.04 -0.33 90)
			(layer "F.SilkS")
			(effects
				(font
					(size 0.65 0.65)
					(thickness 0.15)
				)
				(justify right bottom)
			)
		)
		(property "Value" "R_0R_0402"
			(at 0 1.4 90)
			(layer "F.Fab")
			(hide yes)
			(effects
				(font
					(size 0.7 0.7)
					(thickness 0.15)
				)
				(justify right bottom)
			)
		)
		(property "Datasheet" "https://industrial.panasonic.com/cdbs/www-data/pdf/RDA0000/AOA0000C301.pdf"
			(at 0 0 270)
			(layer "F.Fab")
			(hide yes)
			(effects
				(font
					(size 1.27 1.27)
					(thickness 0.15)
				)
			)
		)
		(property "Description" "SMD Chip Resistor, Jumper, 0 ohm, 100 mW, 0402 [1005 Metric], Thick Film, General Purpose"
			(at 0 0 270)
			(layer "F.Fab")
			(hide yes)
			(effects
				(font
					(size 1.27 1.27)
					(thickness 0.15)
				)
			)
		)
		(property "Author" "Antmicro"
			(at 0.2 214.6 0)
			(layer "F.Fab")
			(hide yes)
			(effects
				(font
					(size 1 1)
					(thickness 0.15)
				)
			)
		)
		(property "Current" "1A"
			(at 0.2 214.6 0)
			(layer "F.Fab")
			(hide yes)
			(effects
				(font
					(size 1 1)
					(thickness 0.15)
				)
			)
		)
		(property "License" "Apache-2.0"
			(at 0.2 214.6 0)
			(layer "F.Fab")
			(hide yes)
			(effects
				(font
					(size 1 1)
					(thickness 0.15)
				)
			)
		)
		(property "MPN" "ERJ2GE0R00X"
			(at 0.2 214.6 0)
			(layer "F.Fab")
			(hide yes)
			(effects
				(font
					(size 1 1)
					(thickness 0.15)
				)
			)
		)
		(property "Manufacturer" "Panasonic"
			(at 0.2 214.6 0)
			(layer "F.Fab")
			(hide yes)
			(effects
				(font
					(size 1 1)
					(thickness 0.15)
				)
			)
		)
		(property "Tolerance" "~"
			(at 0.2 214.6 0)
			(layer "F.Fab")
			(hide yes)
			(effects
				(font
					(size 1 1)
					(thickness 0.15)
				)
			)
		)
		(property "Val" "0R"
			(at 0.2 214.6 0)
			(layer "F.Fab")
			(hide yes)
			(effects
				(font
					(size 1 1)
					(thickness 0.15)
				)
			)
		)
		(sheetname "/FPGA/")
		(sheetfile "fpga.kicad_sch")
		(attr smd)
		(fp_rect
			(start -0.925 -0.47)
			(end 0.925 0.47)
			(stroke
				(width 0.05)
				(type default)
			)
			(fill no)
			(layer "F.CrtYd")
		)
		(fp_rect
			(start -0.5 -0.25)
			(end 0.5 0.25)
			(stroke
				(width 0.15)
				(type solid)
			)
			(fill no)
			(layer "F.Fab")
		)
		(fp_text user "License: Apache-2.0"
			(at -0.95 5.169 270)
			(layer "F.Fab")
			(effects
				(font
					(size 0.7 0.7)
					(thickness 0.15)
				)
				(justify left bottom)
			)
		)
		(fp_text user "${REFERENCE}"
			(at -0.95 3.168 270)
			(layer "F.Fab")
			(effects
				(font
					(size 0.7 0.7)
					(thickness 0.15)
				)
				(justify left bottom)
			)
		)
		(fp_text user "Author: Antmicro"
			(at -0.95 4.169 270)
			(layer "F.Fab")
			(effects
				(font
					(size 0.7 0.7)
					(thickness 0.15)
				)
				(justify left bottom)
			)
		)
		(pad "1" smd roundrect
			(at -0.48 0 270)
			(size 0.59 0.64)
			(layers "F.Cu" "F.Mask" "F.Paste")
			(roundrect_rratio 0.25)
			(net 372 "Net-(U17-GPIO3{slash}~{SS3})")
			(pintype "passive")
		)
		(pad "2" smd roundrect
			(at 0.48 0 270)
			(size 0.59 0.64)
			(layers "F.Cu" "F.Mask" "F.Paste")
			(roundrect_rratio 0.25)
			(net 42 "/FPGA/INITN_SOFT")
			(pintype "passive")
		)
	)
	(footprint "antmicro-footprints:BGA-96-48_8x14mm_Layout16x9_P0.8mm"
		(layer "F.Cu")
		(at 124.26 65.34 180)
		(property "Reference" "U12"
			(at 0 -8.1 180)
			(layer "F.SilkS")
			(effects
				(font
					(size 0.7 0.7)
					(thickness 0.15)
				)
				(justify left bottom)
			)
		)
		(property "Value" "MT41K128M16JT-125_K"
			(at 0 8.4 180)
			(layer "F.Fab")
			(effects
				(font
					(size 0.7 0.7)
					(thickness 0.15)
				)
				(justify left bottom)
			)
		)
		(property "Datasheet" "https://www.mouser.com/datasheet/2/671/mict_s_a0002296722_1-2290882.pdf"
			(at 0 0 180)
			(layer "F.Fab")
			(hide yes)
			(effects
				(font
					(size 1.27 1.27)
					(thickness 0.15)
				)
			)
		)
		(property "Description" "SDRAM - DDR3L Memory IC 2Gbit Parallel 800 MHz 13.75 ns 96-FBGA (8x14)"
			(at 0 0 180)
			(layer "F.Fab")
			(hide yes)
			(effects
				(font
					(size 1.27 1.27)
					(thickness 0.15)
				)
			)
		)
		(property "Author" "Antmicro"
			(at 248.52 130.68 0)
			(layer "F.Fab")
			(hide yes)
			(effects
				(font
					(size 1 1)
					(thickness 0.15)
				)
			)
		)
		(property "License" "Apache-2.0"
			(at 248.52 130.68 0)
			(layer "F.Fab")
			(hide yes)
			(effects
				(font
					(size 1 1)
					(thickness 0.15)
				)
			)
		)
		(property "MPN" "MT41K128M16JT-125:K"
			(at 248.52 130.68 0)
			(layer "F.Fab")
			(hide yes)
			(effects
				(font
					(size 1 1)
					(thickness 0.15)
				)
			)
		)
		(property "Manufacturer" "Micron Technology"
			(at 248.52 130.68 0)
			(layer "F.Fab")
			(hide yes)
			(effects
				(font
					(size 1 1)
					(thickness 0.15)
				)
			)
		)
		(sheetname "/DDR3/")
		(sheetfile "ddr3.kicad_sch")
		(attr smd)
		(fp_line
			(start 3.999 6.999)
			(end 3.999 -7)
			(stroke
				(width 0.15)
				(type solid)
			)
			(layer "F.SilkS")
		)
		(fp_line
			(start 3.999 -7)
			(end -4 -7)
			(stroke
				(width 0.15)
				(type solid)
			)
			(layer "F.SilkS")
		)
		(fp_line
			(start -4 6.999)
			(end 3.999 6.999)
			(stroke
				(width 0.15)
				(type solid)
			)
			(layer "F.SilkS")
		)
		(fp_line
			(start -4 -7)
			(end -4 6.999)
			(stroke
				(width 0.15)
				(type solid)
			)
			(layer "F.SilkS")
		)
		(fp_circle
			(center -4.8 -6)
			(end -4.75 -6)
			(stroke
				(width 0.15)
				(type solid)
			)
			(fill yes)
			(layer "F.SilkS")
		)
		(fp_rect
			(start -4.5 -7.5)
			(end 4.499 7.499)
			(stroke
				(width 0.05)
				(type solid)
			)
			(fill no)
			(layer "F.CrtYd")
		)
		(fp_poly
			(pts
				(xy -0.91 -6.75) (xy 0.9 -6.75) (xy 0.9 6.75) (xy -0.91 6.75)
			)
			(stroke
				(width 0.05)
				(type solid)
			)
			(fill yes)
			(layer "F.CrtYd")
		)
		(pad "A1" smd circle
			(at -3.201 -6 180)
			(size 0.35 0.35)
			(layers "F.Cu" "F.Mask" "F.Paste")
			(net 248 "+1V5")
			(pinfunction "VDDQ")
			(pintype "power_in")
		)
		(pad "A2" smd circle
			(at -2.4 -6 180)
			(size 0.35 0.35)
			(layers "F.Cu" "F.Mask" "F.Paste")
			(net 240 "/DDR3/DDR3_DQ13")
			(pinfunction "DQ13")
			(pintype "bidirectional")
		)
		(pad "A3" smd circle
			(at -1.601 -6 180)
			(size 0.35 0.35)
			(layers "F.Cu" "F.Mask" "F.Paste")
			(net 231 "/DDR3/DDR3_DQ15")
			(pinfunction "DQ15")
			(pintype "bidirectional")
		)
		(pad "A7" smd circle
			(at 1.6 -6 180)
			(size 0.35 0.35)
			(layers "F.Cu" "F.Mask" "F.Paste")
			(net 229 "/DDR3/DDR3_DQ12")
			(pinfunction "DQ12")
			(pintype "bidirectional")
		)
		(pad "A8" smd circle
			(at 2.399 -6 180)
			(size 0.35 0.35)
			(layers "F.Cu" "F.Mask" "F.Paste")
			(net 248 "+1V5")
			(pinfunction "VDDQ")
			(pintype "passive")
		)
		(pad "A9" smd circle
			(at 3.2 -6 180)
			(size 0.35 0.35)
			(layers "F.Cu" "F.Mask" "F.Paste")
			(net 1 "GND")
			(pinfunction "VSS")
			(pintype "passive")
		)
		(pad "B1" smd circle
			(at -3.201 -5.201 180)
			(size 0.35 0.35)
			(layers "F.Cu" "F.Mask" "F.Paste")
			(net 1 "GND")
			(pinfunction "VSSQ")
			(pintype "passive")
		)
		(pad "B2" smd circle
			(at -2.4 -5.201 180)
			(size 0.35 0.35)
			(layers "F.Cu" "F.Mask" "F.Paste")
			(net 248 "+1V5")
			(pinfunction "VDD")
			(pintype "power_in")
		)
		(pad "B3" smd circle
			(at -1.601 -5.201 180)
			(size 0.35 0.35)
			(layers "F.Cu" "F.Mask" "F.Paste")
			(net 1 "GND")
			(pinfunction "VSS")
			(pintype "passive")
		)
		(pad "B7" smd circle
			(at 1.6 -5.201 180)
			(size 0.35 0.35)
			(layers "F.Cu" "F.Mask" "F.Paste")
			(net 239 "/DDR3/DDR3_UDQS_N")
			(pinfunction "~{UDQS}")
			(pintype "bidirectional")
		)
		(pad "B8" smd circle
			(at 2.399 -5.201 180)
			(size 0.35 0.35)
			(layers "F.Cu" "F.Mask" "F.Paste")
			(net 241 "/DDR3/DDR3_DQ14")
			(pinfunction "DQ14")
			(pintype "bidirectional")
		)
		(pad "B9" smd circle
			(at 3.2 -5.201 180)
			(size 0.35 0.35)
			(layers "F.Cu" "F.Mask" "F.Paste")
			(net 1 "GND")
			(pinfunction "VSSQ")
			(pintype "passive")
		)
		(pad "C1" smd circle
			(at -3.201 -4.401 180)
			(size 0.35 0.35)
			(layers "F.Cu" "F.Mask" "F.Paste")
			(net 248 "+1V5")
			(pinfunction "VDDQ")
			(pintype "passive")
		)
		(pad "C2" smd circle
			(at -2.4 -4.401 180)
			(size 0.35 0.35)
			(layers "F.Cu" "F.Mask" "F.Paste")
			(net 228 "/DDR3/DDR3_DQ11")
			(pinfunction "DQ11")
			(pintype "bidirectional")
		)
		(pad "C3" smd circle
			(at -1.601 -4.401 180)
			(size 0.35 0.35)
			(layers "F.Cu" "F.Mask" "F.Paste")
			(net 238 "/DDR3/DDR3_DQ9")
			(pinfunction "DQ9")
			(pintype "bidirectional")
		)
		(pad "C7" smd circle
			(at 1.6 -4.401 180)
			(size 0.35 0.35)
			(layers "F.Cu" "F.Mask" "F.Paste")
			(net 227 "/DDR3/DDR3_UDQS_P")
			(pinfunction "UDQS")
			(pintype "bidirectional")
		)
		(pad "C8" smd circle
			(at 2.399 -4.401 180)
			(size 0.35 0.35)
			(layers "F.Cu" "F.Mask" "F.Paste")
			(net 237 "/DDR3/DDR3_DQ10")
			(pinfunction "DQ10")
			(pintype "bidirectional")
		)
		(pad "C9" smd circle
			(at 3.2 -4.401 180)
			(size 0.35 0.35)
			(layers "F.Cu" "F.Mask" "F.Paste")
			(net 248 "+1V5")
			(pinfunction "VDDQ")
			(pintype "passive")
		)
		(pad "D1" smd circle
			(at -3.201 -3.601 180)
			(size 0.35 0.35)
			(layers "F.Cu" "F.Mask" "F.Paste")
			(net 1 "GND")
			(pinfunction "VSSQ")
			(pintype "passive")
		)
		(pad "D2" smd circle
			(at -2.4 -3.601 180)
			(size 0.35 0.35)
			(layers "F.Cu" "F.Mask" "F.Paste")
			(net 248 "+1V5")
			(pinfunction "VDDQ")
			(pintype "passive")
		)
		(pad "D3" smd circle
			(at -1.601 -3.601 180)
			(size 0.35 0.35)
			(layers "F.Cu" "F.Mask" "F.Paste")
			(net 230 "/DDR3/DDR3_UDM")
			(pinfunction "UDM")
			(pintype "input")
		)
		(pad "D7" smd circle
			(at 1.6 -3.601 180)
			(size 0.35 0.35)
			(layers "F.Cu" "F.Mask" "F.Paste")
			(net 226 "/DDR3/DDR3_DQ8")
			(pinfunction "DQ8")
			(pintype "bidirectional")
		)
		(pad "D8" smd circle
			(at 2.399 -3.601 180)
			(size 0.35 0.35)
			(layers "F.Cu" "F.Mask" "F.Paste")
			(net 1 "GND")
			(pinfunction "VSSQ")
			(pintype "passive")
		)
		(pad "D9" smd circle
			(at 3.2 -3.601 180)
			(size 0.35 0.35)
			(layers "F.Cu" "F.Mask" "F.Paste")
			(net 248 "+1V5")
			(pinfunction "VDD")
			(pintype "passive")
		)
		(pad "E1" smd circle
			(at -3.201 -2.8 180)
			(size 0.35 0.35)
			(layers "F.Cu" "F.Mask" "F.Paste")
			(net 1 "GND")
			(pinfunction "VSS")
			(pintype "passive")
		)
		(pad "E2" smd circle
			(at -2.4 -2.8 180)
			(size 0.35 0.35)
			(layers "F.Cu" "F.Mask" "F.Paste")
			(net 1 "GND")
			(pinfunction "VSSQ")
			(pintype "passive")
		)
		(pad "E3" smd circle
			(at -1.601 -2.8 180)
			(size 0.35 0.35)
			(layers "F.Cu" "F.Mask" "F.Paste")
			(net 221 "/DDR3/DDR3_DQ0")
			(pinfunction "DQ0")
			(pintype "bidirectional")
		)
		(pad "E7" smd circle
			(at 1.6 -2.8 180)
			(size 0.35 0.35)
			(layers "F.Cu" "F.Mask" "F.Paste")
			(net 232 "/DDR3/DDR3_LDM")
			(pinfunction "LDM")
			(pintype "input")
		)
		(pad "E8" smd circle
			(at 2.399 -2.8 180)
			(size 0.35 0.35)
			(layers "F.Cu" "F.Mask" "F.Paste")
			(net 1 "GND")
			(pinfunction "VSSQ")
			(pintype "passive")
		)
		(pad "E9" smd circle
			(at 3.2 -2.8 180)
			(size 0.35 0.35)
			(layers "F.Cu" "F.Mask" "F.Paste")
			(net 248 "+1V5")
			(pinfunction "VDDQ")
			(pintype "passive")
		)
		(pad "F1" smd circle
			(at -3.201 -2 180)
			(size 0.35 0.35)
			(layers "F.Cu" "F.Mask" "F.Paste")
			(net 248 "+1V5")
			(pinfunction "VDDQ")
			(pintype "passive")
		)
		(pad "F2" smd circle
			(at -2.4 -2 180)
			(size 0.35 0.35)
			(layers "F.Cu" "F.Mask" "F.Paste")
			(net 234 "/DDR3/DDR3_DQ2")
			(pinfunction "DQ2")
			(pintype "bidirectional")
		)
		(pad "F3" smd circle
			(at -1.601 -2 180)
			(size 0.35 0.35)
			(layers "F.Cu" "F.Mask" "F.Paste")
			(net 223 "/DDR3/DDR3_LDQS_P")
			(pinfunction "LDQS")
			(pintype "bidirectional")
		)
		(pad "F7" smd circle
			(at 1.6 -2 180)
			(size 0.35 0.35)
			(layers "F.Cu" "F.Mask" "F.Paste")
			(net 233 "/DDR3/DDR3_DQ1")
			(pinfunction "DQ1")
			(pintype "bidirectional")
		)
		(pad "F8" smd circle
			(at 2.399 -2 180)
			(size 0.35 0.35)
			(layers "F.Cu" "F.Mask" "F.Paste")
			(net 222 "/DDR3/DDR3_DQ3")
			(pinfunction "DQ3")
			(pintype "bidirectional")
		)
		(pad "F9" smd circle
			(at 3.2 -2 180)
			(size 0.35 0.35)
			(layers "F.Cu" "F.Mask" "F.Paste")
			(net 1 "GND")
			(pinfunction "VSSQ")
			(pintype "passive")
		)
		(pad "G1" smd circle
			(at -3.201 -1.2 180)
			(size 0.35 0.35)
			(layers "F.Cu" "F.Mask" "F.Paste")
			(net 1 "GND")
			(pinfunction "VSSQ")
			(pintype "passive")
		)
		(pad "G2" smd circle
			(at -2.4 -1.2 180)
			(size 0.35 0.35)
			(layers "F.Cu" "F.Mask" "F.Paste")
			(net 236 "/DDR3/DDR3_DQ6")
			(pinfunction "DQ6")
			(pintype "bidirectional")
		)
		(pad "G3" smd circle
			(at -1.601 -1.2 180)
			(size 0.35 0.35)
			(layers "F.Cu" "F.Mask" "F.Paste")
			(net 220 "/DDR3/DDR3_LDQS_N")
			(pinfunction "~{LDQS}")
			(pintype "bidirectional")
		)
		(pad "G7" smd circle
			(at 1.6 -1.2 180)
			(size 0.35 0.35)
			(layers "F.Cu" "F.Mask" "F.Paste")
			(net 248 "+1V5")
			(pinfunction "VDD")
			(pintype "passive")
		)
		(pad "G8" smd circle
			(at 2.399 -1.2 180)
			(size 0.35 0.35)
			(layers "F.Cu" "F.Mask" "F.Paste")
			(net 1 "GND")
			(pinfunction "VSS")
			(pintype "passive")
		)
		(pad "G9" smd circle
			(at 3.2 -1.2 180)
			(size 0.35 0.35)
			(layers "F.Cu" "F.Mask" "F.Paste")
			(net 1 "GND")
			(pinfunction "VSSQ")
			(pintype "passive")
		)
		(pad "H1" smd circle
			(at -3.201 -0.401 180)
			(size 0.35 0.35)
			(layers "F.Cu" "F.Mask" "F.Paste")
			(net 5 "Vref")
			(pinfunction "VREFDQ")
			(pintype "power_in")
		)
		(pad "H2" smd circle
			(at -2.4 -0.401 180)
			(size 0.35 0.35)
			(layers "F.Cu" "F.Mask" "F.Paste")
			(net 248 "+1V5")
			(pinfunction "VDDQ")
			(pintype "passive")
		)
		(pad "H3" smd circle
			(at -1.601 -0.401 180)
			(size 0.35 0.35)
			(layers "F.Cu" "F.Mask" "F.Paste")
			(net 235 "/DDR3/DDR3_DQ4")
			(pinfunction "DQ4")
			(pintype "bidirectional")
		)
		(pad "H7" smd circle
			(at 1.6 -0.401 180)
			(size 0.35 0.35)
			(layers "F.Cu" "F.Mask" "F.Paste")
			(net 225 "/DDR3/DDR3_DQ7")
			(pinfunction "DQ7")
			(pintype "bidirectional")
		)
		(pad "H8" smd circle
			(at 2.399 -0.401 180)
			(size 0.35 0.35)
			(layers "F.Cu" "F.Mask" "F.Paste")
			(net 224 "/DDR3/DDR3_DQ5")
			(pinfunction "DQ5")
			(pintype "bidirectional")
		)
		(pad "H9" smd circle
			(at 3.2 -0.401 180)
			(size 0.35 0.35)
			(layers "F.Cu" "F.Mask" "F.Paste")
			(net 248 "+1V5")
			(pinfunction "VDDQ")
			(pintype "passive")
		)
		(pad "J1" smd circle
			(at -3.201 0.4 180)
			(size 0.35 0.35)
			(layers "F.Cu" "F.Mask" "F.Paste")
			(net 322 "unconnected-(U12-PadJ1)")
			(pinfunction "J1")
			(pintype "no_connect")
		)
		(pad "J2" smd circle
			(at -2.4 0.4 180)
			(size 0.35 0.35)
			(layers "F.Cu" "F.Mask" "F.Paste")
			(net 1 "GND")
			(pinfunction "VSS")
			(pintype "passive")
		)
		(pad "J3" smd circle
			(at -1.601 0.4 180)
			(size 0.35 0.35)
			(layers "F.Cu" "F.Mask" "F.Paste")
			(net 162 "/DDR3/~{DDR3_RAS}")
			(pinfunction "~{RAS}")
			(pintype "input")
		)
		(pad "J7" smd circle
			(at 1.6 0.4 180)
			(size 0.35 0.35)
			(layers "F.Cu" "F.Mask" "F.Paste")
			(net 143 "/DDR3/DDR3_CK_P")
			(pinfunction "CK")
			(pintype "input")
		)
		(pad "J8" smd circle
			(at 2.399 0.4 180)
			(size 0.35 0.35)
			(layers "F.Cu" "F.Mask" "F.Paste")
			(net 1 "GND")
			(pinfunction "VSS")
			(pintype "passive")
		)
		(pad "J9" smd circle
			(at 3.2 0.4 180)
			(size 0.35 0.35)
			(layers "F.Cu" "F.Mask" "F.Paste")
			(net 318 "unconnected-(U12-PadJ9)")
			(pinfunction "J9")
			(pintype "no_connect")
		)
		(pad "K1" smd circle
			(at -3.201 1.199 180)
			(size 0.35 0.35)
			(layers "F.Cu" "F.Mask" "F.Paste")
			(net 166 "/DDR3/DDR3_ODT")
			(pinfunction "ODT")
			(pintype "input")
		)
		(pad "K2" smd circle
			(at -2.4 1.199 180)
			(size 0.35 0.35)
			(layers "F.Cu" "F.Mask" "F.Paste")
			(net 248 "+1V5")
			(pinfunction "VDD")
			(pintype "passive")
		)
		(pad "K3" smd circle
			(at -1.601 1.199 180)
			(size 0.35 0.35)
			(layers "F.Cu" "F.Mask" "F.Paste")
			(net 161 "/DDR3/~{DDR3_CAS}")
			(pinfunction "~{CAS}")
			(pintype "input")
		)
		(pad "K7" smd circle
			(at 1.6 1.199 180)
			(size 0.35 0.35)
			(layers "F.Cu" "F.Mask" "F.Paste")
			(net 142 "/DDR3/DDR3_CK_N")
			(pinfunction "~{CK}")
			(pintype "input")
		)
		(pad "K8" smd circle
			(at 2.399 1.199 180)
			(size 0.35 0.35)
			(layers "F.Cu" "F.Mask" "F.Paste")
			(net 248 "+1V5")
			(pinfunction "VDD")
			(pintype "passive")
		)
		(pad "K9" smd circle
			(at 3.2 1.199 180)
			(size 0.35 0.35)
			(layers "F.Cu" "F.Mask" "F.Paste")
			(net 165 "/DDR3/DDR3_CKE")
			(pinfunction "CKE")
			(pintype "input")
		)
		(pad "L1" smd circle
			(at -3.201 1.999 180)
			(size 0.35 0.35)
			(layers "F.Cu" "F.Mask" "F.Paste")
			(net 321 "unconnected-(U12-PadL1)")
			(pinfunction "L1")
			(pintype "no_connect")
		)
		(pad "L2" smd circle
			(at -2.4 1.999 180)
			(size 0.35 0.35)
			(layers "F.Cu" "F.Mask" "F.Paste")
			(net 168 "/DDR3/~{DDR3_CS}")
			(pinfunction "~{CS}")
			(pintype "input")
		)
		(pad "L3" smd circle
			(at -1.601 1.999 180)
			(size 0.35 0.35)
			(layers "F.Cu" "F.Mask" "F.Paste")
			(net 163 "/DDR3/~{DDR3_WE}")
			(pinfunction "~{WE}")
			(pintype "input")
		)
		(pad "L7" smd circle
			(at 1.6 1.999 180)
			(size 0.35 0.35)
			(layers "F.Cu" "F.Mask" "F.Paste")
			(net 152 "/DDR3/DDR3_A10")
			(pinfunction "A10/AP")
			(pintype "input")
		)
		(pad "L8" smd circle
			(at 2.399 1.999 180)
			(size 0.35 0.35)
			(layers "F.Cu" "F.Mask" "F.Paste")
			(net 287 "Net-(U12A-ZQ)")
			(pinfunction "ZQ")
			(pintype "passive")
		)
		(pad "L9" smd circle
			(at 3.2 1.999 180)
			(size 0.35 0.35)
			(layers "F.Cu" "F.Mask" "F.Paste")
			(net 317 "unconnected-(U12-PadL9)")
			(pinfunction "L9")
			(pintype "no_connect")
		)
		(pad "M1" smd circle
			(at -3.201 2.799 180)
			(size 0.35 0.35)
			(layers "F.Cu" "F.Mask" "F.Paste")
			(net 1 "GND")
			(pinfunction "VSS")
			(pintype "passive")
		)
		(pad "M2" smd circle
			(at -2.4 2.799 180)
			(size 0.35 0.35)
			(layers "F.Cu" "F.Mask" "F.Paste")
			(net 157 "/DDR3/DDR3_BA0")
			(pinfunction "BA0")
			(pintype "input")
		)
		(pad "M3" smd circle
			(at -1.601 2.799 180)
			(size 0.35 0.35)
			(layers "F.Cu" "F.Mask" "F.Paste")
			(net 167 "/DDR3/DDR3_BA2")
			(pinfunction "BA2")
			(pintype "input")
		)
		(pad "M7" smd circle
			(at 1.6 2.799 180)
			(size 0.35 0.35)
			(layers "F.Cu" "F.Mask" "F.Paste")
			(net 320 "unconnected-(U12-PadM7)")
			(pinfunction "M7")
			(pintype "no_connect")
		)
		(pad "M8" smd circle
			(at 2.399 2.799 180)
			(size 0.35 0.35)
			(layers "F.Cu" "F.Mask" "F.Paste")
			(net 5 "Vref")
			(pinfunction "VREFCA")
			(pintype "power_in")
		)
		(pad "M9" smd circle
			(at 3.2 2.799 180)
			(size 0.35 0.35)
			(layers "F.Cu" "F.Mask" "F.Paste")
			(net 1 "GND")
			(pinfunction "VSS")
			(pintype "passive")
		)
		(pad "N1" smd circle
			(at -3.201 3.6 180)
			(size 0.35 0.35)
			(layers "F.Cu" "F.Mask" "F.Paste")
			(net 248 "+1V5")
			(pinfunction "VDD")
			(pintype "passive")
		)
		(pad "N2" smd circle
			(at -2.4 3.6 180)
			(size 0.35 0.35)
			(layers "F.Cu" "F.Mask" "F.Paste")
			(net 146 "/DDR3/DDR3_A3")
			(pinfunction "A3")
			(pintype "input")
		)
		(pad "N3" smd circle
			(at -1.601 3.6 180)
			(size 0.35 0.35)
			(layers "F.Cu" "F.Mask" "F.Paste")
			(net 147 "/DDR3/DDR3_A0")
			(pinfunction "A0")
			(pintype "input")
		)
		(pad "N7" smd circle
			(at 1.6 3.6 180)
			(size 0.35 0.35)
			(layers "F.Cu" "F.Mask" "F.Paste")
			(net 160 "/DDR3/DDR3_A12")
			(pinfunction "A12/~{BC}")
			(pintype "input")
		)
		(pad "N8" smd circle
			(at 2.399 3.6 180)
			(size 0.35 0.35)
			(layers "F.Cu" "F.Mask" "F.Paste")
			(net 159 "/DDR3/DDR3_BA1")
			(pinfunction "BA1")
			(pintype "input")
		)
		(pad "N9" smd circle
			(at 3.2 3.6 180)
			(size 0.35 0.35)
			(layers "F.Cu" "F.Mask" "F.Paste")
			(net 248 "+1V5")
			(pinfunction "VDD")
			(pintype "passive")
		)
		(pad "P1" smd circle
			(at -3.201 4.4 180)
			(size 0.35 0.35)
			(layers "F.Cu" "F.Mask" "F.Paste")
			(net 1 "GND")
			(pinfunction "VSS")
			(pintype "passive")
		)
		(pad "P2" smd circle
			(at -2.4 4.4 180)
			(size 0.35 0.35)
			(layers "F.Cu" "F.Mask" "F.Paste")
			(net 149 "/DDR3/DDR3_A5")
			(pinfunction "A5")
			(pintype "input")
		)
		(pad "P3" smd circle
			(at -1.601 4.4 180)
			(size 0.35 0.35)
			(layers "F.Cu" "F.Mask" "F.Paste")
			(net 144 "/DDR3/DDR3_A2")
			(pinfunction "A2")
			(pintype "input")
		)
		(pad "P7" smd circle
			(at 1.6 4.4 180)
			(size 0.35 0.35)
			(layers "F.Cu" "F.Mask" "F.Paste")
			(net 145 "/DDR3/DDR3_A1")
			(pinfunction "A1")
			(pintype "input")
		)
		(pad "P8" smd circle
			(at 2.399 4.4 180)
			(size 0.35 0.35)
			(layers "F.Cu" "F.Mask" "F.Paste")
			(net 151 "/DDR3/DDR3_A4")
			(pinfunction "A4")
			(pintype "input")
		)
		(pad "P9" smd circle
			(at 3.2 4.4 180)
			(size 0.35 0.35)
			(layers "F.Cu" "F.Mask" "F.Paste")
			(net 1 "GND")
			(pinfunction "VSS")
			(pintype "passive")
		)
		(pad "R1" smd circle
			(at -3.201 5.2 180)
			(size 0.35 0.35)
			(layers "F.Cu" "F.Mask" "F.Paste")
			(net 248 "+1V5")
			(pinfunction "VDD")
			(pintype "passive")
		)
		(pad "R2" smd circle
			(at -2.4 5.2 180)
			(size 0.35 0.35)
			(layers "F.Cu" "F.Mask" "F.Paste")
			(net 150 "/DDR3/DDR3_A7")
			(pinfunction "A7")
			(pintype "input")
		)
		(pad "R3" smd circle
			(at -1.601 5.2 180)
			(size 0.35 0.35)
			(layers "F.Cu" "F.Mask" "F.Paste")
			(net 153 "/DDR3/DDR3_A9")
			(pinfunction "A9")
			(pintype "input")
		)
		(pad "R7" smd circle
			(at 1.6 5.2 180)
			(size 0.35 0.35)
			(layers "F.Cu" "F.Mask" "F.Paste")
			(net 154 "/DDR3/DDR3_A11")
			(pinfunction "A11")
			(pintype "input")
		)
		(pad "R8" smd circle
			(at 2.399 5.2 180)
			(size 0.35 0.35)
			(layers "F.Cu" "F.Mask" "F.Paste")
			(net 148 "/DDR3/DDR3_A6")
			(pinfunction "A6")
			(pintype "input")
		)
		(pad "R9" smd circle
			(at 3.2 5.2 180)
			(size 0.35 0.35)
			(layers "F.Cu" "F.Mask" "F.Paste")
			(net 248 "+1V5")
			(pinfunction "VDD")
			(pintype "passive")
		)
		(pad "T1" smd circle
			(at -3.201 5.999 180)
			(size 0.35 0.35)
			(layers "F.Cu" "F.Mask" "F.Paste")
			(net 1 "GND")
			(pinfunction "VSS")
			(pintype "passive")
		)
		(pad "T2" smd circle
			(at -2.4 5.999 180)
			(size 0.35 0.35)
			(layers "F.Cu" "F.Mask" "F.Paste")
			(net 164 "/DDR3/~{DDR3_RESET}")
			(pinfunction "~{RESET}")
			(pintype "input")
		)
		(pad "T3" smd circle
			(at -1.601 5.999 180)
			(size 0.35 0.35)
			(layers "F.Cu" "F.Mask" "F.Paste")
			(net 158 "/DDR3/DDR3_A13")
			(pinfunction "A13")
			(pintype "input")
		)
		(pad "T7" smd circle
			(at 1.6 5.999 180)
			(size 0.35 0.35)
			(layers "F.Cu" "F.Mask" "F.Paste")
			(net 319 "unconnected-(U12-PadT7)")
			(pinfunction "T7")
			(pintype "no_connect")
		)
		(pad "T8" smd circle
			(at 2.399 5.999 180)
			(size 0.35 0.35)
			(layers "F.Cu" "F.Mask" "F.Paste")
			(net 155 "/DDR3/DDR3_A8")
			(pinfunction "A8")
			(pintype "input")
		)
		(pad "T9" smd circle
			(at 3.2 5.999 180)
			(size 0.35 0.35)
			(layers "F.Cu" "F.Mask" "F.Paste")
			(net 1 "GND")
			(pinfunction "VSS")
			(pintype "passive")
		)
	)
	(footprint "antmicro-footprints:LED_0603_1608Metric_R"
		(layer "F.Cu")
		(at 124.03 109.65 -90)
		(descr "LED SMD 0603 Red")
		(tags "LED SMD 0603 Red")
		(property "Reference" "D6"
			(at -2.71 0.4 90)
			(layer "F.SilkS")
			(effects
				(font
					(size 0.65 0.65)
					(thickness 0.15)
				)
				(justify right top)
			)
		)
		(property "Value" "LED_R_0603_LTST-C190KRKT"
			(at 0 1.6 90)
			(layer "F.Fab")
			(hide yes)
			(effects
				(font
					(size 0.7 0.7)
					(thickness 0.15)
				)
				(justify right top)
			)
		)
		(property "Datasheet" "https://optoelectronics.liteon.com/upload/download/DS-22-99-0151/LTST-C190KRKT.pdf"
			(at 0 0 90)
			(layer "F.Fab")
			(hide yes)
			(effects
				(font
					(size 1.27 1.27)
					(thickness 0.15)
				)
			)
		)
		(property "Description" "LED, Red, SMD, 0603, 25 mA, 2 V, 631 nm"
			(at 0 0 90)
			(layer "F.Fab")
			(hide yes)
			(effects
				(font
					(size 1.27 1.27)
					(thickness 0.15)
				)
			)
		)
		(property "Author" "Antmicro"
			(at 233.68 -14.38 0)
			(layer "F.Fab")
			(hide yes)
			(effects
				(font
					(size 1 1)
					(thickness 0.15)
				)
			)
		)
		(property "License" "Apache-2.0"
			(at 233.68 -14.38 0)
			(layer "F.Fab")
			(hide yes)
			(effects
				(font
					(size 1 1)
					(thickness 0.15)
				)
			)
		)
		(property "MPN" "LTST-C190KRKT"
			(at 233.68 -14.38 0)
			(layer "F.Fab")
			(hide yes)
			(effects
				(font
					(size 1 1)
					(thickness 0.15)
				)
			)
		)
		(property "Manufacturer" "Lite-On"
			(at 233.68 -14.38 0)
			(layer "F.Fab")
			(hide yes)
			(effects
				(font
					(size 1 1)
					(thickness 0.15)
				)
			)
		)
		(property "Color" "Red"
			(at 0 0 270)
			(unlocked yes)
			(layer "F.Fab")
			(hide yes)
			(effects
				(font
					(size 1 1)
					(thickness 0.15)
				)
			)
		)
		(sheetname "/FPGA/")
		(sheetfile "fpga.kicad_sch")
		(attr smd)
		(fp_line
			(start 0.22 0.35)
			(end -0.22 0.35)
			(stroke
				(width 0.15)
				(type solid)
			)
			(layer "F.SilkS")
		)
		(fp_line
			(start -0.094672 0.201008)
			(end -0.094672 -0.198992)
			(stroke
				(width 0.1)
				(type solid)
			)
			(layer "F.SilkS")
		)
		(fp_line
			(start 0.105328 0.201008)
			(end -0.094672 0.001008)
			(stroke
				(width 0.1)
				(type solid)
			)
			(layer "F.SilkS")
		)
		(fp_line
			(start 0.105328 0.201008)
			(end 0.105328 -0.198992)
			(stroke
				(width 0.1)
				(type solid)
			)
			(layer "F.SilkS")
		)
		(fp_line
			(start -0.094672 0.001008)
			(end -0.24 0.001008)
			(stroke
				(width 0.1)
				(type solid)
			)
			(layer "F.SilkS")
		)
		(fp_line
			(start -0.094672 0.001008)
			(end 0.105328 -0.198992)
			(stroke
				(width 0.1)
				(type solid)
			)
			(layer "F.SilkS")
		)
		(fp_line
			(start 0.105328 0.001008)
			(end 0.24 0.001)
			(stroke
				(width 0.1)
				(type solid)
			)
			(layer "F.SilkS")
		)
		(fp_line
			(start -1.18 -0.319)
			(end -1.18 0.321)
			(stroke
				(width 0.15)
				(type solid)
			)
			(layer "F.SilkS")
		)
		(fp_line
			(start 0.22 -0.35)
			(end -0.22 -0.35)
			(stroke
				(width 0.15)
				(type solid)
			)
			(layer "F.SilkS")
		)
		(fp_rect
			(start 1.25 0.65)
			(end -1.25 -0.65)
			(stroke
				(width 0.05)
				(type solid)
			)
			(fill no)
			(layer "F.CrtYd")
		)
		(fp_line
			(start -0.199 0.2)
			(end -0.199 0.1)
			(stroke
				(width 0.15)
				(type solid)
			)
			(layer "F.Fab")
		)
		(fp_line
			(start 0.201 0.2)
			(end 0.201 0)
			(stroke
				(width 0.15)
				(type solid)
			)
			(layer "F.Fab")
		)
		(fp_line
			(start -0.199 0)
			(end -0.597 0)
			(stroke
				(width 0.15)
				(type solid)
			)
			(layer "F.Fab")
		)
		(fp_line
			(start -0.101 0)
			(end 0.201 0.2)
			(stroke
				(width 0.15)
				(type solid)
			)
			(layer "F.Fab")
		)
		(fp_line
			(start 0.201 0)
			(end 0.201 -0.202)
			(stroke
				(width 0.15)
				(type solid)
			)
			(layer "F.Fab")
		)
		(fp_line
			(start 0.599 0)
			(end 0.201 0)
			(stroke
				(width 0.15)
				(type solid)
			)
			(layer "F.Fab")
		)
		(fp_line
			(start -0.199 -0.202)
			(end -0.199 0.1)
			(stroke
				(width 0.15)
				(type solid)
			)
			(layer "F.Fab")
		)
		(fp_line
			(start 0.201 -0.202)
			(end -0.101 0)
			(stroke
				(width 0.15)
				(type solid)
			)
			(layer "F.Fab")
		)
		(fp_rect
			(start 0.848 0.4)
			(end -0.85 -0.402)
			(stroke
				(width 0.15)
				(type solid)
			)
			(fill no)
			(layer "F.Fab")
		)
		(fp_text user "${REFERENCE}"
			(at -1.31 3.769 90)
			(layer "F.Fab")
			(effects
				(font
					(size 0.7 0.7)
					(thickness 0.15)
				)
				(justify right top)
			)
		)
		(fp_text user "License: Apache-2.0"
			(at -1.31 5.769 90)
			(layer "F.Fab")
			(effects
				(font
					(size 0.7 0.7)
					(thickness 0.15)
				)
				(justify right top)
			)
		)
		(fp_text user "Author: Antmicro"
			(at -1.31 4.769 90)
			(layer "F.Fab")
			(effects
				(font
					(size 0.7 0.7)
					(thickness 0.15)
				)
				(justify right top)
			)
		)
		(pad "1" smd roundrect
			(at -0.7 0 90)
			(size 0.8 1)
			(layers "F.Cu" "F.Mask" "F.Paste")
			(roundrect_rratio 0.2)
			(net 15 "/FPGA/INITN")
			(pinfunction "C")
			(pintype "passive")
		)
		(pad "2" smd roundrect
			(at 0.7 0 90)
			(size 0.8 1)
			(layers "F.Cu" "F.Mask" "F.Paste")
			(roundrect_rratio 0.2)
			(net 245 "Net-(D6-A)")
			(pinfunction "A")
			(pintype "passive")
		)
	)
	(footprint "antmicro-footprints:R_0402_1005Metric"
		(layer "F.Cu")
		(at 133.83 110.15 180)
		(descr "Resistor SMD 0402")
		(tags "resistor SMD 0402")
		(property "Reference" "R68"
			(at 3.2 0.01 180)
			(layer "F.SilkS")
			(effects
				(font
					(size 0.65 0.65)
					(thickness 0.15)
				)
				(justify left bottom)
			)
		)
		(property "Value" "R_10k_0402"
			(at 0 1.4 180)
			(layer "F.Fab")
			(hide yes)
			(effects
				(font
					(size 0.7 0.7)
					(thickness 0.15)
				)
				(justify left bottom)
			)
		)
		(property "Datasheet" "https://www.bourns.com/docs/product-datasheets/cr.pdf"
			(at 0 0 180)
			(layer "F.Fab")
			(hide yes)
			(effects
				(font
					(size 1.27 1.27)
					(thickness 0.15)
				)
			)
		)
		(property "Description" "SMD Chip Resistor, 10 kohm, ± 1%, 62.5 mW, 0402 [1005 Metric], Thick Film, General Purpose"
			(at 0 0 180)
			(layer "F.Fab")
			(hide yes)
			(effects
				(font
					(size 1.27 1.27)
					(thickness 0.15)
				)
			)
		)
		(property "Author" "Antmicro"
			(at 267.66 220.3 0)
			(layer "F.Fab")
			(hide yes)
			(effects
				(font
					(size 1 1)
					(thickness 0.15)
				)
			)
		)
		(property "License" "Apache-2.0"
			(at 267.66 220.3 0)
			(layer "F.Fab")
			(hide yes)
			(effects
				(font
					(size 1 1)
					(thickness 0.15)
				)
			)
		)
		(property "MPN" "CR0402-FX-1002GLF"
			(at 267.66 220.3 0)
			(layer "F.Fab")
			(hide yes)
			(effects
				(font
					(size 1 1)
					(thickness 0.15)
				)
			)
		)
		(property "Manufacturer" "Bourns"
			(at 267.66 220.3 0)
			(layer "F.Fab")
			(hide yes)
			(effects
				(font
					(size 1 1)
					(thickness 0.15)
				)
			)
		)
		(property "Tolerance" "1%"
			(at 267.66 220.3 0)
			(layer "F.Fab")
			(hide yes)
			(effects
				(font
					(size 1 1)
					(thickness 0.15)
				)
			)
		)
		(property "Val" "10k"
			(at 267.66 220.3 0)
			(layer "F.Fab")
			(hide yes)
			(effects
				(font
					(size 1 1)
					(thickness 0.15)
				)
			)
		)
		(sheetname "/FPGA/")
		(sheetfile "fpga.kicad_sch")
		(attr smd)
		(fp_rect
			(start -0.925 -0.47)
			(end 0.925 0.47)
			(stroke
				(width 0.05)
				(type default)
			)
			(fill no)
			(layer "F.CrtYd")
		)
		(fp_rect
			(start -0.5 -0.25)
			(end 0.5 0.25)
			(stroke
				(width 0.15)
				(type solid)
			)
			(fill no)
			(layer "F.Fab")
		)
		(fp_text user "${REFERENCE}"
			(at -0.95 3.168 180)
			(layer "F.Fab")
			(effects
				(font
					(size 0.7 0.7)
					(thickness 0.15)
				)
				(justify left bottom)
			)
		)
		(fp_text user "Author: Antmicro"
			(at -0.95 4.169 180)
			(layer "F.Fab")
			(effects
				(font
					(size 0.7 0.7)
					(thickness 0.15)
				)
				(justify left bottom)
			)
		)
		(fp_text user "License: Apache-2.0"
			(at -0.95 5.169 180)
			(layer "F.Fab")
			(effects
				(font
					(size 0.7 0.7)
					(thickness 0.15)
				)
				(justify left bottom)
			)
		)
		(pad "1" smd roundrect
			(at -0.48 0 180)
			(size 0.59 0.64)
			(layers "F.Cu" "F.Mask" "F.Paste")
			(roundrect_rratio 0.25)
			(net 36 "/FPGA/PROGRAMN")
			(pintype "passive")
		)
		(pad "2" smd roundrect
			(at 0.48 0 180)
			(size 0.59 0.64)
			(layers "F.Cu" "F.Mask" "F.Paste")
			(roundrect_rratio 0.25)
			(net 2 "+3V3")
			(pintype "passive")
		)
	)
	(footprint "antmicro-footprints:R_0603_1608Metric"
		(layer "F.Cu")
		(at 169.9 77.73 180)
		(descr "Resistor SMD 0603")
		(tags "resistor SMD 0603")
		(property "Reference" "R120"
			(at 1.46 0.86 180)
			(layer "F.SilkS")
			(effects
				(font
					(size 0.65 0.65)
					(thickness 0.15)
				)
				(justify left bottom)
			)
		)
		(property "Value" "R_200R_0603"
			(at 0 1.6 180)
			(layer "F.Fab")
			(hide yes)
			(effects
				(font
					(size 0.7 0.7)
					(thickness 0.15)
				)
				(justify left bottom)
			)
		)
		(property "Datasheet" "https://www.bourns.com/docs/product-datasheets/cr.pdf"
			(at 0 0 180)
			(layer "F.Fab")
			(hide yes)
			(effects
				(font
					(size 1.27 1.27)
					(thickness 0.15)
				)
			)
		)
		(property "Description" "SMD Chip Resistor, 200 ohm, ± 1%, 100 mW, 0603 [1608 Metric], Thick Film, General Purpose"
			(at 0 0 180)
			(layer "F.Fab")
			(hide yes)
			(effects
				(font
					(size 1.27 1.27)
					(thickness 0.15)
				)
			)
		)
		(property "Author" "Antmicro"
			(at 339.78 155.6 0)
			(layer "F.Fab")
			(hide yes)
			(effects
				(font
					(size 1 1)
					(thickness 0.15)
				)
			)
		)
		(property "License" "Apache-2.0"
			(at 339.78 155.6 0)
			(layer "F.Fab")
			(hide yes)
			(effects
				(font
					(size 1 1)
					(thickness 0.15)
				)
			)
		)
		(property "MPN" "CR0603-FX-2000ELF"
			(at 339.78 155.6 0)
			(layer "F.Fab")
			(hide yes)
			(effects
				(font
					(size 1 1)
					(thickness 0.15)
				)
			)
		)
		(property "Manufacturer" "Bourns"
			(at 339.78 155.6 0)
			(layer "F.Fab")
			(hide yes)
			(effects
				(font
					(size 1 1)
					(thickness 0.15)
				)
			)
		)
		(property "Tolerance" "1%"
			(at 339.78 155.6 0)
			(layer "F.Fab")
			(hide yes)
			(effects
				(font
					(size 1 1)
					(thickness 0.15)
				)
			)
		)
		(property "Val" "200R"
			(at 339.78 155.6 0)
			(layer "F.Fab")
			(hide yes)
			(effects
				(font
					(size 1 1)
					(thickness 0.15)
				)
			)
		)
		(sheetname "/Peripherals/")
		(sheetfile "peripherals.kicad_sch")
		(attr smd)
		(fp_line
			(start -0.15 0.4)
			(end 0.15 0.4)
			(stroke
				(width 0.15)
				(type solid)
			)
			(layer "F.SilkS")
		)
		(fp_line
			(start -0.15 -0.4)
			(end 0.15 -0.4)
			(stroke
				(width 0.15)
				(type solid)
			)
			(layer "F.SilkS")
		)
		(fp_rect
			(start -1.25 -0.65)
			(end 1.25 0.65)
			(stroke
				(width 0.05)
				(type solid)
			)
			(fill no)
			(layer "F.CrtYd")
		)
		(fp_rect
			(start -0.8 -0.4)
			(end 0.8 0.4)
			(stroke
				(width 0.15)
				(type solid)
			)
			(fill no)
			(layer "F.Fab")
		)
		(fp_text user "Author: Antmicro"
			(at -1.25 4.9 180)
			(layer "F.Fab")
			(effects
				(font
					(size 0.7 0.7)
					(thickness 0.15)
				)
				(justify left bottom)
			)
		)
		(fp_text user "${REFERENCE}"
			(at -1.25 3.898 180)
			(layer "F.Fab")
			(effects
				(font
					(size 0.7 0.7)
					(thickness 0.15)
				)
				(justify left bottom)
			)
		)
		(fp_text user "License: Apache-2.0"
			(at -1.25 5.9 180)
			(layer "F.Fab")
			(effects
				(font
					(size 0.7 0.7)
					(thickness 0.15)
				)
				(justify left bottom)
			)
		)
		(pad "1" smd roundrect
			(at -0.7 0 180)
			(size 0.8 1)
			(layers "F.Cu" "F.Mask" "F.Paste")
			(roundrect_rratio 0.2)
			(net 257 "Net-(D11-A)")
			(pintype "passive")
		)
		(pad "2" smd roundrect
			(at 0.7 0 180)
			(size 0.8 1)
			(layers "F.Cu" "F.Mask" "F.Paste")
			(roundrect_rratio 0.2)
			(net 310 "/Peripherals/QWIIC_3V3")
			(pintype "passive")
		)
	)
	(footprint "antmicro-footprints:R_0402_1005Metric"
		(layer "F.Cu")
		(at 107.9 90.24 180)
		(descr "Resistor SMD 0402")
		(tags "resistor SMD 0402")
		(property "Reference" "R82"
			(at 1.17 0.676084 180)
			(layer "F.SilkS")
			(effects
				(font
					(size 0.65 0.65)
					(thickness 0.15)
				)
				(justify left bottom)
			)
		)
		(property "Value" "R_0R_0402"
			(at 0 1.4 180)
			(layer "F.Fab")
			(hide yes)
			(effects
				(font
					(size 0.7 0.7)
					(thickness 0.15)
				)
				(justify left bottom)
			)
		)
		(property "Datasheet" "https://industrial.panasonic.com/cdbs/www-data/pdf/RDA0000/AOA0000C301.pdf"
			(at 0 0 180)
			(layer "F.Fab")
			(hide yes)
			(effects
				(font
					(size 1.27 1.27)
					(thickness 0.15)
				)
			)
		)
		(property "Description" "SMD Chip Resistor, Jumper, 0 ohm, 100 mW, 0402 [1005 Metric], Thick Film, General Purpose"
			(at 0 0 180)
			(layer "F.Fab")
			(hide yes)
			(effects
				(font
					(size 1.27 1.27)
					(thickness 0.15)
				)
			)
		)
		(property "Author" "Antmicro"
			(at 215.8 180.48 0)
			(layer "F.Fab")
			(hide yes)
			(effects
				(font
					(size 1 1)
					(thickness 0.15)
				)
			)
		)
		(property "Current" "1A"
			(at 215.8 180.48 0)
			(layer "F.Fab")
			(hide yes)
			(effects
				(font
					(size 1 1)
					(thickness 0.15)
				)
			)
		)
		(property "License" "Apache-2.0"
			(at 215.8 180.48 0)
			(layer "F.Fab")
			(hide yes)
			(effects
				(font
					(size 1 1)
					(thickness 0.15)
				)
			)
		)
		(property "MPN" "ERJ2GE0R00X"
			(at 215.8 180.48 0)
			(layer "F.Fab")
			(hide yes)
			(effects
				(font
					(size 1 1)
					(thickness 0.15)
				)
			)
		)
		(property "Manufacturer" "Panasonic"
			(at 215.8 180.48 0)
			(layer "F.Fab")
			(hide yes)
			(effects
				(font
					(size 1 1)
					(thickness 0.15)
				)
			)
		)
		(property "Tolerance" "~"
			(at 215.8 180.48 0)
			(layer "F.Fab")
			(hide yes)
			(effects
				(font
					(size 1 1)
					(thickness 0.15)
				)
			)
		)
		(property "Val" "0R"
			(at 215.8 180.48 0)
			(layer "F.Fab")
			(hide yes)
			(effects
				(font
					(size 1 1)
					(thickness 0.15)
				)
			)
		)
		(sheetname "/FPGA/")
		(sheetfile "fpga.kicad_sch")
		(attr smd)
		(fp_rect
			(start -0.925 -0.47)
			(end 0.925 0.47)
			(stroke
				(width 0.05)
				(type default)
			)
			(fill no)
			(layer "F.CrtYd")
		)
		(fp_rect
			(start -0.5 -0.25)
			(end 0.5 0.25)
			(stroke
				(width 0.15)
				(type solid)
			)
			(fill no)
			(layer "F.Fab")
		)
		(fp_text user "Author: Antmicro"
			(at -0.95 4.169 180)
			(layer "F.Fab")
			(effects
				(font
					(size 0.7 0.7)
					(thickness 0.15)
				)
				(justify left bottom)
			)
		)
		(fp_text user "${REFERENCE}"
			(at -0.95 3.168 180)
			(layer "F.Fab")
			(effects
				(font
					(size 0.7 0.7)
					(thickness 0.15)
				)
				(justify left bottom)
			)
		)
		(fp_text user "License: Apache-2.0"
			(at -0.95 5.169 180)
			(layer "F.Fab")
			(effects
				(font
					(size 0.7 0.7)
					(thickness 0.15)
				)
				(justify left bottom)
			)
		)
		(pad "1" smd roundrect
			(at -0.48 0 180)
			(size 0.59 0.64)
			(layers "F.Cu" "F.Mask" "F.Paste")
			(roundrect_rratio 0.25)
			(net 324 "Net-(U21-D4)")
			(pintype "passive")
		)
		(pad "2" smd roundrect
			(at 0.48 0 180)
			(size 0.59 0.64)
			(layers "F.Cu" "F.Mask" "F.Paste")
			(roundrect_rratio 0.25)
			(net 306 "Net-(U18-~{CS})")
			(pintype "passive")
		)
	)
	(footprint "antmicro-footprints:MP_Pad5.4mm_Drill2.7mm"
		(layer "F.Cu")
		(at 170.03 60.15)
		(descr "Mounting Hole 2.7mm, M2.5")
		(tags "mounting hole 2.7mm m2.5")
		(property "Reference" "MP3"
			(at 0 -2.9 0)
			(layer "F.SilkS")
			(hide yes)
			(effects
				(font
					(size 0.7 0.7)
					(thickness 0.15)
				)
				(justify left bottom)
			)
		)
		(property "Value" "MP_Pad5.4mm_Drill2.7mm"
			(at 0 3.6 0)
			(layer "F.Fab")
			(effects
				(font
					(size 0.7 0.7)
					(thickness 0.15)
				)
				(justify left bottom)
			)
		)
		(property "Description" "Mechanical part"
			(at 0 0 0)
			(layer "F.Fab")
			(hide yes)
			(effects
				(font
					(size 1.27 1.27)
					(thickness 0.15)
				)
			)
		)
		(property "Author" "Antmicro"
			(at 0 0 0)
			(unlocked yes)
			(layer "F.Fab")
			(hide yes)
			(effects
				(font
					(size 1 1)
					(thickness 0.15)
				)
			)
		)
		(property "License" "Apache-2.0"
			(at 0 0 0)
			(unlocked yes)
			(layer "F.Fab")
			(hide yes)
			(effects
				(font
					(size 1 1)
					(thickness 0.15)
				)
			)
		)
		(sheetname "/")
		(sheetfile "sdi-mipi-video-converter.kicad_sch")
		(attr exclude_from_pos_files exclude_from_bom)
		(fp_circle
			(center 0 0)
			(end 2.95 0)
			(stroke
				(width 0.05)
				(type default)
			)
			(fill no)
			(layer "F.CrtYd")
		)
		(fp_text user "Author: Antmicro"
			(at -8.4 7.2 0)
			(layer "F.Fab")
			(effects
				(font
					(size 0.7 0.7)
					(thickness 0.15)
				)
				(justify left bottom)
			)
		)
		(fp_text user "${REFERENCE}"
			(at -8.4 6 0)
			(layer "F.Fab")
			(effects
				(font
					(size 0.7 0.7)
					(thickness 0.15)
				)
				(justify left bottom)
			)
		)
		(fp_text user "License: Apache-2.0"
			(at -8.4 8.4 0)
			(layer "F.Fab")
			(effects
				(font
					(size 0.7 0.7)
					(thickness 0.15)
				)
				(justify left bottom)
			)
		)
		(pad "1" thru_hole circle
			(at 0 0)
			(size 5.4 5.4)
			(drill 2.7)
			(layers "*.Cu" "*.Mask")
			(remove_unused_layers no)
			(net 400 "unconnected-(MP3-Pad1)")
			(pintype "passive+no_connect")
			(solder_paste_margin_ratio -1)
		)
	)
	(footprint "antmicro-footprints:C_0603_1608Metric"
		(layer "F.Cu")
		(at 145.74 109.9 -90)
		(descr "Capacitor SMD 0603")
		(tags "capacitor 0603")
		(property "Reference" "C19"
			(at -1.16 -1.69 90)
			(layer "F.SilkS")
			(effects
				(font
					(size 0.65 0.65)
					(thickness 0.15)
				)
				(justify right bottom)
			)
		)
		(property "Value" "C_1u_0603"
			(at 0 1.6 90)
			(layer "F.Fab")
			(hide yes)
			(effects
				(font
					(size 0.7 0.7)
					(thickness 0.15)
				)
				(justify right bottom)
			)
		)
		(property "Datasheet" "https://spicat.kyocera-avx.com/product/mlcc/chartview/0603YD105KAT2A/"
			(at 0 0 270)
			(layer "F.Fab")
			(hide yes)
			(effects
				(font
					(size 1.27 1.27)
					(thickness 0.15)
				)
			)
		)
		(property "Description" "SMD Multilayer Ceramic Capacitor, 1 µF, 16 V, 0603 [1608 Metric], ± 10%, X5R, AVX 0603 MLCC"
			(at 0 0 270)
			(layer "F.Fab")
			(hide yes)
			(effects
				(font
					(size 1.27 1.27)
					(thickness 0.15)
				)
			)
		)
		(property "Author" "Antmicro"
			(at 35.84 255.64 0)
			(layer "F.Fab")
			(hide yes)
			(effects
				(font
					(size 1 1)
					(thickness 0.15)
				)
			)
		)
		(property "Dielectric" ""
			(at 35.84 255.64 0)
			(layer "F.Fab")
			(hide yes)
			(effects
				(font
					(size 1 1)
					(thickness 0.15)
				)
			)
		)
		(property "License" "Apache-2.0"
			(at 35.84 255.64 0)
			(layer "F.Fab")
			(hide yes)
			(effects
				(font
					(size 1 1)
					(thickness 0.15)
				)
			)
		)
		(property "MPN" "0603YD105KAT2A"
			(at 35.84 255.64 0)
			(layer "F.Fab")
			(hide yes)
			(effects
				(font
					(size 1 1)
					(thickness 0.15)
				)
			)
		)
		(property "Manufacturer" "KYOCERA AVX"
			(at 35.84 255.64 0)
			(layer "F.Fab")
			(hide yes)
			(effects
				(font
					(size 1 1)
					(thickness 0.15)
				)
			)
		)
		(property "Val" "1u"
			(at 35.84 255.64 0)
			(layer "F.Fab")
			(hide yes)
			(effects
				(font
					(size 1 1)
					(thickness 0.15)
				)
			)
		)
		(property "Voltage" ""
			(at 35.84 255.64 0)
			(layer "F.Fab")
			(hide yes)
			(effects
				(font
					(size 1 1)
					(thickness 0.15)
				)
			)
		)
		(sheetname "/Power Supply/")
		(sheetfile "supply.kicad_sch")
		(attr smd)
		(fp_line
			(start -0.15 0.4)
			(end 0.15 0.4)
			(stroke
				(width 0.15)
				(type solid)
			)
			(layer "F.SilkS")
		)
		(fp_line
			(start -0.15 -0.4)
			(end 0.15 -0.4)
			(stroke
				(width 0.15)
				(type solid)
			)
			(layer "F.SilkS")
		)
		(fp_rect
			(start -1.25 -0.65)
			(end 1.25 0.65)
			(stroke
				(width 0.05)
				(type solid)
			)
			(fill no)
			(layer "F.CrtYd")
		)
		(fp_rect
			(start -0.8 -0.4)
			(end 0.8 0.4)
			(stroke
				(width 0.15)
				(type solid)
			)
			(fill no)
			(layer "F.Fab")
		)
		(fp_text user "${REFERENCE}"
			(at -1.682 3.895 270)
			(layer "F.Fab")
			(effects
				(font
					(size 0.7 0.7)
					(thickness 0.15)
				)
				(justify left bottom)
			)
		)
		(fp_text user "License: Apache-2.0"
			(at -1.682 5.895 270)
			(layer "F.Fab")
			(effects
				(font
					(size 0.7 0.7)
					(thickness 0.15)
				)
				(justify left bottom)
			)
		)
		(fp_text user "Author: Antmicro"
			(at -1.682 4.894 270)
			(layer "F.Fab")
			(effects
				(font
					(size 0.7 0.7)
					(thickness 0.15)
				)
				(justify left bottom)
			)
		)
		(pad "1" smd roundrect
			(at -0.7 0 270)
			(size 0.8 1)
			(layers "F.Cu" "F.Mask" "F.Paste")
			(roundrect_rratio 0.2)
			(net 1 "GND")
			(pintype "passive")
		)
		(pad "2" smd roundrect
			(at 0.7 0 270)
			(size 0.8 1)
			(layers "F.Cu" "F.Mask" "F.Paste")
			(roundrect_rratio 0.2)
			(net 2 "+3V3")
			(pintype "passive")
		)
	)
	(footprint "antmicro-footprints:LED_0603_1608Metric_G"
		(layer "F.Cu")
		(at 164.79 70.3 90)
		(descr "LED SMD 0603 Green")
		(tags "LED SMD 0603 Green")
		(property "Reference" "D1"
			(at 1.2 -0.34 90)
			(layer "F.SilkS")
			(effects
				(font
					(size 0.65 0.65)
					(thickness 0.15)
				)
				(justify left top)
			)
		)
		(property "Value" "LED_G_0603_LTST-C190GKT"
			(at 0 1.6 90)
			(layer "F.Fab")
			(hide yes)
			(effects
				(font
					(size 0.7 0.7)
					(thickness 0.15)
				)
				(justify left top)
			)
		)
		(property "Datasheet" "https://media.digikey.com/pdf/Data%20Sheets/Lite-On%20PDFs/LTST-C190GKT.pdf"
			(at 0 0 90)
			(layer "F.Fab")
			(hide yes)
			(effects
				(font
					(size 1.27 1.27)
					(thickness 0.15)
				)
			)
		)
		(property "Description" "LED, Green, SMD, 0603, 20 mA, 2.1 V, 569 nm"
			(at 0 0 90)
			(layer "F.Fab")
			(hide yes)
			(effects
				(font
					(size 1.27 1.27)
					(thickness 0.15)
				)
			)
		)
		(property "Author" "Antmicro"
			(at 94.49 235.09 0)
			(layer "F.Fab")
			(hide yes)
			(effects
				(font
					(size 1 1)
					(thickness 0.15)
				)
			)
		)
		(property "License" "Apache-2.0"
			(at 94.49 235.09 0)
			(layer "F.Fab")
			(hide yes)
			(effects
				(font
					(size 1 1)
					(thickness 0.15)
				)
			)
		)
		(property "MPN" "LTST-C190GKT"
			(at 94.49 235.09 0)
			(layer "F.Fab")
			(hide yes)
			(effects
				(font
					(size 1 1)
					(thickness 0.15)
				)
			)
		)
		(property "Manufacturer" "Lite-On"
			(at 94.49 235.09 0)
			(layer "F.Fab")
			(hide yes)
			(effects
				(font
					(size 1 1)
					(thickness 0.15)
				)
			)
		)
		(property "Color" "Green"
			(at 0 0 90)
			(unlocked yes)
			(layer "F.Fab")
			(hide yes)
			(effects
				(font
					(size 1 1)
					(thickness 0.15)
				)
			)
		)
		(sheetname "/Power Supply/")
		(sheetfile "supply.kicad_sch")
		(attr smd)
		(fp_line
			(start 0.22 -0.35)
			(end -0.22 -0.35)
			(stroke
				(width 0.15)
				(type solid)
			)
			(layer "F.SilkS")
		)
		(fp_line
			(start -1.18 -0.319)
			(end -1.18 0.321)
			(stroke
				(width 0.15)
				(type solid)
			)
			(layer "F.SilkS")
		)
		(fp_line
			(start 0.105328 0.001008)
			(end 0.24 0.001)
			(stroke
				(width 0.1)
				(type solid)
			)
			(layer "F.SilkS")
		)
		(fp_line
			(start -0.094672 0.001008)
			(end 0.105328 -0.198992)
			(stroke
				(width 0.1)
				(type solid)
			)
			(layer "F.SilkS")
		)
		(fp_line
			(start -0.094672 0.001008)
			(end -0.24 0.001008)
			(stroke
				(width 0.1)
				(type solid)
			)
			(layer "F.SilkS")
		)
		(fp_line
			(start 0.105328 0.201008)
			(end 0.105328 -0.198992)
			(stroke
				(width 0.1)
				(type solid)
			)
			(layer "F.SilkS")
		)
		(fp_line
			(start 0.105328 0.201008)
			(end -0.094672 0.001008)
			(stroke
				(width 0.1)
				(type solid)
			)
			(layer "F.SilkS")
		)
		(fp_line
			(start -0.094672 0.201008)
			(end -0.094672 -0.198992)
			(stroke
				(width 0.1)
				(type solid)
			)
			(layer "F.SilkS")
		)
		(fp_line
			(start 0.22 0.35)
			(end -0.22 0.35)
			(stroke
				(width 0.15)
				(type solid)
			)
			(layer "F.SilkS")
		)
		(fp_rect
			(start 1.25 0.65)
			(end -1.25 -0.65)
			(stroke
				(width 0.05)
				(type solid)
			)
			(fill no)
			(layer "F.CrtYd")
		)
		(fp_line
			(start 0.201 -0.202)
			(end -0.101 0)
			(stroke
				(width 0.15)
				(type solid)
			)
			(layer "F.Fab")
		)
		(fp_line
			(start -0.199 -0.202)
			(end -0.199 0.1)
			(stroke
				(width 0.15)
				(type solid)
			)
			(layer "F.Fab")
		)
		(fp_line
			(start 0.599 0)
			(end 0.201 0)
			(stroke
				(width 0.15)
				(type solid)
			)
			(layer "F.Fab")
		)
		(fp_line
			(start 0.201 0)
			(end 0.201 -0.202)
			(stroke
				(width 0.15)
				(type solid)
			)
			(layer "F.Fab")
		)
		(fp_line
			(start -0.101 0)
			(end 0.201 0.2)
			(stroke
				(width 0.15)
				(type solid)
			)
			(layer "F.Fab")
		)
		(fp_line
			(start -0.199 0)
			(end -0.597 0)
			(stroke
				(width 0.15)
				(type solid)
			)
			(layer "F.Fab")
		)
		(fp_line
			(start 0.201 0.2)
			(end 0.201 0)
			(stroke
				(width 0.15)
				(type solid)
			)
			(layer "F.Fab")
		)
		(fp_line
			(start -0.199 0.2)
			(end -0.199 0.1)
			(stroke
				(width 0.15)
				(type solid)
			)
			(layer "F.Fab")
		)
		(fp_rect
			(start 0.848 0.4)
			(end -0.85 -0.402)
			(stroke
				(width 0.15)
				(type solid)
			)
			(fill no)
			(layer "F.Fab")
		)
		(fp_text user "Author: Antmicro"
			(at -1.4224 4.799 90)
			(layer "F.Fab")
			(effects
				(font
					(size 0.7 0.7)
					(thickness 0.15)
				)
				(justify left bottom)
			)
		)
		(fp_text user "License: Apache-2.0"
			(at -1.4224 3.599 90)
			(layer "F.Fab")
			(effects
				(font
					(size 0.7 0.7)
					(thickness 0.15)
				)
				(justify left bottom)
			)
		)
		(fp_text user "${REFERENCE}"
			(at -1.4224 5.999 90)
			(layer "F.Fab")
			(effects
				(font
					(size 0.7 0.7)
					(thickness 0.15)
				)
				(justify left bottom)
			)
		)
		(pad "1" smd roundrect
			(at -0.7 0 270)
			(size 0.8 1)
			(layers "F.Cu" "F.Mask" "F.Paste")
			(roundrect_rratio 0.2)
			(net 1 "GND")
			(pinfunction "C")
			(pintype "passive")
		)
		(pad "2" smd roundrect
			(at 0.7 0 270)
			(size 0.8 1)
			(layers "F.Cu" "F.Mask" "F.Paste")
			(roundrect_rratio 0.2)
			(net 58 "Net-(D1-A)")
			(pinfunction "A")
			(pintype "passive")
		)
	)
	(footprint "antmicro-footprints:R_0402_1005Metric"
		(layer "F.Cu")
		(at 165.19 59.04 180)
		(descr "Resistor SMD 0402")
		(tags "resistor SMD 0402")
		(property "Reference" "R27"
			(at 1.06 0.7 180)
			(layer "F.SilkS")
			(effects
				(font
					(size 0.65 0.65)
					(thickness 0.15)
				)
				(justify left bottom)
			)
		)
		(property "Value" "R_10k_0402"
			(at 0 1.4 180)
			(layer "F.Fab")
			(hide yes)
			(effects
				(font
					(size 0.7 0.7)
					(thickness 0.15)
				)
				(justify left bottom)
			)
		)
		(property "Datasheet" "https://www.bourns.com/docs/product-datasheets/cr.pdf"
			(at 0 0 180)
			(layer "F.Fab")
			(hide yes)
			(effects
				(font
					(size 1.27 1.27)
					(thickness 0.15)
				)
			)
		)
		(property "Description" "SMD Chip Resistor, 10 kohm, ± 1%, 62.5 mW, 0402 [1005 Metric], Thick Film, General Purpose"
			(at 0 0 180)
			(layer "F.Fab")
			(hide yes)
			(effects
				(font
					(size 1.27 1.27)
					(thickness 0.15)
				)
			)
		)
		(property "Author" "Antmicro"
			(at 330.38 118.08 0)
			(layer "F.Fab")
			(hide yes)
			(effects
				(font
					(size 1 1)
					(thickness 0.15)
				)
			)
		)
		(property "License" "Apache-2.0"
			(at 330.38 118.08 0)
			(layer "F.Fab")
			(hide yes)
			(effects
				(font
					(size 1 1)
					(thickness 0.15)
				)
			)
		)
		(property "MPN" "CR0402-FX-1002GLF"
			(at 330.38 118.08 0)
			(layer "F.Fab")
			(hide yes)
			(effects
				(font
					(size 1 1)
					(thickness 0.15)
				)
			)
		)
		(property "Manufacturer" "Bourns"
			(at 330.38 118.08 0)
			(layer "F.Fab")
			(hide yes)
			(effects
				(font
					(size 1 1)
					(thickness 0.15)
				)
			)
		)
		(property "Tolerance" "1%"
			(at 330.38 118.08 0)
			(layer "F.Fab")
			(hide yes)
			(effects
				(font
					(size 1 1)
					(thickness 0.15)
				)
			)
		)
		(property "Val" "10k"
			(at 330.38 118.08 0)
			(layer "F.Fab")
			(hide yes)
			(effects
				(font
					(size 1 1)
					(thickness 0.15)
				)
			)
		)
		(sheetname "/Power Supply/")
		(sheetfile "supply.kicad_sch")
		(attr smd)
		(fp_rect
			(start -0.925 -0.47)
			(end 0.925 0.47)
			(stroke
				(width 0.05)
				(type default)
			)
			(fill no)
			(layer "F.CrtYd")
		)
		(fp_rect
			(start -0.5 -0.25)
			(end 0.5 0.25)
			(stroke
				(width 0.15)
				(type solid)
			)
			(fill no)
			(layer "F.Fab")
		)
		(fp_text user "${REFERENCE}"
			(at -0.95 3.168 180)
			(layer "F.Fab")
			(effects
				(font
					(size 0.7 0.7)
					(thickness 0.15)
				)
				(justify left bottom)
			)
		)
		(fp_text user "License: Apache-2.0"
			(at -0.95 5.169 180)
			(layer "F.Fab")
			(effects
				(font
					(size 0.7 0.7)
					(thickness 0.15)
				)
				(justify left bottom)
			)
		)
		(fp_text user "Author: Antmicro"
			(at -0.95 4.169 180)
			(layer "F.Fab")
			(effects
				(font
					(size 0.7 0.7)
					(thickness 0.15)
				)
				(justify left bottom)
			)
		)
		(pad "1" smd roundrect
			(at -0.48 0 180)
			(size 0.59 0.64)
			(layers "F.Cu" "F.Mask" "F.Paste")
			(roundrect_rratio 0.25)
			(net 1 "GND")
			(pintype "passive")
		)
		(pad "2" smd roundrect
			(at 0.48 0 180)
			(size 0.59 0.64)
			(layers "F.Cu" "F.Mask" "F.Paste")
			(roundrect_rratio 0.25)
			(net 270 "Net-(U7-FB)")
			(pintype "passive")
		)
	)
	(footprint "antmicro-footprints:TP_SMD_0.75mm"
		(layer "F.Cu")
		(at 100.25 69.5)
		(property "Reference" "TP25"
			(at 0.53 0.39 0)
			(layer "F.SilkS")
			(effects
				(font
					(size 0.65 0.65)
					(thickness 0.15)
				)
				(justify left bottom)
			)
		)
		(property "Value" "TP_0.75mm_SMD"
			(at 0 1.2 0)
			(layer "F.Fab")
			(hide yes)
			(effects
				(font
					(size 0.7 0.7)
					(thickness 0.15)
				)
				(justify left bottom)
			)
		)
		(property "Description" "SMT test point"
			(at 0 0 0)
			(layer "F.Fab")
			(hide yes)
			(effects
				(font
					(size 1.27 1.27)
					(thickness 0.15)
				)
			)
		)
		(property "Author" "Antmicro"
			(at 0 0 0)
			(layer "F.Fab")
			(hide yes)
			(effects
				(font
					(size 1 1)
					(thickness 0.15)
				)
			)
		)
		(property "License" "Apache-2.0"
			(at 0 0 0)
			(layer "F.Fab")
			(hide yes)
			(effects
				(font
					(size 1 1)
					(thickness 0.15)
				)
			)
		)
		(property "MPN" ""
			(at 0 0 0)
			(layer "F.Fab")
			(hide yes)
			(effects
				(font
					(size 1 1)
					(thickness 0.15)
				)
			)
		)
		(property "Manufacturer" ""
			(at 0 0 0)
			(layer "F.Fab")
			(hide yes)
			(effects
				(font
					(size 1 1)
					(thickness 0.15)
				)
			)
		)
		(sheetname "/SDI/")
		(sheetfile "sdi.kicad_sch")
		(attr exclude_from_pos_files)
		(fp_circle
			(center 0 0)
			(end 0.475 0)
			(stroke
				(width 0.05)
				(type default)
			)
			(fill no)
			(layer "F.CrtYd")
		)
		(fp_text user "Author: Antmicro"
			(at -0.4 3.901 0)
			(layer "F.Fab")
			(effects
				(font
					(size 0.7 0.7)
					(thickness 0.15)
				)
				(justify left bottom)
			)
		)
		(fp_text user "License: Apache-2.0"
			(at -0.4 5.101 0)
			(layer "F.Fab")
			(effects
				(font
					(size 0.7 0.7)
					(thickness 0.15)
				)
				(justify left bottom)
			)
		)
		(fp_text user "${REFERENCE}"
			(at -0.4 2.7 0)
			(layer "F.Fab")
			(effects
				(font
					(size 0.7 0.7)
					(thickness 0.15)
				)
				(justify left bottom)
			)
		)
		(pad "1" smd circle
			(at 0 0)
			(size 0.75 0.75)
			(layers "F.Cu" "F.Mask")
			(net 217 "/SDI/SDI_STAT1")
			(pinfunction "1")
			(pintype "passive")
		)
	)
	(footprint "antmicro-footprints:MP_Pad5.4mm_Drill2.7mm"
		(layer "F.Cu")
		(at 80.03 60.15)
		(descr "Mounting Hole 2.7mm, M2.5")
		(tags "mounting hole 2.7mm m2.5")
		(property "Reference" "MP1"
			(at 0 -2.9 0)
			(layer "F.SilkS")
			(hide yes)
			(effects
				(font
					(size 0.7 0.7)
					(thickness 0.15)
				)
				(justify left bottom)
			)
		)
		(property "Value" "MP_Pad5.4mm_Drill2.7mm"
			(at 0 3.6 0)
			(layer "F.Fab")
			(effects
				(font
					(size 0.7 0.7)
					(thickness 0.15)
				)
				(justify left bottom)
			)
		)
		(property "Description" "Mechanical part"
			(at 0 0 0)
			(layer "F.Fab")
			(hide yes)
			(effects
				(font
					(size 1.27 1.27)
					(thickness 0.15)
				)
			)
		)
		(property "Author" "Antmicro"
			(at 0 0 0)
			(unlocked yes)
			(layer "F.Fab")
			(hide yes)
			(effects
				(font
					(size 1 1)
					(thickness 0.15)
				)
			)
		)
		(property "License" "Apache-2.0"
			(at 0 0 0)
			(unlocked yes)
			(layer "F.Fab")
			(hide yes)
			(effects
				(font
					(size 1 1)
					(thickness 0.15)
				)
			)
		)
		(sheetname "/")
		(sheetfile "sdi-mipi-video-converter.kicad_sch")
		(attr exclude_from_pos_files exclude_from_bom)
		(fp_circle
			(center 0 0)
			(end 2.95 0)
			(stroke
				(width 0.05)
				(type default)
			)
			(fill no)
			(layer "F.CrtYd")
		)
		(fp_text user "${REFERENCE}"
			(at -8.4 6 0)
			(layer "F.Fab")
			(effects
				(font
					(size 0.7 0.7)
					(thickness 0.15)
				)
				(justify left bottom)
			)
		)
		(fp_text user "License: Apache-2.0"
			(at -8.4 8.4 0)
			(layer "F.Fab")
			(effects
				(font
					(size 0.7 0.7)
					(thickness 0.15)
				)
				(justify left bottom)
			)
		)
		(fp_text user "Author: Antmicro"
			(at -8.4 7.2 0)
			(layer "F.Fab")
			(effects
				(font
					(size 0.7 0.7)
					(thickness 0.15)
				)
				(justify left bottom)
			)
		)
		(pad "1" thru_hole circle
			(at 0 0)
			(size 5.4 5.4)
			(drill 2.7)
			(layers "*.Cu" "*.Mask")
			(remove_unused_layers no)
			(net 398 "unconnected-(MP1-Pad1)")
			(pintype "passive+no_connect")
			(solder_paste_margin_ratio -1)
		)
	)
	(footprint "antmicro-footprints:R_0603_1608Metric"
		(layer "F.Cu")
		(at 105.58 70.55 90)
		(descr "Resistor SMD 0603")
		(tags "resistor SMD 0603")
		(property "Reference" "R100"
			(at 1.41 0.45 90)
			(layer "F.SilkS")
			(effects
				(font
					(size 0.65 0.65)
					(thickness 0.15)
				)
				(justify left bottom)
			)
		)
		(property "Value" "R_200R_0603"
			(at 0 1.6 90)
			(layer "F.Fab")
			(hide yes)
			(effects
				(font
					(size 0.7 0.7)
					(thickness 0.15)
				)
				(justify left bottom)
			)
		)
		(property "Datasheet" "https://www.bourns.com/docs/product-datasheets/cr.pdf"
			(at 0 0 90)
			(layer "F.Fab")
			(hide yes)
			(effects
				(font
					(size 1.27 1.27)
					(thickness 0.15)
				)
			)
		)
		(property "Description" "SMD Chip Resistor, 200 ohm, ± 1%, 100 mW, 0603 [1608 Metric], Thick Film, General Purpose"
			(at 0 0 90)
			(layer "F.Fab")
			(hide yes)
			(effects
				(font
					(size 1.27 1.27)
					(thickness 0.15)
				)
			)
		)
		(property "Author" "Antmicro"
			(at 176.13 -35.03 0)
			(layer "F.Fab")
			(hide yes)
			(effects
				(font
					(size 1 1)
					(thickness 0.15)
				)
			)
		)
		(property "License" "Apache-2.0"
			(at 176.13 -35.03 0)
			(layer "F.Fab")
			(hide yes)
			(effects
				(font
					(size 1 1)
					(thickness 0.15)
				)
			)
		)
		(property "MPN" "CR0603-FX-2000ELF"
			(at 176.13 -35.03 0)
			(layer "F.Fab")
			(hide yes)
			(effects
				(font
					(size 1 1)
					(thickness 0.15)
				)
			)
		)
		(property "Manufacturer" "Bourns"
			(at 176.13 -35.03 0)
			(layer "F.Fab")
			(hide yes)
			(effects
				(font
					(size 1 1)
					(thickness 0.15)
				)
			)
		)
		(property "Tolerance" "1%"
			(at 176.13 -35.03 0)
			(layer "F.Fab")
			(hide yes)
			(effects
				(font
					(size 1 1)
					(thickness 0.15)
				)
			)
		)
		(property "Val" "200R"
			(at 176.13 -35.03 0)
			(layer "F.Fab")
			(hide yes)
			(effects
				(font
					(size 1 1)
					(thickness 0.15)
				)
			)
		)
		(sheetname "/SDI/")
		(sheetfile "sdi.kicad_sch")
		(attr smd)
		(fp_line
			(start -0.15 -0.4)
			(end 0.15 -0.4)
			(stroke
				(width 0.15)
				(type solid)
			)
			(layer "F.SilkS")
		)
		(fp_line
			(start -0.15 0.4)
			(end 0.15 0.4)
			(stroke
				(width 0.15)
				(type solid)
			)
			(layer "F.SilkS")
		)
		(fp_rect
			(start -1.25 -0.65)
			(end 1.25 0.65)
			(stroke
				(width 0.05)
				(type solid)
			)
			(fill no)
			(layer "F.CrtYd")
		)
		(fp_rect
			(start -0.8 -0.4)
			(end 0.8 0.4)
			(stroke
				(width 0.15)
				(type solid)
			)
			(fill no)
			(layer "F.Fab")
		)
		(fp_text user "License: Apache-2.0"
			(at -1.25 5.9 90)
			(layer "F.Fab")
			(effects
				(font
					(size 0.7 0.7)
					(thickness 0.15)
				)
				(justify left bottom)
			)
		)
		(fp_text user "${REFERENCE}"
			(at -1.25 3.898 90)
			(layer "F.Fab")
			(effects
				(font
					(size 0.7 0.7)
					(thickness 0.15)
				)
				(justify left bottom)
			)
		)
		(fp_text user "Author: Antmicro"
			(at -1.25 4.9 90)
			(layer "F.Fab")
			(effects
				(font
					(size 0.7 0.7)
					(thickness 0.15)
				)
				(justify left bottom)
			)
		)
		(pad "1" smd roundrect
			(at -0.7 0 90)
			(size 0.8 1)
			(layers "F.Cu" "F.Mask" "F.Paste")
			(roundrect_rratio 0.2)
			(net 246 "Net-(D7-A)")
			(pintype "passive")
		)
		(pad "2" smd roundrect
			(at 0.7 0 90)
			(size 0.8 1)
			(layers "F.Cu" "F.Mask" "F.Paste")
			(roundrect_rratio 0.2)
			(net 183 "/SDI/SDI_STAT5")
			(pintype "passive")
		)
	)
	(footprint "antmicro-footprints:R_0603_1608Metric"
		(layer "F.Cu")
		(at 138.79 112.9 90)
		(descr "Resistor SMD 0603")
		(tags "resistor SMD 0603")
		(property "Reference" "R37"
			(at -1.64 -0.96 90)
			(layer "F.SilkS")
			(effects
				(font
					(size 0.65 0.65)
					(thickness 0.15)
				)
				(justify left bottom)
			)
		)
		(property "Value" "R_0R_0603"
			(at 0 1.6 90)
			(layer "F.Fab")
			(hide yes)
			(effects
				(font
					(size 0.7 0.7)
					(thickness 0.15)
				)
				(justify left bottom)
			)
		)
		(property "Datasheet" "https://www.bourns.com/docs/product-datasheets/cr.pdf?sfvrsn=574d41f6_14"
			(at 0 0 90)
			(layer "F.Fab")
			(hide yes)
			(effects
				(font
					(size 1.27 1.27)
					(thickness 0.15)
				)
			)
		)
		(property "Description" "Zero Ohm Resistor, Jumper, 0603 [1608 Metric], Thick Film, 100 mW, 1 A, Surface Mount Device, CR"
			(at 0 0 90)
			(layer "F.Fab")
			(hide yes)
			(effects
				(font
					(size 1.27 1.27)
					(thickness 0.15)
				)
			)
		)
		(property "Author" "Antmicro"
			(at 251.69 -25.89 0)
			(layer "F.Fab")
			(hide yes)
			(effects
				(font
					(size 1 1)
					(thickness 0.15)
				)
			)
		)
		(property "Current" "1A"
			(at 251.69 -25.89 0)
			(layer "F.Fab")
			(hide yes)
			(effects
				(font
					(size 1 1)
					(thickness 0.15)
				)
			)
		)
		(property "License" "Apache-2.0"
			(at 251.69 -25.89 0)
			(layer "F.Fab")
			(hide yes)
			(effects
				(font
					(size 1 1)
					(thickness 0.15)
				)
			)
		)
		(property "MPN" "CR0603-J/-000ELF"
			(at 251.69 -25.89 0)
			(layer "F.Fab")
			(hide yes)
			(effects
				(font
					(size 1 1)
					(thickness 0.15)
				)
			)
		)
		(property "Manufacturer" "Bourns"
			(at 251.69 -25.89 0)
			(layer "F.Fab")
			(hide yes)
			(effects
				(font
					(size 1 1)
					(thickness 0.15)
				)
			)
		)
		(property "Tolerance" "~"
			(at 251.69 -25.89 0)
			(layer "F.Fab")
			(hide yes)
			(effects
				(font
					(size 1 1)
					(thickness 0.15)
				)
			)
		)
		(property "Val" "0R"
			(at 251.69 -25.89 0)
			(layer "F.Fab")
			(hide yes)
			(effects
				(font
					(size 1 1)
					(thickness 0.15)
				)
			)
		)
		(sheetname "/Power Supply/")
		(sheetfile "supply.kicad_sch")
		(attr smd)
		(fp_line
			(start -0.15 -0.4)
			(end 0.15 -0.4)
			(stroke
				(width 0.15)
				(type solid)
			)
			(layer "F.SilkS")
		)
		(fp_line
			(start -0.15 0.4)
			(end 0.15 0.4)
			(stroke
				(width 0.15)
				(type solid)
			)
			(layer "F.SilkS")
		)
		(fp_rect
			(start -1.25 -0.65)
			(end 1.25 0.65)
			(stroke
				(width 0.05)
				(type solid)
			)
			(fill no)
			(layer "F.CrtYd")
		)
		(fp_rect
			(start -0.8 -0.4)
			(end 0.8 0.4)
			(stroke
				(width 0.15)
				(type solid)
			)
			(fill no)
			(layer "F.Fab")
		)
		(fp_text user "License: Apache-2.0"
			(at -1.25 5.9 90)
			(layer "F.Fab")
			(effects
				(font
					(size 0.7 0.7)
					(thickness 0.15)
				)
				(justify left bottom)
			)
		)
		(fp_text user "Author: Antmicro"
			(at -1.25 4.9 90)
			(layer "F.Fab")
			(effects
				(font
					(size 0.7 0.7)
					(thickness 0.15)
				)
				(justify left bottom)
			)
		)
		(fp_text user "${REFERENCE}"
			(at -1.25 3.898 90)
			(layer "F.Fab")
			(effects
				(font
					(size 0.7 0.7)
					(thickness 0.15)
				)
				(justify left bottom)
			)
		)
		(pad "1" smd roundrect
			(at -0.7 0 90)
			(size 0.8 1)
			(layers "F.Cu" "F.Mask" "F.Paste")
			(roundrect_rratio 0.2)
			(net 284 "Net-(U10-V_{OUT})")
			(pintype "passive")
		)
		(pad "2" smd roundrect
			(at 0.7 0 90)
			(size 0.8 1)
			(layers "F.Cu" "F.Mask" "F.Paste")
			(roundrect_rratio 0.2)
			(net 50 "+1V8")
			(pintype "passive")
		)
	)
	(footprint "antmicro-footprints:Conn_BNC_031-70526-21"
		(layer "F.Cu")
		(at 68.45 74.85 -90)
		(property "Reference" "J2"
			(at 6.69 -7.98 0)
			(unlocked yes)
			(layer "F.SilkS")
			(effects
				(font
					(size 0.65 0.65)
					(thickness 0.15)
				)
				(justify left bottom)
			)
		)
		(property "Value" "Conn_BNC_031-70526-21"
			(at 0 13.9 90)
			(layer "F.Fab")
			(hide yes)
			(effects
				(font
					(size 0.7 0.7)
					(thickness 0.15)
				)
				(justify right bottom)
			)
		)
		(property "Datasheet" "https://www.farnell.com/cad/2305565.pdf?_ga=2.190633003.1014497200.1574067480-156563690.1566371002&_gac=1.57062104.1572875319.Cj0KCQiAtf_tBRDtARIsAIbAKe0A1M5y_jdFCiNLNrHM5L2GjmDvn_4qnRvhHAD9jBdL9AmoMNThLCoaAjhJEALw_wcB"
			(at 0 0 270)
			(layer "F.Fab")
			(hide yes)
			(effects
				(font
					(size 1.27 1.27)
					(thickness 0.15)
				)
			)
		)
		(property "Description" "RF / Coaxial Connector, BNC Coaxial, Straight Bulkhead Jack, Board Edge / End Launch, 75 ohm"
			(at 0 0 270)
			(layer "F.Fab")
			(hide yes)
			(effects
				(font
					(size 1.27 1.27)
					(thickness 0.15)
				)
			)
		)
		(property "Author" "Antmicro"
			(at -6.4 143.3 0)
			(layer "F.Fab")
			(hide yes)
			(effects
				(font
					(size 1 1)
					(thickness 0.15)
				)
			)
		)
		(property "License" "Apache-2.0"
			(at -6.4 143.3 0)
			(layer "F.Fab")
			(hide yes)
			(effects
				(font
					(size 1 1)
					(thickness 0.15)
				)
			)
		)
		(property "MPN" "031-70526-21"
			(at -6.4 143.3 0)
			(layer "F.Fab")
			(hide yes)
			(effects
				(font
					(size 1 1)
					(thickness 0.15)
				)
			)
		)
		(property "Manufacturer" "Amphenol"
			(at -6.4 143.3 0)
			(layer "F.Fab")
			(hide yes)
			(effects
				(font
					(size 1 1)
					(thickness 0.15)
				)
			)
		)
		(property ki_fp_filters "*BNC* *SMA* *SMB* *SMC* *Cinch*")
		(sheetname "/SDI/")
		(sheetfile "sdi.kicad_sch")
		(attr smd)
		(fp_line
			(start 7.3 12.9)
			(end -7.4 12.9)
			(stroke
				(width 0.05)
				(type solid)
			)
			(layer "B.CrtYd")
		)
		(fp_line
			(start -8.2 -4.6)
			(end -7.4 -4.6)
			(stroke
				(width 0.05)
				(type solid)
			)
			(layer "B.CrtYd")
		)
		(fp_line
			(start -7.4 -4.6)
			(end -7.4 12.9)
			(stroke
				(width 0.05)
				(type solid)
			)
			(layer "B.CrtYd")
		)
		(fp_line
			(start 7.3 -4.6)
			(end 7.3 12.9)
			(stroke
				(width 0.05)
				(type solid)
			)
			(layer "B.CrtYd")
		)
		(fp_line
			(start 8.1 -4.6)
			(end 7.3 -4.6)
			(stroke
				(width 0.05)
				(type solid)
			)
			(layer "B.CrtYd")
		)
		(fp_line
			(start -8.2 -5.5)
			(end -8.2 -4.6)
			(stroke
				(width 0.05)
				(type solid)
			)
			(layer "B.CrtYd")
		)
		(fp_line
			(start -6.6 -5.5)
			(end -8.2 -5.5)
			(stroke
				(width 0.05)
				(type solid)
			)
			(layer "B.CrtYd")
		)
		(fp_line
			(start 6.5 -5.5)
			(end 8.1 -5.5)
			(stroke
				(width 0.05)
				(type solid)
			)
			(layer "B.CrtYd")
		)
		(fp_line
			(start 8.1 -5.5)
			(end 8.1 -4.6)
			(stroke
				(width 0.05)
				(type solid)
			)
			(layer "B.CrtYd")
		)
		(fp_line
			(start -6.6 -6.6)
			(end -6.6 -5.5)
			(stroke
				(width 0.05)
				(type solid)
			)
			(layer "B.CrtYd")
		)
		(fp_line
			(start -5.7 -6.6)
			(end -6.6 -6.6)
			(stroke
				(width 0.05)
				(type solid)
			)
			(layer "B.CrtYd")
		)
		(fp_line
			(start 5.6 -6.6)
			(end 6.5 -6.6)
			(stroke
				(width 0.05)
				(type solid)
			)
			(layer "B.CrtYd")
		)
		(fp_line
			(start 6.5 -6.6)
			(end 6.5 -5.5)
			(stroke
				(width 0.05)
				(type solid)
			)
			(layer "B.CrtYd")
		)
		(fp_line
			(start 4.1 -12.9)
			(end -4.2 -12.9)
			(stroke
				(width 0.05)
				(type solid)
			)
			(layer "B.CrtYd")
		)
		(fp_line
			(start -5.7 -13.6)
			(end -5.7 -6.6)
			(stroke
				(width 0.05)
				(type solid)
			)
			(layer "B.CrtYd")
		)
		(fp_line
			(start -4.2 -13.6)
			(end -4.2 -12.9)
			(stroke
				(width 0.05)
				(type solid)
			)
			(layer "B.CrtYd")
		)
		(fp_line
			(start -4.2 -13.6)
			(end -5.7 -13.6)
			(stroke
				(width 0.05)
				(type solid)
			)
			(layer "B.CrtYd")
		)
		(fp_line
			(start 4.1 -13.6)
			(end 4.1 -12.9)
			(stroke
				(width 0.05)
				(type solid)
			)
			(layer "B.CrtYd")
		)
		(fp_line
			(start 4.1 -13.6)
			(end 5.6 -13.6)
			(stroke
				(width 0.05)
				(type solid)
			)
			(layer "B.CrtYd")
		)
		(fp_line
			(start 5.6 -13.6)
			(end 5.6 -6.6)
			(stroke
				(width 0.05)
				(type solid)
			)
			(layer "B.CrtYd")
		)
		(fp_line
			(start -7.4 12.9)
			(end 7.3 12.9)
			(stroke
				(width 0.05)
				(type solid)
			)
			(layer "F.CrtYd")
		)
		(fp_line
			(start -8.2 -4.6)
			(end -7.4 -4.6)
			(stroke
				(width 0.05)
				(type solid)
			)
			(layer "F.CrtYd")
		)
		(fp_line
			(start -7.4 -4.6)
			(end -7.4 12.9)
			(stroke
				(width 0.05)
				(type solid)
			)
			(layer "F.CrtYd")
		)
		(fp_line
			(start 7.3 -4.6)
			(end 7.3 12.9)
			(stroke
				(width 0.05)
				(type solid)
			)
			(layer "F.CrtYd")
		)
		(fp_line
			(start 8.1 -4.6)
			(end 7.3 -4.6)
			(stroke
				(width 0.05)
				(type solid)
			)
			(layer "F.CrtYd")
		)
		(fp_line
			(start -8.2 -5.5)
			(end -8.2 -4.6)
			(stroke
				(width 0.05)
				(type solid)
			)
			(layer "F.CrtYd")
		)
		(fp_line
			(start -6.6 -5.5)
			(end -8.2 -5.5)
			(stroke
				(width 0.05)
				(type solid)
			)
			(layer "F.CrtYd")
		)
		(fp_line
			(start 6.5 -5.5)
			(end 8.1 -5.5)
			(stroke
				(width 0.05)
				(type solid)
			)
			(layer "F.CrtYd")
		)
		(fp_line
			(start 8.1 -5.5)
			(end 8.1 -4.6)
			(stroke
				(width 0.05)
				(type solid)
			)
			(layer "F.CrtYd")
		)
		(fp_line
			(start -6.6 -6.6)
			(end -6.6 -5.5)
			(stroke
				(width 0.05)
				(type solid)
			)
			(layer "F.CrtYd")
		)
		(fp_line
			(start -5.7 -6.6)
			(end -6.6 -6.6)
			(stroke
				(width 0.05)
				(type solid)
			)
			(layer "F.CrtYd")
		)
		(fp_line
			(start 5.6 -6.6)
			(end 6.5 -6.6)
			(stroke
				(width 0.05)
				(type solid)
			)
			(layer "F.CrtYd")
		)
		(fp_line
			(start 6.5 -6.6)
			(end 6.5 -5.5)
			(stroke
				(width 0.05)
				(type solid)
			)
			(layer "F.CrtYd")
		)
		(fp_line
			(start -4.2 -12.9)
			(end 4.1 -12.9)
			(stroke
				(width 0.05)
				(type solid)
			)
			(layer "F.CrtYd")
		)
		(fp_line
			(start -5.7 -13.6)
			(end -5.7 -6.6)
			(stroke
				(width 0.05)
				(type solid)
			)
			(layer "F.CrtYd")
		)
		(fp_line
			(start -4.2 -13.6)
			(end -4.2 -12.9)
			(stroke
				(width 0.05)
				(type solid)
			)
			(layer "F.CrtYd")
		)
		(fp_line
			(start -4.2 -13.6)
			(end -5.7 -13.6)
			(stroke
				(width 0.05)
				(type solid)
			)
			(layer "F.CrtYd")
		)
		(fp_line
			(start 4.1 -13.6)
			(end 4.1 -12.9)
			(stroke
				(width 0.05)
				(type solid)
			)
			(layer "F.CrtYd")
		)
		(fp_line
			(start 4.1 -13.6)
			(end 5.6 -13.6)
			(stroke
				(width 0.05)
				(type solid)
			)
			(layer "F.CrtYd")
		)
		(fp_line
			(start 5.6 -13.6)
			(end 5.6 -6.6)
			(stroke
				(width 0.05)
				(type solid)
			)
			(layer "F.CrtYd")
		)
		(pad "1" smd rect
			(at 0 -7.872 270)
			(size 1.1 1.75)
			(layers "F.Cu" "F.Mask" "F.Paste")
			(net 253 "/SDI/SDI_IN")
			(pinfunction "1")
			(pintype "passive")
		)
		(pad "2" smd rect
			(at -4.851 -10.221 270)
			(size 1.1 6.45)
			(layers "F.Cu" "F.Mask" "F.Paste")
			(net 1 "GND")
			(pinfunction "2")
			(pintype "passive")
		)
		(pad "2" smd rect
			(at 4.849 -10.221 270)
			(size 1.1 6.45)
			(layers "F.Cu" "F.Mask" "F.Paste")
			(net 1 "GND")
			(pinfunction "2")
			(pintype "passive")
		)
	)
	(footprint "antmicro-footprints:TP_SMD_0.75mm"
		(layer "F.Cu")
		(at 120.53 113.0992 180)
		(property "Reference" "TP19"
			(at 2.75 -0.3408 0)
			(layer "F.SilkS")
			(effects
				(font
					(size 0.65 0.65)
					(thickness 0.15)
				)
				(justify right bottom)
			)
		)
		(property "Value" "TP_0.75mm_SMD"
			(at 0 1.2 0)
			(layer "F.Fab")
			(hide yes)
			(effects
				(font
					(size 0.7 0.7)
					(thickness 0.15)
				)
				(justify right bottom)
			)
		)
		(property "Description" "SMT test point"
			(at 0 0 180)
			(layer "F.Fab")
			(hide yes)
			(effects
				(font
					(size 1.27 1.27)
					(thickness 0.15)
				)
			)
		)
		(property "Author" "Antmicro"
			(at 241.06 226.1984 0)
			(layer "F.Fab")
			(hide yes)
			(effects
				(font
					(size 1 1)
					(thickness 0.15)
				)
			)
		)
		(property "License" "Apache-2.0"
			(at 241.06 226.1984 0)
			(layer "F.Fab")
			(hide yes)
			(effects
				(font
					(size 1 1)
					(thickness 0.15)
				)
			)
		)
		(property "MPN" ""
			(at 241.06 226.1984 0)
			(layer "F.Fab")
			(hide yes)
			(effects
				(font
					(size 1 1)
					(thickness 0.15)
				)
			)
		)
		(property "Manufacturer" ""
			(at 241.06 226.1984 0)
			(layer "F.Fab")
			(hide yes)
			(effects
				(font
					(size 1 1)
					(thickness 0.15)
				)
			)
		)
		(sheetname "/FPGA/")
		(sheetfile "fpga.kicad_sch")
		(attr exclude_from_pos_files)
		(fp_circle
			(center 0 0)
			(end 0.475 0)
			(stroke
				(width 0.05)
				(type default)
			)
			(fill no)
			(layer "F.CrtYd")
		)
		(fp_text user "License: Apache-2.0"
			(at -0.4 5.101 180)
			(layer "F.Fab")
			(effects
				(font
					(size 0.7 0.7)
					(thickness 0.15)
				)
				(justify left bottom)
			)
		)
		(fp_text user "Author: Antmicro"
			(at -0.4 3.901 180)
			(layer "F.Fab")
			(effects
				(font
					(size 0.7 0.7)
					(thickness 0.15)
				)
				(justify left bottom)
			)
		)
		(fp_text user "${REFERENCE}"
			(at -0.4 2.7 180)
			(layer "F.Fab")
			(effects
				(font
					(size 0.7 0.7)
					(thickness 0.15)
				)
				(justify left bottom)
			)
		)
		(pad "1" smd circle
			(at 0 0 180)
			(size 0.75 0.75)
			(layers "F.Cu" "F.Mask")
			(net 40 "/FPGA/DONE")
			(pinfunction "1")
			(pintype "passive")
		)
	)
	(footprint "antmicro-footprints:SOT-23-3"
		(layer "F.Cu")
		(at 125.03 113.65 -90)
		(property "Reference" "Q6"
			(at 0.89 -1.5 90)
			(layer "F.SilkS")
			(effects
				(font
					(size 0.65 0.65)
					(thickness 0.15)
				)
				(justify right bottom)
			)
		)
		(property "Value" "2N7002_SOT-23-3"
			(at -1.9 2.7 90)
			(layer "F.Fab")
			(hide yes)
			(effects
				(font
					(size 0.7 0.7)
					(thickness 0.15)
				)
				(justify right bottom)
			)
		)
		(property "Datasheet" "https://www.onsemi.com/pub/Collateral/NDS7002A-D.PDF"
			(at 0 0 270)
			(layer "F.Fab")
			(hide yes)
			(effects
				(font
					(size 1.27 1.27)
					(thickness 0.15)
				)
			)
		)
		(property "Description" "Power MOSFET, N Channel, 60 V, 115 mA, 1.2 ohm, SOT-23, Surface Mount"
			(at 0 0 270)
			(layer "F.Fab")
			(hide yes)
			(effects
				(font
					(size 1.27 1.27)
					(thickness 0.15)
				)
			)
		)
		(property "Author" "Antmicro"
			(at 11.38 238.68 0)
			(layer "F.Fab")
			(hide yes)
			(effects
				(font
					(size 1 1)
					(thickness 0.15)
				)
			)
		)
		(property "License" "Apache-2.0"
			(at 11.38 238.68 0)
			(layer "F.Fab")
			(hide yes)
			(effects
				(font
					(size 1 1)
					(thickness 0.15)
				)
			)
		)
		(property "MPN" "2N7002"
			(at 11.38 238.68 0)
			(layer "F.Fab")
			(hide yes)
			(effects
				(font
					(size 1 1)
					(thickness 0.15)
				)
			)
		)
		(property "Manufacturer" "ON Semiconductor"
			(at 11.38 238.68 0)
			(layer "F.Fab")
			(hide yes)
			(effects
				(font
					(size 1 1)
					(thickness 0.15)
				)
			)
		)
		(sheetname "/FPGA/")
		(sheetfile "fpga.kicad_sch")
		(attr smd)
		(fp_line
			(start -0.7 1.5)
			(end -0.7 1.35)
			(stroke
				(width 0.15)
				(type solid)
			)
			(layer "F.SilkS")
		)
		(fp_line
			(start 0.7 1.5)
			(end -0.7 1.5)
			(stroke
				(width 0.15)
				(type solid)
			)
			(layer "F.SilkS")
		)
		(fp_line
			(start 0.7 0.4)
			(end 0.7 1.5)
			(stroke
				(width 0.15)
				(type solid)
			)
			(layer "F.SilkS")
		)
		(fp_line
			(start 0.7 -0.4)
			(end 0.7 -1.5)
			(stroke
				(width 0.15)
				(type solid)
			)
			(layer "F.SilkS")
		)
		(fp_line
			(start -1.45 -1.35)
			(end -0.85 -1.35)
			(stroke
				(width 0.15)
				(type solid)
			)
			(layer "F.SilkS")
		)
		(fp_line
			(start -0.85 -1.35)
			(end -0.7 -1.5)
			(stroke
				(width 0.15)
				(type solid)
			)
			(layer "F.SilkS")
		)
		(fp_line
			(start 0.7 -1.5)
			(end -0.7 -1.5)
			(stroke
				(width 0.15)
				(type solid)
			)
			(layer "F.SilkS")
		)
		(fp_line
			(start -0.85 1.65)
			(end -0.85 1.4)
			(stroke
				(width 0.05)
				(type solid)
			)
			(layer "F.CrtYd")
		)
		(fp_line
			(start 0.85 1.65)
			(end -0.85 1.65)
			(stroke
				(width 0.05)
				(type solid)
			)
			(layer "F.CrtYd")
		)
		(fp_line
			(start -1.75 1.4)
			(end -1.75 0.5)
			(stroke
				(width 0.05)
				(type solid)
			)
			(layer "F.CrtYd")
		)
		(fp_line
			(start -0.85 1.4)
			(end -1.75 1.4)
			(stroke
				(width 0.05)
				(type solid)
			)
			(layer "F.CrtYd")
		)
		(fp_line
			(start -1.75 0.5)
			(end -0.85 0.5)
			(stroke
				(width 0.05)
				(type solid)
			)
			(layer "F.CrtYd")
		)
		(fp_line
			(start -0.85 0.5)
			(end -0.85 -0.5)
			(stroke
				(width 0.05)
				(type solid)
			)
			(layer "F.CrtYd")
		)
		(fp_line
			(start 0.85 0.45)
			(end 0.85 1.65)
			(stroke
				(width 0.05)
				(type solid)
			)
			(layer "F.CrtYd")
		)
		(fp_line
			(start 1.75 0.45)
			(end 0.85 0.45)
			(stroke
				(width 0.05)
				(type solid)
			)
			(layer "F.CrtYd")
		)
		(fp_line
			(start 0.825 -0.45)
			(end 1.75 -0.45)
			(stroke
				(width 0.05)
				(type solid)
			)
			(layer "F.CrtYd")
		)
		(fp_line
			(start 1.75 -0.45)
			(end 1.75 0.45)
			(stroke
				(width 0.05)
				(type solid)
			)
			(layer "F.CrtYd")
		)
		(fp_line
			(start -1.75 -0.5)
			(end -1.75 -1.4)
			(stroke
				(width 0.05)
				(type solid)
			)
			(layer "F.CrtYd")
		)
		(fp_line
			(start -0.85 -0.5)
			(end -1.75 -0.5)
			(stroke
				(width 0.05)
				(type solid)
			)
			(layer "F.CrtYd")
		)
		(fp_line
			(start -0.9 -1.4)
			(end -1.75 -1.4)
			(stroke
				(width 0.05)
				(type solid)
			)
			(layer "F.CrtYd")
		)
		(fp_line
			(start -0.9 -1.6)
			(end -0.9 -1.4)
			(stroke
				(width 0.05)
				(type solid)
			)
			(layer "F.CrtYd")
		)
		(fp_line
			(start -0.9 -1.6)
			(end 0.825 -1.6)
			(stroke
				(width 0.05)
				(type solid)
			)
			(layer "F.CrtYd")
		)
		(fp_line
			(start 0.825 -1.6)
			(end 0.825 -0.45)
			(stroke
				(width 0.05)
				(type solid)
			)
			(layer "F.CrtYd")
		)
		(fp_line
			(start -0.712 1.519)
			(end 0.688 1.519)
			(stroke
				(width 0.15)
				(type solid)
			)
			(layer "F.Fab")
		)
		(fp_line
			(start 0.688 1.519)
			(end 0.688 -1.52)
			(stroke
				(width 0.15)
				(type solid)
			)
			(layer "F.Fab")
		)
		(fp_line
			(start -0.712 -1.325)
			(end -0.712 1.523)
			(stroke
				(width 0.15)
				(type solid)
			)
			(layer "F.Fab")
		)
		(fp_line
			(start -0.437 -1.526)
			(end -0.712 -1.325)
			(stroke
				(width 0.15)
				(type solid)
			)
			(layer "F.Fab")
		)
		(fp_line
			(start -0.437 -1.526)
			(end 0.688 -1.526)
			(stroke
				(width 0.15)
				(type solid)
			)
			(layer "F.Fab")
		)
		(pad "1" smd roundrect
			(at -1.1 -0.951 270)
			(size 1 0.6)
			(layers "F.Cu" "F.Mask" "F.Paste")
			(roundrect_rratio 0.15)
			(net 261 "Net-(Q6-G)")
			(pinfunction "G")
			(pintype "input")
		)
		(pad "2" smd roundrect
			(at -1.1 0.949 270)
			(size 1 0.6)
			(layers "F.Cu" "F.Mask" "F.Paste")
			(roundrect_rratio 0.15)
			(net 1 "GND")
			(pinfunction "S")
			(pintype "passive")
		)
		(pad "3" smd roundrect
			(at 1.1 -0.0005 270)
			(size 1 0.6)
			(layers "F.Cu" "F.Mask" "F.Paste")
			(roundrect_rratio 0.15)
			(net 66 "Net-(D5-C)")
			(pinfunction "D")
			(pintype "passive")
		)
	)
	(footprint "antmicro-footprints:LED_0603_1608Metric_G"
		(layer "F.Cu")
		(at 172.69 77.73 180)
		(descr "LED SMD 0603 Green")
		(tags "LED SMD 0603 Green")
		(property "Reference" "D11"
			(at -1.04 1.66 0)
			(layer "F.SilkS")
			(effects
				(font
					(size 0.65 0.65)
					(thickness 0.15)
				)
				(justify right top)
			)
		)
		(property "Value" "LED_G_0603_LTST-C190GKT"
			(at 0 1.6 0)
			(layer "F.Fab")
			(hide yes)
			(effects
				(font
					(size 0.7 0.7)
					(thickness 0.15)
				)
				(justify right top)
			)
		)
		(property "Datasheet" "https://media.digikey.com/pdf/Data%20Sheets/Lite-On%20PDFs/LTST-C190GKT.pdf"
			(at 0 0 0)
			(layer "F.Fab")
			(hide yes)
			(effects
				(font
					(size 1.27 1.27)
					(thickness 0.15)
				)
			)
		)
		(property "Description" "LED, Green, SMD, 0603, 20 mA, 2.1 V, 569 nm"
			(at 0 0 0)
			(layer "F.Fab")
			(hide yes)
			(effects
				(font
					(size 1.27 1.27)
					(thickness 0.15)
				)
			)
		)
		(property "Author" "Antmicro"
			(at 0 0 0)
			(layer "F.Fab")
			(hide yes)
			(effects
				(font
					(size 1 1)
					(thickness 0.15)
				)
			)
		)
		(property "License" "Apache-2.0"
			(at 0 0 0)
			(layer "F.Fab")
			(hide yes)
			(effects
				(font
					(size 1 1)
					(thickness 0.15)
				)
			)
		)
		(property "MPN" "LTST-C190GKT"
			(at 0 0 0)
			(layer "F.Fab")
			(hide yes)
			(effects
				(font
					(size 1 1)
					(thickness 0.15)
				)
			)
		)
		(property "Manufacturer" "Lite-On"
			(at 0 0 0)
			(layer "F.Fab")
			(hide yes)
			(effects
				(font
					(size 1 1)
					(thickness 0.15)
				)
			)
		)
		(property "Color" "Green"
			(at 0 0 180)
			(unlocked yes)
			(layer "F.Fab")
			(hide yes)
			(effects
				(font
					(size 1 1)
					(thickness 0.15)
				)
			)
		)
		(sheetname "/Peripherals/")
		(sheetfile "peripherals.kicad_sch")
		(attr smd)
		(fp_line
			(start 0.22 0.35)
			(end -0.22 0.35)
			(stroke
				(width 0.15)
				(type solid)
			)
			(layer "F.SilkS")
		)
		(fp_line
			(start 0.22 -0.35)
			(end -0.22 -0.35)
			(stroke
				(width 0.15)
				(type solid)
			)
			(layer "F.SilkS")
		)
		(fp_line
			(start 0.105328 0.201008)
			(end 0.105328 -0.198992)
			(stroke
				(width 0.1)
				(type solid)
			)
			(layer "F.SilkS")
		)
		(fp_line
			(start 0.105328 0.201008)
			(end -0.094672 0.001008)
			(stroke
				(width 0.1)
				(type solid)
			)
			(layer "F.SilkS")
		)
		(fp_line
			(start 0.105328 0.001008)
			(end 0.24 0.001)
			(stroke
				(width 0.1)
				(type solid)
			)
			(layer "F.SilkS")
		)
		(fp_line
			(start -0.094672 0.201008)
			(end -0.094672 -0.198992)
			(stroke
				(width 0.1)
				(type solid)
			)
			(layer "F.SilkS")
		)
		(fp_line
			(start -0.094672 0.001008)
			(end 0.105328 -0.198992)
			(stroke
				(width 0.1)
				(type solid)
			)
			(layer "F.SilkS")
		)
		(fp_line
			(start -0.094672 0.001008)
			(end -0.24 0.001008)
			(stroke
				(width 0.1)
				(type solid)
			)
			(layer "F.SilkS")
		)
		(fp_line
			(start -1.18 -0.319)
			(end -1.18 0.321)
			(stroke
				(width 0.15)
				(type solid)
			)
			(layer "F.SilkS")
		)
		(fp_rect
			(start 1.25 0.65)
			(end -1.25 -0.65)
			(stroke
				(width 0.05)
				(type solid)
			)
			(fill no)
			(layer "F.CrtYd")
		)
		(fp_line
			(start 0.599 0)
			(end 0.201 0)
			(stroke
				(width 0.15)
				(type solid)
			)
			(layer "F.Fab")
		)
		(fp_line
			(start 0.201 0.2)
			(end 0.201 0)
			(stroke
				(width 0.15)
				(type solid)
			)
			(layer "F.Fab")
		)
		(fp_line
			(start 0.201 0)
			(end 0.201 -0.202)
			(stroke
				(width 0.15)
				(type solid)
			)
			(layer "F.Fab")
		)
		(fp_line
			(start 0.201 -0.202)
			(end -0.101 0)
			(stroke
				(width 0.15)
				(type solid)
			)
			(layer "F.Fab")
		)
		(fp_line
			(start -0.101 0)
			(end 0.201 0.2)
			(stroke
				(width 0.15)
				(type solid)
			)
			(layer "F.Fab")
		)
		(fp_line
			(start -0.199 0.2)
			(end -0.199 0.1)
			(stroke
				(width 0.15)
				(type solid)
			)
			(layer "F.Fab")
		)
		(fp_line
			(start -0.199 0)
			(end -0.597 0)
			(stroke
				(width 0.15)
				(type solid)
			)
			(layer "F.Fab")
		)
		(fp_line
			(start -0.199 -0.202)
			(end -0.199 0.1)
			(stroke
				(width 0.15)
				(type solid)
			)
			(layer "F.Fab")
		)
		(fp_rect
			(start 0.848 0.4)
			(end -0.85 -0.402)
			(stroke
				(width 0.15)
				(type solid)
			)
			(fill no)
			(layer "F.Fab")
		)
		(fp_text user "${REFERENCE}"
			(at -1.4224 5.999 0)
			(layer "F.Fab")
			(effects
				(font
					(size 0.7 0.7)
					(thickness 0.15)
				)
				(justify right top)
			)
		)
		(fp_text user "Author: Antmicro"
			(at -1.4224 4.799 0)
			(layer "F.Fab")
			(effects
				(font
					(size 0.7 0.7)
					(thickness 0.15)
				)
				(justify right top)
			)
		)
		(fp_text user "License: Apache-2.0"
			(at -1.4224 3.599 0)
			(layer "F.Fab")
			(effects
				(font
					(size 0.7 0.7)
					(thickness 0.15)
				)
				(justify right top)
			)
		)
		(pad "1" smd roundrect
			(at -0.7 0)
			(size 0.8 1)
			(layers "F.Cu" "F.Mask" "F.Paste")
			(roundrect_rratio 0.2)
			(net 1 "GND")
			(pinfunction "C")
			(pintype "passive")
		)
		(pad "2" smd roundrect
			(at 0.7 0)
			(size 0.8 1)
			(layers "F.Cu" "F.Mask" "F.Paste")
			(roundrect_rratio 0.2)
			(net 257 "Net-(D11-A)")
			(pinfunction "A")
			(pintype "passive")
		)
	)
	(footprint "antmicro-footprints:SOT-23-6"
		(layer "F.Cu")
		(at 162.53 86.65 -90)
		(property "Reference" "U14"
			(at -1.75 -2 270)
			(layer "F.SilkS")
			(effects
				(font
					(size 0.65 0.65)
					(thickness 0.15)
				)
				(justify left bottom)
			)
		)
		(property "Value" "DIO7553ST6"
			(at -1.75 2.75 270)
			(layer "F.Fab")
			(hide yes)
			(effects
				(font
					(size 0.7 0.7)
					(thickness 0.15)
				)
				(justify left bottom)
			)
		)
		(property "Datasheet" "https://www.mouser.com/datasheet/2/802/7e5c577022fb784effcb3cdb25b437c0-1815562.pdf"
			(at 0 0 270)
			(layer "F.Fab")
			(hide yes)
			(effects
				(font
					(size 1.27 1.27)
					(thickness 0.15)
				)
			)
		)
		(property "Description" "Power switch"
			(at 0 0 270)
			(layer "F.Fab")
			(hide yes)
			(effects
				(font
					(size 1.27 1.27)
					(thickness 0.15)
				)
			)
		)
		(property "Author" "Antmicro"
			(at 75.88 249.18 0)
			(layer "F.Fab")
			(hide yes)
			(effects
				(font
					(size 1 1)
					(thickness 0.15)
				)
			)
		)
		(property "License" "Apache-2.0"
			(at 75.88 249.18 0)
			(layer "F.Fab")
			(hide yes)
			(effects
				(font
					(size 1 1)
					(thickness 0.15)
				)
			)
		)
		(property "MPN" "DIO7553ST6"
			(at 75.88 249.18 0)
			(layer "F.Fab")
			(hide yes)
			(effects
				(font
					(size 1 1)
					(thickness 0.15)
				)
			)
		)
		(property "Manufacturer" "DIOO Microcircuits"
			(at 75.88 249.18 0)
			(layer "F.Fab")
			(hide yes)
			(effects
				(font
					(size 1 1)
					(thickness 0.15)
				)
			)
		)
		(sheetname "/Peripherals/")
		(sheetfile "peripherals.kicad_sch")
		(attr smd)
		(fp_line
			(start -1.45 0.643)
			(end -1.45 0.343)
			(stroke
				(width 0.12)
				(type solid)
			)
			(layer "F.SilkS")
		)
		(fp_line
			(start 1.3 0.643)
			(end 1.45 0.643)
			(stroke
				(width 0.12)
				(type solid)
			)
			(layer "F.SilkS")
		)
		(fp_line
			(start 1.45 0.643)
			(end 1.45 0.343)
			(stroke
				(width 0.12)
				(type solid)
			)
			(layer "F.SilkS")
		)
		(fp_line
			(start -1.45 -0.757)
			(end -1.45 -0.457)
			(stroke
				(width 0.12)
				(type solid)
			)
			(layer "F.SilkS")
		)
		(fp_line
			(start -1.3 -0.757)
			(end -1.45 -0.757)
			(stroke
				(width 0.12)
				(type solid)
			)
			(layer "F.SilkS")
		)
		(fp_line
			(start 1.3 -0.757)
			(end 1.45 -0.757)
			(stroke
				(width 0.12)
				(type solid)
			)
			(layer "F.SilkS")
		)
		(fp_line
			(start 1.45 -0.757)
			(end 1.45 -0.457)
			(stroke
				(width 0.12)
				(type solid)
			)
			(layer "F.SilkS")
		)
		(fp_rect
			(start -1.55 -1.85)
			(end 1.55 1.75)
			(stroke
				(width 0.05)
				(type solid)
			)
			(fill no)
			(layer "F.CrtYd")
		)
		(fp_line
			(start -1.5 0.643)
			(end -1.5 -0.757)
			(stroke
				(width 0.1)
				(type solid)
			)
			(layer "F.Fab")
		)
		(fp_line
			(start 1.5 0.643)
			(end -1.5 0.643)
			(stroke
				(width 0.1)
				(type solid)
			)
			(layer "F.Fab")
		)
		(fp_line
			(start -1.5 -0.757)
			(end 1.5 -0.757)
			(stroke
				(width 0.1)
				(type solid)
			)
			(layer "F.Fab")
		)
		(fp_line
			(start 1.5 -0.757)
			(end 1.5 0.643)
			(stroke
				(width 0.1)
				(type solid)
			)
			(layer "F.Fab")
		)
		(fp_text user "."
			(at -1.76 2.05 90)
			(layer "F.SilkS")
			(effects
				(font
					(size 1 1)
					(thickness 0.15)
				)
			)
		)
		(fp_text user "License: Apache-2.0"
			(at -1.75 6.5 270)
			(layer "F.Fab")
			(effects
				(font
					(size 0.7 0.7)
					(thickness 0.15)
				)
				(justify left bottom)
			)
		)
		(fp_text user "${REFERENCE}"
			(at -1.75 4 270)
			(layer "F.Fab")
			(effects
				(font
					(size 0.7 0.7)
					(thickness 0.15)
				)
				(justify left bottom)
			)
		)
		(fp_text user "Author: Antmicro"
			(at -1.829 5.25 270)
			(layer "F.Fab")
			(effects
				(font
					(size 0.7 0.7)
					(thickness 0.15)
				)
				(justify left bottom)
			)
		)
		(pad "1" smd roundrect
			(at -0.954 1.1 270)
			(size 0.55 1)
			(layers "F.Cu" "F.Mask" "F.Paste")
			(roundrect_rratio 0.15)
			(net 14 "+5V")
			(pinfunction "IN")
			(pintype "power_in")
		)
		(pad "2" smd roundrect
			(at -0.003 1.1 270)
			(size 0.55 1)
			(layers "F.Cu" "F.Mask" "F.Paste")
			(roundrect_rratio 0.15)
			(net 1 "GND")
			(pinfunction "GND")
			(pintype "power_in")
		)
		(pad "3" smd roundrect
			(at 0.947 1.1 270)
			(size 0.55 1)
			(layers "F.Cu" "F.Mask" "F.Paste")
			(roundrect_rratio 0.15)
			(net 307 "/Peripherals/FFC1_PEN")
			(pinfunction "EN")
			(pintype "input")
		)
		(pad "4" smd roundrect
			(at 0.947 -1.214 270)
			(size 0.55 1)
			(layers "F.Cu" "F.Mask" "F.Paste")
			(roundrect_rratio 0.15)
			(net 351 "Net-(U13-~{FAULT})")
			(pinfunction "~{FAULT}")
			(pintype "output")
		)
		(pad "5" smd roundrect
			(at -0.003 -1.214 270)
			(size 0.55 1)
			(layers "F.Cu" "F.Mask" "F.Paste")
			(roundrect_rratio 0.15)
			(net 354 "Net-(U14-ILIM)")
			(pinfunction "ILIM")
			(pintype "passive")
		)
		(pad "6" smd roundrect
			(at -0.954 -1.214 270)
			(size 0.55 1)
			(layers "F.Cu" "F.Mask" "F.Paste")
			(roundrect_rratio 0.15)
			(net 16 "/Peripherals/FFC1_5V")
			(pinfunction "OUT")
			(pintype "power_out")
		)
	)
	(footprint "antmicro-footprints:R_0402_1005Metric"
		(layer "F.Cu")
		(at 83.7 109.65 -90)
		(descr "Resistor SMD 0402")
		(tags "resistor SMD 0402")
		(property "Reference" "R62"
			(at -9.21 -3.43 90)
			(layer "F.SilkS")
			(effects
				(font
					(size 0.65 0.65)
					(thickness 0.15)
				)
				(justify right bottom)
			)
		)
		(property "Value" "R_75R_0402"
			(at 0 1.4 90)
			(layer "F.Fab")
			(hide yes)
			(effects
				(font
					(size 0.7 0.7)
					(thickness 0.15)
				)
				(justify right bottom)
			)
		)
		(property "Datasheet" "https://www.bourns.com/docs/product-datasheets/cr.pdf"
			(at 0 0 270)
			(layer "F.Fab")
			(hide yes)
			(effects
				(font
					(size 1.27 1.27)
					(thickness 0.15)
				)
			)
		)
		(property "Description" "SMD Chip Resistor, 75 ohm, ± 1%, 62.5 mW, 0402 [1005 Metric], Thick Film, General Purpose"
			(at 0 0 270)
			(layer "F.Fab")
			(hide yes)
			(effects
				(font
					(size 1.27 1.27)
					(thickness 0.15)
				)
			)
		)
		(property "Author" "Antmicro"
			(at -25.95 193.35 0)
			(layer "F.Fab")
			(hide yes)
			(effects
				(font
					(size 1 1)
					(thickness 0.15)
				)
			)
		)
		(property "License" "Apache-2.0"
			(at -25.95 193.35 0)
			(layer "F.Fab")
			(hide yes)
			(effects
				(font
					(size 1 1)
					(thickness 0.15)
				)
			)
		)
		(property "MPN" "CR0402-FX-75R0GLF"
			(at -25.95 193.35 0)
			(layer "F.Fab")
			(hide yes)
			(effects
				(font
					(size 1 1)
					(thickness 0.15)
				)
			)
		)
		(property "Manufacturer" "Bourns"
			(at -25.95 193.35 0)
			(layer "F.Fab")
			(hide yes)
			(effects
				(font
					(size 1 1)
					(thickness 0.15)
				)
			)
		)
		(property "Tolerance" "1%"
			(at -25.95 193.35 0)
			(layer "F.Fab")
			(hide yes)
			(effects
				(font
					(size 1 1)
					(thickness 0.15)
				)
			)
		)
		(property "Val" "75R"
			(at -25.95 193.35 0)
			(layer "F.Fab")
			(hide yes)
			(effects
				(font
					(size 1 1)
					(thickness 0.15)
				)
			)
		)
		(sheetname "/SDI/")
		(sheetfile "sdi.kicad_sch")
		(attr smd)
		(fp_rect
			(start -0.925 -0.47)
			(end 0.925 0.47)
			(stroke
				(width 0.05)
				(type default)
			)
			(fill no)
			(layer "F.CrtYd")
		)
		(fp_rect
			(start -0.5 -0.25)
			(end 0.5 0.25)
			(stroke
				(width 0.15)
				(type solid)
			)
			(fill no)
			(layer "F.Fab")
		)
		(fp_text user "Author: Antmicro"
			(at -0.95 4.169 270)
			(layer "F.Fab")
			(effects
				(font
					(size 0.7 0.7)
					(thickness 0.15)
				)
				(justify left bottom)
			)
		)
		(fp_text user "${REFERENCE}"
			(at -0.95 3.168 270)
			(layer "F.Fab")
			(effects
				(font
					(size 0.7 0.7)
					(thickness 0.15)
				)
				(justify left bottom)
			)
		)
		(fp_text user "License: Apache-2.0"
			(at -0.95 5.169 270)
			(layer "F.Fab")
			(effects
				(font
					(size 0.7 0.7)
					(thickness 0.15)
				)
				(justify left bottom)
			)
		)
		(pad "1" smd roundrect
			(at -0.48 0 270)
			(size 0.59 0.64)
			(layers "F.Cu" "F.Mask" "F.Paste")
			(roundrect_rratio 0.25)
			(net 250 "Net-(C77-Pad2)")
			(pintype "passive")
		)
		(pad "2" smd roundrect
			(at 0.48 0 270)
			(size 0.59 0.64)
			(layers "F.Cu" "F.Mask" "F.Paste")
			(roundrect_rratio 0.25)
			(net 1 "GND")
			(pintype "passive")
		)
	)
	(footprint "antmicro-footprints:C_0603_1608Metric"
		(layer "F.Cu")
		(at 151.48 64.75 90)
		(descr "Capacitor SMD 0603")
		(tags "capacitor 0603")
		(property "Reference" "C124"
			(at -1.24 -1.07 90)
			(layer "F.SilkS")
			(effects
				(font
					(size 0.65 0.65)
					(thickness 0.15)
				)
				(justify left bottom)
			)
		)
		(property "Value" "C_1u_0603"
			(at 0 1.6 90)
			(layer "F.Fab")
			(hide yes)
			(effects
				(font
					(size 0.7 0.7)
					(thickness 0.15)
				)
				(justify left bottom)
			)
		)
		(property "Datasheet" "https://spicat.kyocera-avx.com/product/mlcc/chartview/0603YD105KAT2A/"
			(at 0 0 90)
			(layer "F.Fab")
			(hide yes)
			(effects
				(font
					(size 1.27 1.27)
					(thickness 0.15)
				)
			)
		)
		(property "Description" "SMD Multilayer Ceramic Capacitor, 1 µF, 16 V, 0603 [1608 Metric], ± 10%, X5R, AVX 0603 MLCC"
			(at 0 0 90)
			(layer "F.Fab")
			(hide yes)
			(effects
				(font
					(size 1.27 1.27)
					(thickness 0.15)
				)
			)
		)
		(property "Author" "Antmicro"
			(at 216.2 -86.7 0)
			(layer "F.Fab")
			(hide yes)
			(effects
				(font
					(size 1 1)
					(thickness 0.15)
				)
			)
		)
		(property "Dielectric" ""
			(at 216.2 -86.7 0)
			(layer "F.Fab")
			(hide yes)
			(effects
				(font
					(size 1 1)
					(thickness 0.15)
				)
			)
		)
		(property "License" "Apache-2.0"
			(at 216.2 -86.7 0)
			(layer "F.Fab")
			(hide yes)
			(effects
				(font
					(size 1 1)
					(thickness 0.15)
				)
			)
		)
		(property "MPN" "0603YD105KAT2A"
			(at 216.2 -86.7 0)
			(layer "F.Fab")
			(hide yes)
			(effects
				(font
					(size 1 1)
					(thickness 0.15)
				)
			)
		)
		(property "Manufacturer" "KYOCERA AVX"
			(at 216.2 -86.7 0)
			(layer "F.Fab")
			(hide yes)
			(effects
				(font
					(size 1 1)
					(thickness 0.15)
				)
			)
		)
		(property "Val" "1u"
			(at 216.2 -86.7 0)
			(layer "F.Fab")
			(hide yes)
			(effects
				(font
					(size 1 1)
					(thickness 0.15)
				)
			)
		)
		(property "Voltage" ""
			(at 216.2 -86.7 0)
			(layer "F.Fab")
			(hide yes)
			(effects
				(font
					(size 1 1)
					(thickness 0.15)
				)
			)
		)
		(sheetname "/Peripherals/")
		(sheetfile "peripherals.kicad_sch")
		(attr smd)
		(fp_line
			(start -0.15 -0.4)
			(end 0.15 -0.4)
			(stroke
				(width 0.15)
				(type solid)
			)
			(layer "F.SilkS")
		)
		(fp_line
			(start -0.15 0.4)
			(end 0.15 0.4)
			(stroke
				(width 0.15)
				(type solid)
			)
			(layer "F.SilkS")
		)
		(fp_rect
			(start -1.25 -0.65)
			(end 1.25 0.65)
			(stroke
				(width 0.05)
				(type solid)
			)
			(fill no)
			(layer "F.CrtYd")
		)
		(fp_rect
			(start -0.8 -0.4)
			(end 0.8 0.4)
			(stroke
				(width 0.15)
				(type solid)
			)
			(fill no)
			(layer "F.Fab")
		)
		(fp_text user "Author: Antmicro"
			(at -1.682 4.894 90)
			(layer "F.Fab")
			(effects
				(font
					(size 0.7 0.7)
					(thickness 0.15)
				)
				(justify left bottom)
			)
		)
		(fp_text user "${REFERENCE}"
			(at -1.682 3.895 90)
			(layer "F.Fab")
			(effects
				(font
					(size 0.7 0.7)
					(thickness 0.15)
				)
				(justify left bottom)
			)
		)
		(fp_text user "License: Apache-2.0"
			(at -1.682 5.895 90)
			(layer "F.Fab")
			(effects
				(font
					(size 0.7 0.7)
					(thickness 0.15)
				)
				(justify left bottom)
			)
		)
		(pad "1" smd roundrect
			(at -0.7 0 90)
			(size 0.8 1)
			(layers "F.Cu" "F.Mask" "F.Paste")
			(roundrect_rratio 0.2)
			(net 1 "GND")
			(pintype "passive")
		)
		(pad "2" smd roundrect
			(at 0.7 0 90)
			(size 0.8 1)
			(layers "F.Cu" "F.Mask" "F.Paste")
			(roundrect_rratio 0.2)
			(net 325 "USB_POWER_IN")
			(pintype "passive")
		)
	)
	(footprint "antmicro-footprints:R_0402_1005Metric"
		(layer "F.Cu")
		(at 144.28 77.14 180)
		(descr "Resistor SMD 0402")
		(tags "resistor SMD 0402")
		(property "Reference" "R23"
			(at 3.05 -0.39 180)
			(layer "F.SilkS")
			(effects
				(font
					(size 0.65 0.65)
					(thickness 0.15)
				)
				(justify left bottom)
			)
		)
		(property "Value" "R_10k_0402"
			(at 0 1.4 180)
			(layer "F.Fab")
			(hide yes)
			(effects
				(font
					(size 0.7 0.7)
					(thickness 0.15)
				)
				(justify left bottom)
			)
		)
		(property "Datasheet" "https://www.bourns.com/docs/product-datasheets/cr.pdf"
			(at 0 0 180)
			(layer "F.Fab")
			(hide yes)
			(effects
				(font
					(size 1.27 1.27)
					(thickness 0.15)
				)
			)
		)
		(property "Description" "SMD Chip Resistor, 10 kohm, ± 1%, 62.5 mW, 0402 [1005 Metric], Thick Film, General Purpose"
			(at 0 0 180)
			(layer "F.Fab")
			(hide yes)
			(effects
				(font
					(size 1.27 1.27)
					(thickness 0.15)
				)
			)
		)
		(property "Author" "Antmicro"
			(at 288.56 154.1 0)
			(layer "F.Fab")
			(hide yes)
			(effects
				(font
					(size 1 1)
					(thickness 0.15)
				)
			)
		)
		(property "License" "Apache-2.0"
			(at 288.56 154.1 0)
			(layer "F.Fab")
			(hide yes)
			(effects
				(font
					(size 1 1)
					(thickness 0.15)
				)
			)
		)
		(property "MPN" "CR0402-FX-1002GLF"
			(at 288.56 154.1 0)
			(layer "F.Fab")
			(hide yes)
			(effects
				(font
					(size 1 1)
					(thickness 0.15)
				)
			)
		)
		(property "Manufacturer" "Bourns"
			(at 288.56 154.1 0)
			(layer "F.Fab")
			(hide yes)
			(effects
				(font
					(size 1 1)
					(thickness 0.15)
				)
			)
		)
		(property "Tolerance" "1%"
			(at 288.56 154.1 0)
			(layer "F.Fab")
			(hide yes)
			(effects
				(font
					(size 1 1)
					(thickness 0.15)
				)
			)
		)
		(property "Val" "10k"
			(at 288.56 154.1 0)
			(layer "F.Fab")
			(hide yes)
			(effects
				(font
					(size 1 1)
					(thickness 0.15)
				)
			)
		)
		(sheetname "/Power Supply/")
		(sheetfile "supply.kicad_sch")
		(attr smd)
		(fp_rect
			(start -0.925 -0.47)
			(end 0.925 0.47)
			(stroke
				(width 0.05)
				(type default)
			)
			(fill no)
			(layer "F.CrtYd")
		)
		(fp_rect
			(start -0.5 -0.25)
			(end 0.5 0.25)
			(stroke
				(width 0.15)
				(type solid)
			)
			(fill no)
			(layer "F.Fab")
		)
		(fp_text user "License: Apache-2.0"
			(at -0.95 5.169 180)
			(layer "F.Fab")
			(effects
				(font
					(size 0.7 0.7)
					(thickness 0.15)
				)
				(justify left bottom)
			)
		)
		(fp_text user "Author: Antmicro"
			(at -0.95 4.169 180)
			(layer "F.Fab")
			(effects
				(font
					(size 0.7 0.7)
					(thickness 0.15)
				)
				(justify left bottom)
			)
		)
		(fp_text user "${REFERENCE}"
			(at -0.95 3.168 180)
			(layer "F.Fab")
			(effects
				(font
					(size 0.7 0.7)
					(thickness 0.15)
				)
				(justify left bottom)
			)
		)
		(pad "1" smd roundrect
			(at -0.48 0 180)
			(size 0.59 0.64)
			(layers "F.Cu" "F.Mask" "F.Paste")
			(roundrect_rratio 0.25)
			(net 1 "GND")
			(pintype "passive")
		)
		(pad "2" smd roundrect
			(at 0.48 0 180)
			(size 0.59 0.64)
			(layers "F.Cu" "F.Mask" "F.Paste")
			(roundrect_rratio 0.25)
			(net 267 "Net-(U5-FB)")
			(pintype "passive")
		)
	)
	(footprint "antmicro-footprints:R_0402_1005Metric"
		(layer "F.Cu")
		(at 122.03 114.15)
		(descr "Resistor SMD 0402")
		(tags "resistor SMD 0402")
		(property "Reference" "R84"
			(at -3.9 0.29 0)
			(layer "F.SilkS")
			(effects
				(font
					(size 0.65 0.65)
					(thickness 0.15)
				)
				(justify left bottom)
			)
		)
		(property "Value" "R_100R_0402"
			(at 0 1.4 0)
			(layer "F.Fab")
			(hide yes)
			(effects
				(font
					(size 0.7 0.7)
					(thickness 0.15)
				)
				(justify left bottom)
			)
		)
		(property "Datasheet" "https://www.bourns.com/docs/product-datasheets/cr.pdf"
			(at 0 0 0)
			(layer "F.Fab")
			(hide yes)
			(effects
				(font
					(size 1.27 1.27)
					(thickness 0.15)
				)
			)
		)
		(property "Description" "SMD Chip Resistor, 100 ohm, ± 1%, 62.5 mW, 0402 [1005 Metric], Thick Film, General Purpose"
			(at 0 0 0)
			(layer "F.Fab")
			(hide yes)
			(effects
				(font
					(size 1.27 1.27)
					(thickness 0.15)
				)
			)
		)
		(property "Author" "Antmicro"
			(at 0 0 0)
			(layer "F.Fab")
			(hide yes)
			(effects
				(font
					(size 1 1)
					(thickness 0.15)
				)
			)
		)
		(property "License" "Apache-2.0"
			(at 0 0 0)
			(layer "F.Fab")
			(hide yes)
			(effects
				(font
					(size 1 1)
					(thickness 0.15)
				)
			)
		)
		(property "MPN" "CR0402-FX-1000GLF"
			(at 0 0 0)
			(layer "F.Fab")
			(hide yes)
			(effects
				(font
					(size 1 1)
					(thickness 0.15)
				)
			)
		)
		(property "Manufacturer" "Bourns"
			(at 0 0 0)
			(layer "F.Fab")
			(hide yes)
			(effects
				(font
					(size 1 1)
					(thickness 0.15)
				)
			)
		)
		(property "Tolerance" "1%"
			(at 0 0 0)
			(layer "F.Fab")
			(hide yes)
			(effects
				(font
					(size 1 1)
					(thickness 0.15)
				)
			)
		)
		(property "Val" "100R"
			(at 0 0 0)
			(layer "F.Fab")
			(hide yes)
			(effects
				(font
					(size 1 1)
					(thickness 0.15)
				)
			)
		)
		(sheetname "/FPGA/")
		(sheetfile "fpga.kicad_sch")
		(attr smd)
		(fp_rect
			(start -0.925 -0.47)
			(end 0.925 0.47)
			(stroke
				(width 0.05)
				(type default)
			)
			(fill no)
			(layer "F.CrtYd")
		)
		(fp_rect
			(start -0.5 -0.25)
			(end 0.5 0.25)
			(stroke
				(width 0.15)
				(type solid)
			)
			(fill no)
			(layer "F.Fab")
		)
		(fp_text user "License: Apache-2.0"
			(at -0.95 5.169 0)
			(layer "F.Fab")
			(effects
				(font
					(size 0.7 0.7)
					(thickness 0.15)
				)
				(justify left bottom)
			)
		)
		(fp_text user "${REFERENCE}"
			(at -0.95 3.168 0)
			(layer "F.Fab")
			(effects
				(font
					(size 0.7 0.7)
					(thickness 0.15)
				)
				(justify left bottom)
			)
		)
		(fp_text user "Author: Antmicro"
			(at -0.95 4.169 0)
			(layer "F.Fab")
			(effects
				(font
					(size 0.7 0.7)
					(thickness 0.15)
				)
				(justify left bottom)
			)
		)
		(pad "1" smd roundrect
			(at -0.48 0)
			(size 0.59 0.64)
			(layers "F.Cu" "F.Mask" "F.Paste")
			(roundrect_rratio 0.25)
			(net 40 "/FPGA/DONE")
			(pintype "passive")
		)
		(pad "2" smd roundrect
			(at 0.48 0)
			(size 0.59 0.64)
			(layers "F.Cu" "F.Mask" "F.Paste")
			(roundrect_rratio 0.25)
			(net 261 "Net-(Q6-G)")
			(pintype "passive")
		)
	)
	(footprint "antmicro-footprints:TP_SMD_0.75mm"
		(layer "F.Cu")
		(at 145 91.2608)
		(property "Reference" "TP47"
			(at -3.07 0.3792 0)
			(layer "F.SilkS")
			(effects
				(font
					(size 0.65 0.65)
					(thickness 0.15)
				)
				(justify left bottom)
			)
		)
		(property "Value" "TP_0.75mm_SMD"
			(at 0 1.2 0)
			(layer "F.Fab")
			(hide yes)
			(effects
				(font
					(size 0.7 0.7)
					(thickness 0.15)
				)
				(justify left bottom)
			)
		)
		(property "Description" "SMT test point"
			(at 0 0 0)
			(layer "F.Fab")
			(hide yes)
			(effects
				(font
					(size 1.27 1.27)
					(thickness 0.15)
				)
			)
		)
		(property "Author" "Antmicro"
			(at 0 0 0)
			(layer "F.Fab")
			(hide yes)
			(effects
				(font
					(size 1 1)
					(thickness 0.15)
				)
			)
		)
		(property "License" "Apache-2.0"
			(at 0 0 0)
			(layer "F.Fab")
			(hide yes)
			(effects
				(font
					(size 1 1)
					(thickness 0.15)
				)
			)
		)
		(property "MPN" ""
			(at 0 0 0)
			(layer "F.Fab")
			(hide yes)
			(effects
				(font
					(size 1 1)
					(thickness 0.15)
				)
			)
		)
		(property "Manufacturer" ""
			(at 0 0 0)
			(layer "F.Fab")
			(hide yes)
			(effects
				(font
					(size 1 1)
					(thickness 0.15)
				)
			)
		)
		(sheetname "/Peripherals/")
		(sheetfile "peripherals.kicad_sch")
		(attr exclude_from_pos_files)
		(fp_circle
			(center 0 0)
			(end 0.475 0)
			(stroke
				(width 0.05)
				(type default)
			)
			(fill no)
			(layer "F.CrtYd")
		)
		(fp_text user "Author: Antmicro"
			(at -0.4 3.901 0)
			(layer "F.Fab")
			(effects
				(font
					(size 0.7 0.7)
					(thickness 0.15)
				)
				(justify left bottom)
			)
		)
		(fp_text user "${REFERENCE}"
			(at -0.4 2.7 0)
			(layer "F.Fab")
			(effects
				(font
					(size 0.7 0.7)
					(thickness 0.15)
				)
				(justify left bottom)
			)
		)
		(fp_text user "License: Apache-2.0"
			(at -0.4 5.101 0)
			(layer "F.Fab")
			(effects
				(font
					(size 0.7 0.7)
					(thickness 0.15)
				)
				(justify left bottom)
			)
		)
		(pad "1" smd circle
			(at 0 0)
			(size 0.75 0.75)
			(layers "F.Cu" "F.Mask")
			(net 380 "Net-(U20-CBUS3)")
			(pinfunction "1")
			(pintype "passive")
		)
	)
	(footprint "antmicro-footprints:R_0402_1005Metric"
		(layer "F.Cu")
		(at 98.94 115.185 90)
		(descr "Resistor SMD 0402")
		(tags "resistor SMD 0402")
		(property "Reference" "R88"
			(at 0.895 0.39 90)
			(layer "F.SilkS")
			(effects
				(font
					(size 0.65 0.65)
					(thickness 0.15)
				)
				(justify left bottom)
			)
		)
		(property "Value" "R_0R_0402"
			(at 0 1.4 90)
			(layer "F.Fab")
			(hide yes)
			(effects
				(font
					(size 0.7 0.7)
					(thickness 0.15)
				)
				(justify left bottom)
			)
		)
		(property "Datasheet" "https://industrial.panasonic.com/cdbs/www-data/pdf/RDA0000/AOA0000C301.pdf"
			(at 0 0 90)
			(layer "F.Fab")
			(hide yes)
			(effects
				(font
					(size 1.27 1.27)
					(thickness 0.15)
				)
			)
		)
		(property "Description" "SMD Chip Resistor, Jumper, 0 ohm, 100 mW, 0402 [1005 Metric], Thick Film, General Purpose"
			(at 0 0 90)
			(layer "F.Fab")
			(hide yes)
			(effects
				(font
					(size 1.27 1.27)
					(thickness 0.15)
				)
			)
		)
		(property "Author" "Antmicro"
			(at 214.125 16.245 0)
			(layer "F.Fab")
			(hide yes)
			(effects
				(font
					(size 1 1)
					(thickness 0.15)
				)
			)
		)
		(property "Current" "1A"
			(at 214.125 16.245 0)
			(layer "F.Fab")
			(hide yes)
			(effects
				(font
					(size 1 1)
					(thickness 0.15)
				)
			)
		)
		(property "License" "Apache-2.0"
			(at 214.125 16.245 0)
			(layer "F.Fab")
			(hide yes)
			(effects
				(font
					(size 1 1)
					(thickness 0.15)
				)
			)
		)
		(property "MPN" "ERJ2GE0R00X"
			(at 214.125 16.245 0)
			(layer "F.Fab")
			(hide yes)
			(effects
				(font
					(size 1 1)
					(thickness 0.15)
				)
			)
		)
		(property "Manufacturer" "Panasonic"
			(at 214.125 16.245 0)
			(layer "F.Fab")
			(hide yes)
			(effects
				(font
					(size 1 1)
					(thickness 0.15)
				)
			)
		)
		(property "Tolerance" "~"
			(at 214.125 16.245 0)
			(layer "F.Fab")
			(hide yes)
			(effects
				(font
					(size 1 1)
					(thickness 0.15)
				)
			)
		)
		(property "Val" "0R"
			(at 214.125 16.245 0)
			(layer "F.Fab")
			(hide yes)
			(effects
				(font
					(size 1 1)
					(thickness 0.15)
				)
			)
		)
		(sheetname "/FPGA/")
		(sheetfile "fpga.kicad_sch")
		(attr smd)
		(fp_rect
			(start -0.925 -0.47)
			(end 0.925 0.47)
			(stroke
				(width 0.05)
				(type default)
			)
			(fill no)
			(layer "F.CrtYd")
		)
		(fp_rect
			(start -0.5 -0.25)
			(end 0.5 0.25)
			(stroke
				(width 0.15)
				(type solid)
			)
			(fill no)
			(layer "F.Fab")
		)
		(fp_text user "${REFERENCE}"
			(at -0.95 3.168 90)
			(layer "F.Fab")
			(effects
				(font
					(size 0.7 0.7)
					(thickness 0.15)
				)
				(justify left bottom)
			)
		)
		(fp_text user "Author: Antmicro"
			(at -0.95 4.169 90)
			(layer "F.Fab")
			(effects
				(font
					(size 0.7 0.7)
					(thickness 0.15)
				)
				(justify left bottom)
			)
		)
		(fp_text user "License: Apache-2.0"
			(at -0.95 5.169 90)
			(layer "F.Fab")
			(effects
				(font
					(size 0.7 0.7)
					(thickness 0.15)
				)
				(justify left bottom)
			)
		)
		(pad "1" smd roundrect
			(at -0.48 0 90)
			(size 0.59 0.64)
			(layers "F.Cu" "F.Mask" "F.Paste")
			(roundrect_rratio 0.25)
			(net 134 "Net-(J7-Pad2)")
			(pintype "passive")
		)
		(pad "2" smd roundrect
			(at 0.48 0 90)
			(size 0.59 0.64)
			(layers "F.Cu" "F.Mask" "F.Paste")
			(roundrect_rratio 0.25)
			(net 169 "TMS")
			(pintype "passive")
		)
	)
	(footprint "antmicro-footprints:C_0603_1608Metric"
		(layer "F.Cu")
		(at 153.59 74.54)
		(descr "Capacitor SMD 0603")
		(tags "capacitor 0603")
		(property "Reference" "C10"
			(at -1.16 1.6 0)
			(layer "F.SilkS")
			(effects
				(font
					(size 0.65 0.65)
					(thickness 0.15)
				)
				(justify left bottom)
			)
		)
		(property "Value" "C_10u_0603"
			(at 0 1.6 0)
			(layer "F.Fab")
			(hide yes)
			(effects
				(font
					(size 0.7 0.7)
					(thickness 0.15)
				)
				(justify left bottom)
			)
		)
		(property "Datasheet" "https://www.murata.com/products/productdetail?partno=GRM188R61A106KE69%23"
			(at 0 0 0)
			(layer "F.Fab")
			(hide yes)
			(effects
				(font
					(size 1.27 1.27)
					(thickness 0.15)
				)
			)
		)
		(property "Description" "SMD Multilayer Ceramic Capacitor, 10 µF, 10 V, 0603 [1608 Metric], ± 10%, X5R, GRM Series"
			(at 0 0 0)
			(layer "F.Fab")
			(hide yes)
			(effects
				(font
					(size 1.27 1.27)
					(thickness 0.15)
				)
			)
		)
		(property "Author" "Antmicro"
			(at 0 0 0)
			(layer "F.Fab")
			(hide yes)
			(effects
				(font
					(size 1 1)
					(thickness 0.15)
				)
			)
		)
		(property "License" "Apache-2.0"
			(at 0 0 0)
			(layer "F.Fab")
			(hide yes)
			(effects
				(font
					(size 1 1)
					(thickness 0.15)
				)
			)
		)
		(property "MPN" "GRM188R61A106KE69D"
			(at 0 0 0)
			(layer "F.Fab")
			(hide yes)
			(effects
				(font
					(size 1 1)
					(thickness 0.15)
				)
			)
		)
		(property "Manufacturer" "Murata"
			(at 0 0 0)
			(layer "F.Fab")
			(hide yes)
			(effects
				(font
					(size 1 1)
					(thickness 0.15)
				)
			)
		)
		(property "Val" "10u"
			(at 0 0 0)
			(layer "F.Fab")
			(hide yes)
			(effects
				(font
					(size 1 1)
					(thickness 0.15)
				)
			)
		)
		(property "Voltage" ""
			(at 0 0 0)
			(layer "F.Fab")
			(hide yes)
			(effects
				(font
					(size 1 1)
					(thickness 0.15)
				)
			)
		)
		(property "Dielectric" "template_dielectric"
			(at 0 0 0)
			(unlocked yes)
			(layer "F.Fab")
			(hide yes)
			(effects
				(font
					(size 1 1)
					(thickness 0.15)
				)
			)
		)
		(sheetname "/Power Supply/")
		(sheetfile "supply.kicad_sch")
		(attr smd)
		(fp_line
			(start -0.15 -0.4)
			(end 0.15 -0.4)
			(stroke
				(width 0.15)
				(type solid)
			)
			(layer "F.SilkS")
		)
		(fp_line
			(start -0.15 0.4)
			(end 0.15 0.4)
			(stroke
				(width 0.15)
				(type solid)
			)
			(layer "F.SilkS")
		)
		(fp_rect
			(start -1.25 -0.65)
			(end 1.25 0.65)
			(stroke
				(width 0.05)
				(type solid)
			)
			(fill no)
			(layer "F.CrtYd")
		)
		(fp_rect
			(start -0.8 -0.4)
			(end 0.8 0.4)
			(stroke
				(width 0.15)
				(type solid)
			)
			(fill no)
			(layer "F.Fab")
		)
		(fp_text user "License: Apache-2.0"
			(at -1.682 5.895 0)
			(layer "F.Fab")
			(effects
				(font
					(size 0.7 0.7)
					(thickness 0.15)
				)
				(justify left bottom)
			)
		)
		(fp_text user "${REFERENCE}"
			(at -1.682 3.895 0)
			(layer "F.Fab")
			(effects
				(font
					(size 0.7 0.7)
					(thickness 0.15)
				)
				(justify left bottom)
			)
		)
		(fp_text user "Author: Antmicro"
			(at -1.682 4.894 0)
			(layer "F.Fab")
			(effects
				(font
					(size 0.7 0.7)
					(thickness 0.15)
				)
				(justify left bottom)
			)
		)
		(pad "1" smd roundrect
			(at -0.7 0)
			(size 0.8 1)
			(layers "F.Cu" "F.Mask" "F.Paste")
			(roundrect_rratio 0.2)
			(net 14 "+5V")
			(pintype "passive")
		)
		(pad "2" smd roundrect
			(at 0.7 0)
			(size 0.8 1)
			(layers "F.Cu" "F.Mask" "F.Paste")
			(roundrect_rratio 0.2)
			(net 1 "GND")
			(pintype "passive")
		)
	)
	(footprint "antmicro-footprints:C_0402_1005Metric"
		(layer "F.Cu")
		(at 106.49 98.7)
		(descr "Capacitor SMD 0402")
		(tags "capacitor SMD 0402")
		(property "Reference" "C82"
			(at 0.24 1.34 0)
			(layer "F.SilkS")
			(effects
				(font
					(size 0.65 0.65)
					(thickness 0.15)
				)
				(justify left bottom)
			)
		)
		(property "Value" "C_100n_0402"
			(at 0 1.4 0)
			(layer "F.Fab")
			(hide yes)
			(effects
				(font
					(size 0.7 0.7)
					(thickness 0.15)
				)
				(justify left bottom)
			)
		)
		(property "Datasheet" "https://www.murata.com/products/productdetail?partno=GRM155R61H104KE14%23"
			(at 0 0 0)
			(layer "F.Fab")
			(hide yes)
			(effects
				(font
					(size 1.27 1.27)
					(thickness 0.15)
				)
			)
		)
		(property "Description" "SMD Multilayer Ceramic Capacitor, 0.1 µF, 50 V, 0402 [1005 Metric], ± 10%, X5R, GRM Series"
			(at 0 0 0)
			(layer "F.Fab")
			(hide yes)
			(effects
				(font
					(size 1.27 1.27)
					(thickness 0.15)
				)
			)
		)
		(property "Author" "Antmicro"
			(at 0 0 0)
			(layer "F.Fab")
			(hide yes)
			(effects
				(font
					(size 1 1)
					(thickness 0.15)
				)
			)
		)
		(property "Dielectric" "X5R"
			(at 0 0 0)
			(layer "F.Fab")
			(hide yes)
			(effects
				(font
					(size 1 1)
					(thickness 0.15)
				)
			)
		)
		(property "License" "Apache-2.0"
			(at 0 0 0)
			(layer "F.Fab")
			(hide yes)
			(effects
				(font
					(size 1 1)
					(thickness 0.15)
				)
			)
		)
		(property "MPN" "GRM155R61H104KE14D"
			(at 0 0 0)
			(layer "F.Fab")
			(hide yes)
			(effects
				(font
					(size 1 1)
					(thickness 0.15)
				)
			)
		)
		(property "Manufacturer" "Murata"
			(at 0 0 0)
			(layer "F.Fab")
			(hide yes)
			(effects
				(font
					(size 1 1)
					(thickness 0.15)
				)
			)
		)
		(property "Val" "100n"
			(at 0 0 0)
			(layer "F.Fab")
			(hide yes)
			(effects
				(font
					(size 1 1)
					(thickness 0.15)
				)
			)
		)
		(property "Voltage" "50V"
			(at 0 0 0)
			(layer "F.Fab")
			(hide yes)
			(effects
				(font
					(size 1 1)
					(thickness 0.15)
				)
			)
		)
		(sheetname "/FPGA/")
		(sheetfile "fpga.kicad_sch")
		(attr smd)
		(fp_rect
			(start -0.925 -0.47)
			(end 0.925 0.47)
			(stroke
				(width 0.05)
				(type default)
			)
			(fill no)
			(layer "F.CrtYd")
		)
		(fp_line
			(start -0.494 -0.25)
			(end 0.504 -0.25)
			(stroke
				(width 0.15)
				(type solid)
			)
			(layer "F.Fab")
		)
		(fp_line
			(start -0.494 0.248)
			(end -0.494 -0.25)
			(stroke
				(width 0.15)
				(type solid)
			)
			(layer "F.Fab")
		)
		(fp_line
			(start 0.504 -0.25)
			(end 0.504 0.248)
			(stroke
				(width 0.15)
				(type solid)
			)
			(layer "F.Fab")
		)
		(fp_line
			(start 0.504 0.248)
			(end -0.494 0.248)
			(stroke
				(width 0.15)
				(type solid)
			)
			(layer "F.Fab")
		)
		(fp_text user "${REFERENCE}"
			(at -0.939 4.599 0)
			(layer "F.Fab")
			(effects
				(font
					(size 0.7 0.7)
					(thickness 0.15)
				)
				(justify left bottom)
			)
		)
		(fp_text user "License: Apache-2.0"
			(at -0.939 5.799 0)
			(layer "F.Fab")
			(effects
				(font
					(size 0.7 0.7)
					(thickness 0.15)
				)
				(justify left bottom)
			)
		)
		(fp_text user "Author: Antmicro"
			(at -0.939 3.399 0)
			(layer "F.Fab")
			(effects
				(font
					(size 0.7 0.7)
					(thickness 0.15)
				)
				(justify left bottom)
			)
		)
		(pad "1" smd roundrect
			(at -0.48 0)
			(size 0.59 0.64)
			(layers "F.Cu" "F.Mask" "F.Paste")
			(roundrect_rratio 0.25)
			(net 1 "GND")
			(pintype "passive")
		)
		(pad "2" smd roundrect
			(at 0.48 0)
			(size 0.59 0.64)
			(layers "F.Cu" "F.Mask" "F.Paste")
			(roundrect_rratio 0.25)
			(net 2 "+3V3")
			(pintype "passive")
		)
	)
	(footprint "antmicro-footprints:R_0603_1608Metric"
		(layer "F.Cu")
		(at 141.46 81)
		(descr "Resistor SMD 0603")
		(tags "resistor SMD 0603")
		(property "Reference" "R135"
			(at 1.27 0.44 0)
			(layer "F.SilkS")
			(effects
				(font
					(size 0.65 0.65)
					(thickness 0.15)
				)
				(justify left bottom)
			)
		)
		(property "Value" "R_200R_0603"
			(at 0 1.6 0)
			(layer "F.Fab")
			(hide yes)
			(effects
				(font
					(size 0.7 0.7)
					(thickness 0.15)
				)
				(justify left bottom)
			)
		)
		(property "Datasheet" "https://www.bourns.com/docs/product-datasheets/cr.pdf"
			(at 0 0 0)
			(layer "F.Fab")
			(hide yes)
			(effects
				(font
					(size 1.27 1.27)
					(thickness 0.15)
				)
			)
		)
		(property "Description" "SMD Chip Resistor, 200 ohm, ± 1%, 100 mW, 0603 [1608 Metric], Thick Film, General Purpose"
			(at 0 0 0)
			(layer "F.Fab")
			(hide yes)
			(effects
				(font
					(size 1.27 1.27)
					(thickness 0.15)
				)
			)
		)
		(property "Author" "Antmicro"
			(at 0 0 0)
			(layer "F.Fab")
			(hide yes)
			(effects
				(font
					(size 1 1)
					(thickness 0.15)
				)
			)
		)
		(property "License" "Apache-2.0"
			(at 0 0 0)
			(layer "F.Fab")
			(hide yes)
			(effects
				(font
					(size 1 1)
					(thickness 0.15)
				)
			)
		)
		(property "MPN" "CR0603-FX-2000ELF"
			(at 0 0 0)
			(layer "F.Fab")
			(hide yes)
			(effects
				(font
					(size 1 1)
					(thickness 0.15)
				)
			)
		)
		(property "Manufacturer" "Bourns"
			(at 0 0 0)
			(layer "F.Fab")
			(hide yes)
			(effects
				(font
					(size 1 1)
					(thickness 0.15)
				)
			)
		)
		(property "Tolerance" "1%"
			(at 0 0 0)
			(layer "F.Fab")
			(hide yes)
			(effects
				(font
					(size 1 1)
					(thickness 0.15)
				)
			)
		)
		(property "Val" "200R"
			(at 0 0 0)
			(layer "F.Fab")
			(hide yes)
			(effects
				(font
					(size 1 1)
					(thickness 0.15)
				)
			)
		)
		(sheetname "/Peripherals/")
		(sheetfile "peripherals.kicad_sch")
		(attr smd)
		(fp_line
			(start -0.15 -0.4)
			(end 0.15 -0.4)
			(stroke
				(width 0.15)
				(type solid)
			)
			(layer "F.SilkS")
		)
		(fp_line
			(start -0.15 0.4)
			(end 0.15 0.4)
			(stroke
				(width 0.15)
				(type solid)
			)
			(layer "F.SilkS")
		)
		(fp_rect
			(start -1.25 -0.65)
			(end 1.25 0.65)
			(stroke
				(width 0.05)
				(type solid)
			)
			(fill no)
			(layer "F.CrtYd")
		)
		(fp_rect
			(start -0.8 -0.4)
			(end 0.8 0.4)
			(stroke
				(width 0.15)
				(type solid)
			)
			(fill no)
			(layer "F.Fab")
		)
		(fp_text user "License: Apache-2.0"
			(at -1.25 5.9 0)
			(layer "F.Fab")
			(effects
				(font
					(size 0.7 0.7)
					(thickness 0.15)
				)
				(justify left bottom)
			)
		)
		(fp_text user "Author: Antmicro"
			(at -1.25 4.9 0)
			(layer "F.Fab")
			(effects
				(font
					(size 0.7 0.7)
					(thickness 0.15)
				)
				(justify left bottom)
			)
		)
		(fp_text user "${REFERENCE}"
			(at -1.25 3.898 0)
			(layer "F.Fab")
			(effects
				(font
					(size 0.7 0.7)
					(thickness 0.15)
				)
				(justify left bottom)
			)
		)
		(pad "1" smd roundrect
			(at -0.7 0)
			(size 0.8 1)
			(layers "F.Cu" "F.Mask" "F.Paste")
			(roundrect_rratio 0.2)
			(net 294 "Net-(D12-A)")
			(pintype "passive")
		)
		(pad "2" smd roundrect
			(at 0.7 0)
			(size 0.8 1)
			(layers "F.Cu" "F.Mask" "F.Paste")
			(roundrect_rratio 0.2)
			(net 348 "/Peripherals/FTDI_VCCIO")
			(pintype "passive")
		)
	)
	(footprint "antmicro-footprints:SOT-23-5"
		(layer "F.Cu")
		(at 141.69 110.7 180)
		(property "Reference" "U10"
			(at -2.14 -2.64 0)
			(layer "F.SilkS")
			(effects
				(font
					(size 0.65 0.65)
					(thickness 0.15)
				)
				(justify right bottom)
			)
		)
		(property "Value" "AP7330-W5-7"
			(at 0.002 2.799 0)
			(layer "F.Fab")
			(hide yes)
			(effects
				(font
					(size 0.7 0.7)
					(thickness 0.15)
				)
				(justify right bottom)
			)
		)
		(property "Datasheet" "https://www.diodes.com/assets/Datasheets/AP7330.pdf"
			(at 0 0 180)
			(layer "F.Fab")
			(hide yes)
			(effects
				(font
					(size 1.27 1.27)
					(thickness 0.15)
				)
			)
		)
		(property "Description" "Voltage regulator"
			(at 0 0 180)
			(layer "F.Fab")
			(hide yes)
			(effects
				(font
					(size 1.27 1.27)
					(thickness 0.15)
				)
			)
		)
		(property "Author" "Antmicro"
			(at 283.38 221.4 0)
			(layer "F.Fab")
			(hide yes)
			(effects
				(font
					(size 1 1)
					(thickness 0.15)
				)
			)
		)
		(property "License" "Apache-2.0"
			(at 283.38 221.4 0)
			(layer "F.Fab")
			(hide yes)
			(effects
				(font
					(size 1 1)
					(thickness 0.15)
				)
			)
		)
		(property "MPN" "AP7330-W5-7"
			(at 283.38 221.4 0)
			(layer "F.Fab")
			(hide yes)
			(effects
				(font
					(size 1 1)
					(thickness 0.15)
				)
			)
		)
		(property "Manufacturer" "Diodes Incorporated"
			(at 283.38 221.4 0)
			(layer "F.Fab")
			(hide yes)
			(effects
				(font
					(size 1 1)
					(thickness 0.15)
				)
			)
		)
		(sheetname "/Power Supply/")
		(sheetfile "supply.kicad_sch")
		(attr smd)
		(fp_line
			(start 0.8 1.599)
			(end 0.549 1.599)
			(stroke
				(width 0.15)
				(type solid)
			)
			(layer "F.SilkS")
		)
		(fp_line
			(start 0.8 1.3)
			(end 0.8 1.599)
			(stroke
				(width 0.15)
				(type solid)
			)
			(layer "F.SilkS")
		)
		(fp_line
			(start 0.8 0.55)
			(end 0.8 -0.55)
			(stroke
				(width 0.15)
				(type solid)
			)
			(layer "F.SilkS")
		)
		(fp_line
			(start 0.8 -1.3)
			(end 0.8 -1.6)
			(stroke
				(width 0.15)
				(type solid)
			)
			(layer "F.SilkS")
		)
		(fp_line
			(start 0.8 -1.6)
			(end 0.5 -1.6)
			(stroke
				(width 0.15)
				(type solid)
			)
			(layer "F.SilkS")
		)
		(fp_line
			(start -0.55 1.6)
			(end -0.85 1.6)
			(stroke
				(width 0.15)
				(type solid)
			)
			(layer "F.SilkS")
		)
		(fp_line
			(start -0.8 -1.6)
			(end -0.5 -1.6)
			(stroke
				(width 0.15)
				(type solid)
			)
			(layer "F.SilkS")
		)
		(fp_line
			(start -0.8 -1.6)
			(end -0.8 -1.3)
			(stroke
				(width 0.15)
				(type solid)
			)
			(layer "F.SilkS")
		)
		(fp_line
			(start -0.85 1.6)
			(end -0.85 1.301)
			(stroke
				(width 0.15)
				(type solid)
			)
			(layer "F.SilkS")
		)
		(fp_circle
			(center -1.25 -1.5)
			(end -1.2 -1.5)
			(stroke
				(width 0.15)
				(type solid)
			)
			(fill yes)
			(layer "F.SilkS")
		)
		(fp_rect
			(start 1.9 -1.76)
			(end -1.9 1.75)
			(stroke
				(width 0.05)
				(type solid)
			)
			(fill no)
			(layer "F.CrtYd")
		)
		(fp_line
			(start -0.398 -1.526)
			(end -0.874 -1.05)
			(stroke
				(width 0.15)
				(type solid)
			)
			(layer "F.Fab")
		)
		(fp_rect
			(start 0.874 1.523)
			(end -0.873 -1.525)
			(stroke
				(width 0.15)
				(type solid)
			)
			(fill no)
			(layer "F.Fab")
		)
		(pad "1" smd rect
			(at -1.351 -0.951 90)
			(size 0.55 1)
			(layers "F.Cu" "F.Mask" "F.Paste")
			(net 266 "Net-(U10-V_{IN})")
			(pinfunction "V_{IN}")
			(pintype "power_in")
		)
		(pad "2" smd rect
			(at -1.351 0 90)
			(size 0.55 1)
			(layers "F.Cu" "F.Mask" "F.Paste")
			(net 1 "GND")
			(pinfunction "GND")
			(pintype "power_in")
		)
		(pad "3" smd rect
			(at -1.351 0.949 90)
			(size 0.55 1)
			(layers "F.Cu" "F.Mask" "F.Paste")
			(net 271 "Net-(U10-EN)")
			(pinfunction "EN")
			(pintype "input")
		)
		(pad "4" smd rect
			(at 1.35 0.949 90)
			(size 0.55 1)
			(layers "F.Cu" "F.Mask" "F.Paste")
			(net 283 "Net-(U10-ADJ)")
			(pinfunction "ADJ")
			(pintype "passive")
		)
		(pad "5" smd rect
			(at 1.35 -0.951 90)
			(size 0.55 1)
			(layers "F.Cu" "F.Mask" "F.Paste")
			(net 284 "Net-(U10-V_{OUT})")
			(pinfunction "V_{OUT}")
			(pintype "power_out")
		)
	)
	(footprint "antmicro-footprints:R_0402_1005Metric"
		(layer "F.Cu")
		(at 167.2 92.6 180)
		(descr "Resistor SMD 0402")
		(tags "resistor SMD 0402")
		(property "Reference" "R123"
			(at 3.67 -0.34 180)
			(layer "F.SilkS")
			(effects
				(font
					(size 0.65 0.65)
					(thickness 0.15)
				)
				(justify left bottom)
			)
		)
		(property "Value" "R_0R_0402"
			(at 0 1.4 180)
			(layer "F.Fab")
			(hide yes)
			(effects
				(font
					(size 0.7 0.7)
					(thickness 0.15)
				)
				(justify left bottom)
			)
		)
		(property "Datasheet" "https://industrial.panasonic.com/cdbs/www-data/pdf/RDA0000/AOA0000C301.pdf"
			(at 0 0 180)
			(layer "F.Fab")
			(hide yes)
			(effects
				(font
					(size 1.27 1.27)
					(thickness 0.15)
				)
			)
		)
		(property "Description" "SMD Chip Resistor, Jumper, 0 ohm, 100 mW, 0402 [1005 Metric], Thick Film, General Purpose"
			(at 0 0 180)
			(layer "F.Fab")
			(hide yes)
			(effects
				(font
					(size 1.27 1.27)
					(thickness 0.15)
				)
			)
		)
		(property "Author" "Antmicro"
			(at 334.4 185.2 0)
			(layer "F.Fab")
			(hide yes)
			(effects
				(font
					(size 1 1)
					(thickness 0.15)
				)
			)
		)
		(property "Current" "1A"
			(at 334.4 185.2 0)
			(layer "F.Fab")
			(hide yes)
			(effects
				(font
					(size 1 1)
					(thickness 0.15)
				)
			)
		)
		(property "License" "Apache-2.0"
			(at 334.4 185.2 0)
			(layer "F.Fab")
			(hide yes)
			(effects
				(font
					(size 1 1)
					(thickness 0.15)
				)
			)
		)
		(property "MPN" "ERJ2GE0R00X"
			(at 334.4 185.2 0)
			(layer "F.Fab")
			(hide yes)
			(effects
				(font
					(size 1 1)
					(thickness 0.15)
				)
			)
		)
		(property "Manufacturer" "Panasonic"
			(at 334.4 185.2 0)
			(layer "F.Fab")
			(hide yes)
			(effects
				(font
					(size 1 1)
					(thickness 0.15)
				)
			)
		)
		(property "Tolerance" "~"
			(at 334.4 185.2 0)
			(layer "F.Fab")
			(hide yes)
			(effects
				(font
					(size 1 1)
					(thickness 0.15)
				)
			)
		)
		(property "Val" "0R"
			(at 334.4 185.2 0)
			(layer "F.Fab")
			(hide yes)
			(effects
				(font
					(size 1 1)
					(thickness 0.15)
				)
			)
		)
		(sheetname "/Peripherals/")
		(sheetfile "peripherals.kicad_sch")
		(attr smd)
		(fp_rect
			(start -0.925 -0.47)
			(end 0.925 0.47)
			(stroke
				(width 0.05)
				(type default)
			)
			(fill no)
			(layer "F.CrtYd")
		)
		(fp_rect
			(start -0.5 -0.25)
			(end 0.5 0.25)
			(stroke
				(width 0.15)
				(type solid)
			)
			(fill no)
			(layer "F.Fab")
		)
		(fp_text user "Author: Antmicro"
			(at -0.95 4.169 180)
			(layer "F.Fab")
			(effects
				(font
					(size 0.7 0.7)
					(thickness 0.15)
				)
				(justify left bottom)
			)
		)
		(fp_text user "License: Apache-2.0"
			(at -0.95 5.169 180)
			(layer "F.Fab")
			(effects
				(font
					(size 0.7 0.7)
					(thickness 0.15)
				)
				(justify left bottom)
			)
		)
		(fp_text user "${REFERENCE}"
			(at -0.95 3.168 180)
			(layer "F.Fab")
			(effects
				(font
					(size 0.7 0.7)
					(thickness 0.15)
				)
				(justify left bottom)
			)
		)
		(pad "1" smd roundrect
			(at -0.48 0 180)
			(size 0.59 0.64)
			(layers "F.Cu" "F.Mask" "F.Paste")
			(roundrect_rratio 0.25)
			(net 364 "Net-(J4-Pad40)")
			(pintype "passive")
		)
		(pad "2" smd roundrect
			(at 0.48 0 180)
			(size 0.59 0.64)
			(layers "F.Cu" "F.Mask" "F.Paste")
			(roundrect_rratio 0.25)
			(net 92 "/Peripherals/FCC1_SCL1")
			(pintype "passive")
		)
	)
	(footprint "antmicro-footprints:Conn_BNC_031-70526-21"
		(layer "F.Cu")
		(at 68.45 104.85 -90)
		(property "Reference" "J3"
			(at 6.59 -7.08 0)
			(unlocked yes)
			(layer "F.SilkS")
			(effects
				(font
					(size 0.65 0.65)
					(thickness 0.15)
				)
				(justify left bottom)
			)
		)
		(property "Value" "Conn_BNC_031-70526-21"
			(at 0 13.9 270)
			(layer "F.Fab")
			(hide yes)
			(effects
				(font
					(size 0.7 0.7)
					(thickness 0.15)
				)
				(justify left bottom)
			)
		)
		(property "Datasheet" "https://www.farnell.com/cad/2305565.pdf?_ga=2.190633003.1014497200.1574067480-156563690.1566371002&_gac=1.57062104.1572875319.Cj0KCQiAtf_tBRDtARIsAIbAKe0A1M5y_jdFCiNLNrHM5L2GjmDvn_4qnRvhHAD9jBdL9AmoMNThLCoaAjhJEALw_wcB"
			(at 0 0 270)
			(layer "F.Fab")
			(hide yes)
			(effects
				(font
					(size 1.27 1.27)
					(thickness 0.15)
				)
			)
		)
		(property "Description" "RF / Coaxial Connector, BNC Coaxial, Straight Bulkhead Jack, Board Edge / End Launch, 75 ohm"
			(at 0 0 270)
			(layer "F.Fab")
			(hide yes)
			(effects
				(font
					(size 1.27 1.27)
					(thickness 0.15)
				)
			)
		)
		(property "Author" "Antmicro"
			(at -36.4 173.3 0)
			(layer "F.Fab")
			(hide yes)
			(effects
				(font
					(size 1 1)
					(thickness 0.15)
				)
			)
		)
		(property "License" "Apache-2.0"
			(at -36.4 173.3 0)
			(layer "F.Fab")
			(hide yes)
			(effects
				(font
					(size 1 1)
					(thickness 0.15)
				)
			)
		)
		(property "MPN" "031-70526-21"
			(at -36.4 173.3 0)
			(layer "F.Fab")
			(hide yes)
			(effects
				(font
					(size 1 1)
					(thickness 0.15)
				)
			)
		)
		(property "Manufacturer" "Amphenol"
			(at -36.4 173.3 0)
			(layer "F.Fab")
			(hide yes)
			(effects
				(font
					(size 1 1)
					(thickness 0.15)
				)
			)
		)
		(property ki_fp_filters "*BNC* *SMA* *SMB* *SMC* *Cinch*")
		(sheetname "/SDI/")
		(sheetfile "sdi.kicad_sch")
		(attr smd)
		(fp_line
			(start 7.3 12.9)
			(end -7.4 12.9)
			(stroke
				(width 0.05)
				(type solid)
			)
			(layer "B.CrtYd")
		)
		(fp_line
			(start -8.2 -4.6)
			(end -7.4 -4.6)
			(stroke
				(width 0.05)
				(type solid)
			)
			(layer "B.CrtYd")
		)
		(fp_line
			(start -7.4 -4.6)
			(end -7.4 12.9)
			(stroke
				(width 0.05)
				(type solid)
			)
			(layer "B.CrtYd")
		)
		(fp_line
			(start 7.3 -4.6)
			(end 7.3 12.9)
			(stroke
				(width 0.05)
				(type solid)
			)
			(layer "B.CrtYd")
		)
		(fp_line
			(start 8.1 -4.6)
			(end 7.3 -4.6)
			(stroke
				(width 0.05)
				(type solid)
			)
			(layer "B.CrtYd")
		)
		(fp_line
			(start -8.2 -5.5)
			(end -8.2 -4.6)
			(stroke
				(width 0.05)
				(type solid)
			)
			(layer "B.CrtYd")
		)
		(fp_line
			(start -6.6 -5.5)
			(end -8.2 -5.5)
			(stroke
				(width 0.05)
				(type solid)
			)
			(layer "B.CrtYd")
		)
		(fp_line
			(start 6.5 -5.5)
			(end 8.1 -5.5)
			(stroke
				(width 0.05)
				(type solid)
			)
			(layer "B.CrtYd")
		)
		(fp_line
			(start 8.1 -5.5)
			(end 8.1 -4.6)
			(stroke
				(width 0.05)
				(type solid)
			)
			(layer "B.CrtYd")
		)
		(fp_line
			(start -6.6 -6.6)
			(end -6.6 -5.5)
			(stroke
				(width 0.05)
				(type solid)
			)
			(layer "B.CrtYd")
		)
		(fp_line
			(start -5.7 -6.6)
			(end -6.6 -6.6)
			(stroke
				(width 0.05)
				(type solid)
			)
			(layer "B.CrtYd")
		)
		(fp_line
			(start 5.6 -6.6)
			(end 6.5 -6.6)
			(stroke
				(width 0.05)
				(type solid)
			)
			(layer "B.CrtYd")
		)
		(fp_line
			(start 6.5 -6.6)
			(end 6.5 -5.5)
			(stroke
				(width 0.05)
				(type solid)
			)
			(layer "B.CrtYd")
		)
		(fp_line
			(start 4.1 -12.9)
			(end -4.2 -12.9)
			(stroke
				(width 0.05)
				(type solid)
			)
			(layer "B.CrtYd")
		)
		(fp_line
			(start -5.7 -13.6)
			(end -5.7 -6.6)
			(stroke
				(width 0.05)
				(type solid)
			)
			(layer "B.CrtYd")
		)
		(fp_line
			(start -4.2 -13.6)
			(end -4.2 -12.9)
			(stroke
				(width 0.05)
				(type solid)
			)
			(layer "B.CrtYd")
		)
		(fp_line
			(start -4.2 -13.6)
			(end -5.7 -13.6)
			(stroke
				(width 0.05)
				(type solid)
			)
			(layer "B.CrtYd")
		)
		(fp_line
			(start 4.1 -13.6)
			(end 4.1 -12.9)
			(stroke
				(width 0.05)
				(type solid)
			)
			(layer "B.CrtYd")
		)
		(fp_line
			(start 4.1 -13.6)
			(end 5.6 -13.6)
			(stroke
				(width 0.05)
				(type solid)
			)
			(layer "B.CrtYd")
		)
		(fp_line
			(start 5.6 -13.6)
			(end 5.6 -6.6)
			(stroke
				(width 0.05)
				(type solid)
			)
			(layer "B.CrtYd")
		)
		(fp_line
			(start -7.4 12.9)
			(end 7.3 12.9)
			(stroke
				(width 0.05)
				(type solid)
			)
			(layer "F.CrtYd")
		)
		(fp_line
			(start -8.2 -4.6)
			(end -7.4 -4.6)
			(stroke
				(width 0.05)
				(type solid)
			)
			(layer "F.CrtYd")
		)
		(fp_line
			(start -7.4 -4.6)
			(end -7.4 12.9)
			(stroke
				(width 0.05)
				(type solid)
			)
			(layer "F.CrtYd")
		)
		(fp_line
			(start 7.3 -4.6)
			(end 7.3 12.9)
			(stroke
				(width 0.05)
				(type solid)
			)
			(layer "F.CrtYd")
		)
		(fp_line
			(start 8.1 -4.6)
			(end 7.3 -4.6)
			(stroke
				(width 0.05)
				(type solid)
			)
			(layer "F.CrtYd")
		)
		(fp_line
			(start -8.2 -5.5)
			(end -8.2 -4.6)
			(stroke
				(width 0.05)
				(type solid)
			)
			(layer "F.CrtYd")
		)
		(fp_line
			(start -6.6 -5.5)
			(end -8.2 -5.5)
			(stroke
				(width 0.05)
				(type solid)
			)
			(layer "F.CrtYd")
		)
		(fp_line
			(start 6.5 -5.5)
			(end 8.1 -5.5)
			(stroke
				(width 0.05)
				(type solid)
			)
			(layer "F.CrtYd")
		)
		(fp_line
			(start 8.1 -5.5)
			(end 8.1 -4.6)
			(stroke
				(width 0.05)
				(type solid)
			)
			(layer "F.CrtYd")
		)
		(fp_line
			(start -6.6 -6.6)
			(end -6.6 -5.5)
			(stroke
				(width 0.05)
				(type solid)
			)
			(layer "F.CrtYd")
		)
		(fp_line
			(start -5.7 -6.6)
			(end -6.6 -6.6)
			(stroke
				(width 0.05)
				(type solid)
			)
			(layer "F.CrtYd")
		)
		(fp_line
			(start 5.6 -6.6)
			(end 6.5 -6.6)
			(stroke
				(width 0.05)
				(type solid)
			)
			(layer "F.CrtYd")
		)
		(fp_line
			(start 6.5 -6.6)
			(end 6.5 -5.5)
			(stroke
				(width 0.05)
				(type solid)
			)
			(layer "F.CrtYd")
		)
		(fp_line
			(start -4.2 -12.9)
			(end 4.1 -12.9)
			(stroke
				(width 0.05)
				(type solid)
			)
			(layer "F.CrtYd")
		)
		(fp_line
			(start -5.7 -13.6)
			(end -5.7 -6.6)
			(stroke
				(width 0.05)
				(type solid)
			)
			(layer "F.CrtYd")
		)
		(fp_line
			(start -4.2 -13.6)
			(end -4.2 -12.9)
			(stroke
				(width 0.05)
				(type solid)
			)
			(layer "F.CrtYd")
		)
		(fp_line
			(start -4.2 -13.6)
			(end -5.7 -13.6)
			(stroke
				(width 0.05)
				(type solid)
			)
			(layer "F.CrtYd")
		)
		(fp_line
			(start 4.1 -13.6)
			(end 4.1 -12.9)
			(stroke
				(width 0.05)
				(type solid)
			)
			(layer "F.CrtYd")
		)
		(fp_line
			(start 4.1 -13.6)
			(end 5.6 -13.6)
			(stroke
				(width 0.05)
				(type solid)
			)
			(layer "F.CrtYd")
		)
		(fp_line
			(start 5.6 -13.6)
			(end 5.6 -6.6)
			(stroke
				(width 0.05)
				(type solid)
			)
			(layer "F.CrtYd")
		)
		(pad "1" smd rect
			(at 0 -7.872 270)
			(size 1.1 1.75)
			(layers "F.Cu" "F.Mask" "F.Paste")
			(net 252 "/SDI/SDI_OUT")
			(pinfunction "1")
			(pintype "passive")
		)
		(pad "2" smd rect
			(at -4.851 -10.221 270)
			(size 1.1 6.45)
			(layers "F.Cu" "F.Mask" "F.Paste")
			(net 1 "GND")
			(pinfunction "2")
			(pintype "passive")
		)
		(pad "2" smd rect
			(at 4.849 -10.221 270)
			(size 1.1 6.45)
			(layers "F.Cu" "F.Mask" "F.Paste")
			(net 1 "GND")
			(pinfunction "2")
			(pintype "passive")
		)
	)
	(footprint "antmicro-footprints:C_0603_1608Metric"
		(layer "F.Cu")
		(at 161.43 66.49 90)
		(descr "Capacitor SMD 0603")
		(tags "capacitor 0603")
		(property "Reference" "C13"
			(at -2.12 -0.82 180)
			(layer "F.SilkS")
			(effects
				(font
					(size 0.65 0.65)
					(thickness 0.15)
				)
				(justify left bottom)
			)
		)
		(property "Value" "C_10u_0603"
			(at 0 1.6 90)
			(layer "F.Fab")
			(hide yes)
			(effects
				(font
					(size 0.7 0.7)
					(thickness 0.15)
				)
				(justify left bottom)
			)
		)
		(property "Datasheet" "https://www.murata.com/products/productdetail?partno=GRM188R61A106KE69%23"
			(at 0 0 90)
			(layer "F.Fab")
			(hide yes)
			(effects
				(font
					(size 1.27 1.27)
					(thickness 0.15)
				)
			)
		)
		(property "Description" "SMD Multilayer Ceramic Capacitor, 10 µF, 10 V, 0603 [1608 Metric], ± 10%, X5R, GRM Series"
			(at 0 0 90)
			(layer "F.Fab")
			(hide yes)
			(effects
				(font
					(size 1.27 1.27)
					(thickness 0.15)
				)
			)
		)
		(property "Author" "Antmicro"
			(at 227.92 -94.94 0)
			(layer "F.Fab")
			(hide yes)
			(effects
				(font
					(size 1 1)
					(thickness 0.15)
				)
			)
		)
		(property "License" "Apache-2.0"
			(at 227.92 -94.94 0)
			(layer "F.Fab")
			(hide yes)
			(effects
				(font
					(size 1 1)
					(thickness 0.15)
				)
			)
		)
		(property "MPN" "GRM188R61A106KE69D"
			(at 227.92 -94.94 0)
			(layer "F.Fab")
			(hide yes)
			(effects
				(font
					(size 1 1)
					(thickness 0.15)
				)
			)
		)
		(property "Manufacturer" "Murata"
			(at 227.92 -94.94 0)
			(layer "F.Fab")
			(hide yes)
			(effects
				(font
					(size 1 1)
					(thickness 0.15)
				)
			)
		)
		(property "Val" "10u"
			(at 227.92 -94.94 0)
			(layer "F.Fab")
			(hide yes)
			(effects
				(font
					(size 1 1)
					(thickness 0.15)
				)
			)
		)
		(property "Voltage" ""
			(at 227.92 -94.94 0)
			(layer "F.Fab")
			(hide yes)
			(effects
				(font
					(size 1 1)
					(thickness 0.15)
				)
			)
		)
		(property "Dielectric" "template_dielectric"
			(at 0 0 90)
			(unlocked yes)
			(layer "F.Fab")
			(hide yes)
			(effects
				(font
					(size 1 1)
					(thickness 0.15)
				)
			)
		)
		(sheetname "/Power Supply/")
		(sheetfile "supply.kicad_sch")
		(attr smd)
		(fp_line
			(start -0.15 -0.4)
			(end 0.15 -0.4)
			(stroke
				(width 0.15)
				(type solid)
			)
			(layer "F.SilkS")
		)
		(fp_line
			(start -0.15 0.4)
			(end 0.15 0.4)
			(stroke
				(width 0.15)
				(type solid)
			)
			(layer "F.SilkS")
		)
		(fp_rect
			(start -1.25 -0.65)
			(end 1.25 0.65)
			(stroke
				(width 0.05)
				(type solid)
			)
			(fill no)
			(layer "F.CrtYd")
		)
		(fp_rect
			(start -0.8 -0.4)
			(end 0.8 0.4)
			(stroke
				(width 0.15)
				(type solid)
			)
			(fill no)
			(layer "F.Fab")
		)
		(fp_text user "License: Apache-2.0"
			(at -1.682 5.895 90)
			(layer "F.Fab")
			(effects
				(font
					(size 0.7 0.7)
					(thickness 0.15)
				)
				(justify left bottom)
			)
		)
		(fp_text user "Author: Antmicro"
			(at -1.682 4.894 90)
			(layer "F.Fab")
			(effects
				(font
					(size 0.7 0.7)
					(thickness 0.15)
				)
				(justify left bottom)
			)
		)
		(fp_text user "${REFERENCE}"
			(at -1.682 3.895 90)
			(layer "F.Fab")
			(effects
				(font
					(size 0.7 0.7)
					(thickness 0.15)
				)
				(justify left bottom)
			)
		)
		(pad "1" smd roundrect
			(at -0.7 0 90)
			(size 0.8 1)
			(layers "F.Cu" "F.Mask" "F.Paste")
			(roundrect_rratio 0.2)
			(net 328 "/Power Supply/5V_3V3_IN")
			(pintype "passive")
		)
		(pad "2" smd roundrect
			(at 0.7 0 90)
			(size 0.8 1)
			(layers "F.Cu" "F.Mask" "F.Paste")
			(roundrect_rratio 0.2)
			(net 1 "GND")
			(pintype "passive")
		)
	)
	(footprint "antmicro-footprints:TP_SMD_0.75mm"
		(layer "F.Cu")
		(at 139.5908 64.25 90)
		(property "Reference" "TP7"
			(at -2.39 0.3392 90)
			(layer "F.SilkS")
			(effects
				(font
					(size 0.65 0.65)
					(thickness 0.15)
				)
				(justify left bottom)
			)
		)
		(property "Value" "TP_0.75mm_SMD"
			(at 0 1.2 90)
			(layer "F.Fab")
			(hide yes)
			(effects
				(font
					(size 0.7 0.7)
					(thickness 0.15)
				)
				(justify left bottom)
			)
		)
		(property "Description" "SMT test point"
			(at 0 0 90)
			(layer "F.Fab")
			(hide yes)
			(effects
				(font
					(size 1.27 1.27)
					(thickness 0.15)
				)
			)
		)
		(property "Author" "Antmicro"
			(at 203.8408 -75.3408 0)
			(layer "F.Fab")
			(hide yes)
			(effects
				(font
					(size 1 1)
					(thickness 0.15)
				)
			)
		)
		(property "License" "Apache-2.0"
			(at 203.8408 -75.3408 0)
			(layer "F.Fab")
			(hide yes)
			(effects
				(font
					(size 1 1)
					(thickness 0.15)
				)
			)
		)
		(property "MPN" ""
			(at 203.8408 -75.3408 0)
			(layer "F.Fab")
			(hide yes)
			(effects
				(font
					(size 1 1)
					(thickness 0.15)
				)
			)
		)
		(property "Manufacturer" ""
			(at 203.8408 -75.3408 0)
			(layer "F.Fab")
			(hide yes)
			(effects
				(font
					(size 1 1)
					(thickness 0.15)
				)
			)
		)
		(sheetname "/Power Supply/")
		(sheetfile "supply.kicad_sch")
		(attr exclude_from_pos_files)
		(fp_circle
			(center 0 0)
			(end 0.475 0)
			(stroke
				(width 0.05)
				(type default)
			)
			(fill no)
			(layer "F.CrtYd")
		)
		(fp_text user "Author: Antmicro"
			(at -0.4 3.901 90)
			(layer "F.Fab")
			(effects
				(font
					(size 0.7 0.7)
					(thickness 0.15)
				)
				(justify left bottom)
			)
		)
		(fp_text user "License: Apache-2.0"
			(at -0.4 5.101 90)
			(layer "F.Fab")
			(effects
				(font
					(size 0.7 0.7)
					(thickness 0.15)
				)
				(justify left bottom)
			)
		)
		(fp_text user "${REFERENCE}"
			(at -0.4 2.7 90)
			(layer "F.Fab")
			(effects
				(font
					(size 0.7 0.7)
					(thickness 0.15)
				)
				(justify left bottom)
			)
		)
		(pad "1" smd circle
			(at 0 0 90)
			(size 0.75 0.75)
			(layers "F.Cu" "F.Mask")
			(net 248 "+1V5")
			(pinfunction "1")
			(pintype "passive")
		)
	)
	(footprint "antmicro-footprints:C_0603_1608Metric"
		(layer "F.Cu")
		(at 161.23 63.94 90)
		(descr "Capacitor SMD 0603")
		(tags "capacitor 0603")
		(property "Reference" "C22"
			(at 0.11 -2.48 180)
			(layer "F.SilkS")
			(effects
				(font
					(size 0.65 0.65)
					(thickness 0.15)
				)
				(justify left bottom)
			)
		)
		(property "Value" "C_22u_0603"
			(at 0 1.6 90)
			(layer "F.Fab")
			(hide yes)
			(effects
				(font
					(size 0.7 0.7)
					(thickness 0.15)
				)
				(justify left bottom)
			)
		)
		(property "Datasheet" "https://www.murata.com/products/productdetail?partno=GRM188R60J226MEA0%23"
			(at 0 0 90)
			(layer "F.Fab")
			(hide yes)
			(effects
				(font
					(size 1.27 1.27)
					(thickness 0.15)
				)
			)
		)
		(property "Description" "SMD Multilayer Ceramic Capacitor, 22 µF, 6.3 V, 0603 [1608 Metric], ± 20%, X5R, GRM Series"
			(at 0 0 90)
			(layer "F.Fab")
			(hide yes)
			(effects
				(font
					(size 1.27 1.27)
					(thickness 0.15)
				)
			)
		)
		(property "Author" "Antmicro"
			(at 225.17 -97.29 0)
			(layer "F.Fab")
			(hide yes)
			(effects
				(font
					(size 1 1)
					(thickness 0.15)
				)
			)
		)
		(property "Dielectric" ""
			(at 225.17 -97.29 0)
			(layer "F.Fab")
			(hide yes)
			(effects
				(font
					(size 1 1)
					(thickness 0.15)
				)
			)
		)
		(property "License" "Apache-2.0"
			(at 225.17 -97.29 0)
			(layer "F.Fab")
			(hide yes)
			(effects
				(font
					(size 1 1)
					(thickness 0.15)
				)
			)
		)
		(property "MPN" "GRM188R60J226MEA0D"
			(at 225.17 -97.29 0)
			(layer "F.Fab")
			(hide yes)
			(effects
				(font
					(size 1 1)
					(thickness 0.15)
				)
			)
		)
		(property "Manufacturer" "Murata"
			(at 225.17 -97.29 0)
			(layer "F.Fab")
			(hide yes)
			(effects
				(font
					(size 1 1)
					(thickness 0.15)
				)
			)
		)
		(property "Val" "22u"
			(at 225.17 -97.29 0)
			(layer "F.Fab")
			(hide yes)
			(effects
				(font
					(size 1 1)
					(thickness 0.15)
				)
			)
		)
		(property "Voltage" ""
			(at 225.17 -97.29 0)
			(layer "F.Fab")
			(hide yes)
			(effects
				(font
					(size 1 1)
					(thickness 0.15)
				)
			)
		)
		(sheetname "/Power Supply/")
		(sheetfile "supply.kicad_sch")
		(attr smd)
		(fp_line
			(start -0.15 -0.4)
			(end 0.15 -0.4)
			(stroke
				(width 0.15)
				(type solid)
			)
			(layer "F.SilkS")
		)
		(fp_line
			(start -0.15 0.4)
			(end 0.15 0.4)
			(stroke
				(width 0.15)
				(type solid)
			)
			(layer "F.SilkS")
		)
		(fp_rect
			(start -1.25 -0.65)
			(end 1.25 0.65)
			(stroke
				(width 0.05)
				(type solid)
			)
			(fill no)
			(layer "F.CrtYd")
		)
		(fp_rect
			(start -0.8 -0.4)
			(end 0.8 0.4)
			(stroke
				(width 0.15)
				(type solid)
			)
			(fill no)
			(layer "F.Fab")
		)
		(fp_text user "License: Apache-2.0"
			(at -1.682 5.895 90)
			(layer "F.Fab")
			(effects
				(font
					(size 0.7 0.7)
					(thickness 0.15)
				)
				(justify left bottom)
			)
		)
		(fp_text user "${REFERENCE}"
			(at -1.682 3.895 90)
			(layer "F.Fab")
			(effects
				(font
					(size 0.7 0.7)
					(thickness 0.15)
				)
				(justify left bottom)
			)
		)
		(fp_text user "Author: Antmicro"
			(at -1.682 4.894 90)
			(layer "F.Fab")
			(effects
				(font
					(size 0.7 0.7)
					(thickness 0.15)
				)
				(justify left bottom)
			)
		)
		(pad "1" smd roundrect
			(at -0.7 0 90)
			(size 0.8 1)
			(layers "F.Cu" "F.Mask" "F.Paste")
			(roundrect_rratio 0.2)
			(net 1 "GND")
			(pintype "passive")
		)
		(pad "2" smd roundrect
			(at 0.7 0 90)
			(size 0.8 1)
			(layers "F.Cu" "F.Mask" "F.Paste")
			(roundrect_rratio 0.2)
			(net 275 "/Power Supply/3V3_OUT")
			(pintype "passive")
		)
	)
	(footprint "antmicro-footprints:TP_SMD_0.75mm"
		(layer "F.Cu")
		(at 166.99 79.4)
		(property "Reference" "TP45"
			(at -1.36 -0.6 0)
			(layer "F.SilkS")
			(effects
				(font
					(size 0.65 0.65)
					(thickness 0.15)
				)
				(justify left bottom)
			)
		)
		(property "Value" "TP_0.75mm_SMD"
			(at 0 1.2 0)
			(layer "F.Fab")
			(hide yes)
			(effects
				(font
					(size 0.7 0.7)
					(thickness 0.15)
				)
				(justify left bottom)
			)
		)
		(property "Description" "SMT test point"
			(at 0 0 0)
			(layer "F.Fab")
			(hide yes)
			(effects
				(font
					(size 1.27 1.27)
					(thickness 0.15)
				)
			)
		)
		(property "Author" "Antmicro"
			(at 0 0 0)
			(layer "F.Fab")
			(hide yes)
			(effects
				(font
					(size 1 1)
					(thickness 0.15)
				)
			)
		)
		(property "License" "Apache-2.0"
			(at 0 0 0)
			(layer "F.Fab")
			(hide yes)
			(effects
				(font
					(size 1 1)
					(thickness 0.15)
				)
			)
		)
		(property "MPN" ""
			(at 0 0 0)
			(layer "F.Fab")
			(hide yes)
			(effects
				(font
					(size 1 1)
					(thickness 0.15)
				)
			)
		)
		(property "Manufacturer" ""
			(at 0 0 0)
			(layer "F.Fab")
			(hide yes)
			(effects
				(font
					(size 1 1)
					(thickness 0.15)
				)
			)
		)
		(sheetname "/Peripherals/")
		(sheetfile "peripherals.kicad_sch")
		(attr exclude_from_pos_files)
		(fp_circle
			(center 0 0)
			(end 0.475 0)
			(stroke
				(width 0.05)
				(type default)
			)
			(fill no)
			(layer "F.CrtYd")
		)
		(fp_text user "Author: Antmicro"
			(at -0.4 3.901 0)
			(layer "F.Fab")
			(effects
				(font
					(size 0.7 0.7)
					(thickness 0.15)
				)
				(justify left bottom)
			)
		)
		(fp_text user "${REFERENCE}"
			(at -0.4 2.7 0)
			(layer "F.Fab")
			(effects
				(font
					(size 0.7 0.7)
					(thickness 0.15)
				)
				(justify left bottom)
			)
		)
		(fp_text user "License: Apache-2.0"
			(at -0.4 5.101 0)
			(layer "F.Fab")
			(effects
				(font
					(size 0.7 0.7)
					(thickness 0.15)
				)
				(justify left bottom)
			)
		)
		(pad "1" smd circle
			(at 0 0)
			(size 0.75 0.75)
			(layers "F.Cu" "F.Mask")
			(net 314 "/Peripherals/QW_FLT")
			(pinfunction "1")
			(pintype "passive")
		)
	)
	(footprint "antmicro-footprints:R_0402_1005Metric"
		(layer "F.Cu")
		(at 101.94 115.185 90)
		(descr "Resistor SMD 0402")
		(tags "resistor SMD 0402")
		(property "Reference" "R95"
			(at 0.895 0.39 90)
			(layer "F.SilkS")
			(effects
				(font
					(size 0.65 0.65)
					(thickness 0.15)
				)
				(justify left bottom)
			)
		)
		(property "Value" "R_0R_0402"
			(at 0 1.4 90)
			(layer "F.Fab")
			(hide yes)
			(effects
				(font
					(size 0.7 0.7)
					(thickness 0.15)
				)
				(justify left bottom)
			)
		)
		(property "Datasheet" "https://industrial.panasonic.com/cdbs/www-data/pdf/RDA0000/AOA0000C301.pdf"
			(at 0 0 90)
			(layer "F.Fab")
			(hide yes)
			(effects
				(font
					(size 1.27 1.27)
					(thickness 0.15)
				)
			)
		)
		(property "Description" "SMD Chip Resistor, Jumper, 0 ohm, 100 mW, 0402 [1005 Metric], Thick Film, General Purpose"
			(at 0 0 90)
			(layer "F.Fab")
			(hide yes)
			(effects
				(font
					(size 1.27 1.27)
					(thickness 0.15)
				)
			)
		)
		(property "Author" "Antmicro"
			(at 217.125 13.245 0)
			(layer "F.Fab")
			(hide yes)
			(effects
				(font
					(size 1 1)
					(thickness 0.15)
				)
			)
		)
		(property "Current" "1A"
			(at 217.125 13.245 0)
			(layer "F.Fab")
			(hide yes)
			(effects
				(font
					(size 1 1)
					(thickness 0.15)
				)
			)
		)
		(property "License" "Apache-2.0"
			(at 217.125 13.245 0)
			(layer "F.Fab")
			(hide yes)
			(effects
				(font
					(size 1 1)
					(thickness 0.15)
				)
			)
		)
		(property "MPN" "ERJ2GE0R00X"
			(at 217.125 13.245 0)
			(layer "F.Fab")
			(hide yes)
			(effects
				(font
					(size 1 1)
					(thickness 0.15)
				)
			)
		)
		(property "Manufacturer" "Panasonic"
			(at 217.125 13.245 0)
			(layer "F.Fab")
			(hide yes)
			(effects
				(font
					(size 1 1)
					(thickness 0.15)
				)
			)
		)
		(property "Tolerance" "~"
			(at 217.125 13.245 0)
			(layer "F.Fab")
			(hide yes)
			(effects
				(font
					(size 1 1)
					(thickness 0.15)
				)
			)
		)
		(property "Val" "0R"
			(at 217.125 13.245 0)
			(layer "F.Fab")
			(hide yes)
			(effects
				(font
					(size 1 1)
					(thickness 0.15)
				)
			)
		)
		(sheetname "/FPGA/")
		(sheetfile "fpga.kicad_sch")
		(attr smd)
		(fp_rect
			(start -0.925 -0.47)
			(end 0.925 0.47)
			(stroke
				(width 0.05)
				(type default)
			)
			(fill no)
			(layer "F.CrtYd")
		)
		(fp_rect
			(start -0.5 -0.25)
			(end 0.5 0.25)
			(stroke
				(width 0.15)
				(type solid)
			)
			(fill no)
			(layer "F.Fab")
		)
		(fp_text user "License: Apache-2.0"
			(at -0.95 5.169 90)
			(layer "F.Fab")
			(effects
				(font
					(size 0.7 0.7)
					(thickness 0.15)
				)
				(justify left bottom)
			)
		)
		(fp_text user "${REFERENCE}"
			(at -0.95 3.168 90)
			(layer "F.Fab")
			(effects
				(font
					(size 0.7 0.7)
					(thickness 0.15)
				)
				(justify left bottom)
			)
		)
		(fp_text user "Author: Antmicro"
			(at -0.95 4.169 90)
			(layer "F.Fab")
			(effects
				(font
					(size 0.7 0.7)
					(thickness 0.15)
				)
				(justify left bottom)
			)
		)
		(pad "1" smd roundrect
			(at -0.48 0 90)
			(size 0.59 0.64)
			(layers "F.Cu" "F.Mask" "F.Paste")
			(roundrect_rratio 0.25)
			(net 138 "Net-(J7-Pad8)")
			(pintype "passive")
		)
		(pad "2" smd roundrect
			(at 0.48 0 90)
			(size 0.59 0.64)
			(layers "F.Cu" "F.Mask" "F.Paste")
			(roundrect_rratio 0.25)
			(net 172 "TDI")
			(pintype "passive")
		)
	)
	(footprint "antmicro-footprints:R_0402_1005Metric"
		(layer "F.Cu")
		(at 93 69.315 -90)
		(descr "Resistor SMD 0402")
		(tags "resistor SMD 0402")
		(property "Reference" "R56"
			(at -1.425 -0.28 270)
			(layer "F.SilkS")
			(effects
				(font
					(size 0.65 0.65)
					(thickness 0.15)
				)
				(justify left bottom)
			)
		)
		(property "Value" "R_105R_0402"
			(at 0 1.4 270)
			(layer "F.Fab")
			(hide yes)
			(effects
				(font
					(size 0.7 0.7)
					(thickness 0.15)
				)
				(justify left bottom)
			)
		)
		(property "Datasheet" "https://www.bourns.com/docs/product-datasheets/cr.pdf"
			(at 0 0 270)
			(layer "F.Fab")
			(hide yes)
			(effects
				(font
					(size 1.27 1.27)
					(thickness 0.15)
				)
			)
		)
		(property "Description" "SMD Chip Resistor, 105 ohm, ± 1%, 62.5 mW, 0402 [1005 Metric], Thick Film, General Purpose"
			(at 0 0 270)
			(layer "F.Fab")
			(hide yes)
			(effects
				(font
					(size 1.27 1.27)
					(thickness 0.15)
				)
			)
		)
		(property "Author" "Antmicro"
			(at 23.685 162.315 0)
			(layer "F.Fab")
			(hide yes)
			(effects
				(font
					(size 1 1)
					(thickness 0.15)
				)
			)
		)
		(property "License" "Apache-2.0"
			(at 23.685 162.315 0)
			(layer "F.Fab")
			(hide yes)
			(effects
				(font
					(size 1 1)
					(thickness 0.15)
				)
			)
		)
		(property "MPN" "CR0402-FX-1050GLF"
			(at 23.685 162.315 0)
			(layer "F.Fab")
			(hide yes)
			(effects
				(font
					(size 1 1)
					(thickness 0.15)
				)
			)
		)
		(property "Manufacturer" "Bourns"
			(at 23.685 162.315 0)
			(layer "F.Fab")
			(hide yes)
			(effects
				(font
					(size 1 1)
					(thickness 0.15)
				)
			)
		)
		(property "Tolerance" "1%"
			(at 23.685 162.315 0)
			(layer "F.Fab")
			(hide yes)
			(effects
				(font
					(size 1 1)
					(thickness 0.15)
				)
			)
		)
		(property "Val" "105R"
			(at 23.685 162.315 0)
			(layer "F.Fab")
			(hide yes)
			(effects
				(font
					(size 1 1)
					(thickness 0.15)
				)
			)
		)
		(sheetname "/SDI/")
		(sheetfile "sdi.kicad_sch")
		(attr smd)
		(fp_rect
			(start -0.925 -0.47)
			(end 0.925 0.47)
			(stroke
				(width 0.05)
				(type default)
			)
			(fill no)
			(layer "F.CrtYd")
		)
		(fp_rect
			(start -0.5 -0.25)
			(end 0.5 0.25)
			(stroke
				(width 0.15)
				(type solid)
			)
			(fill no)
			(layer "F.Fab")
		)
		(fp_text user "${REFERENCE}"
			(at -0.95 3.168 270)
			(layer "F.Fab")
			(effects
				(font
					(size 0.7 0.7)
					(thickness 0.15)
				)
				(justify left bottom)
			)
		)
		(fp_text user "License: Apache-2.0"
			(at -0.95 5.169 270)
			(layer "F.Fab")
			(effects
				(font
					(size 0.7 0.7)
					(thickness 0.15)
				)
				(justify left bottom)
			)
		)
		(fp_text user "Author: Antmicro"
			(at -0.95 4.169 270)
			(layer "F.Fab")
			(effects
				(font
					(size 0.7 0.7)
					(thickness 0.15)
				)
				(justify left bottom)
			)
		)
		(pad "1" smd roundrect
			(at -0.48 0 270)
			(size 0.59 0.64)
			(layers "F.Cu" "F.Mask" "F.Paste")
			(roundrect_rratio 0.25)
			(net 3 "+1V2")
			(pintype "passive")
		)
		(pad "2" smd roundrect
			(at 0.48 0 270)
			(size 0.59 0.64)
			(layers "F.Cu" "F.Mask" "F.Paste")
			(roundrect_rratio 0.25)
			(net 244 "Net-(U15C-VCO_{VDD})")
			(pintype "passive")
		)
	)
	(footprint "antmicro-footprints:LED_0603_1608Metric_G"
		(layer "F.Cu")
		(at 172.63 80.968952 180)
		(descr "LED SMD 0603 Green")
		(tags "LED SMD 0603 Green")
		(property "Reference" "D9"
			(at -1.4 0.71 90)
			(layer "F.SilkS")
			(effects
				(font
					(size 0.65 0.65)
					(thickness 0.15)
				)
				(justify right top)
			)
		)
		(property "Value" "LED_G_0603_LTST-C190GKT"
			(at 0 1.6 0)
			(layer "F.Fab")
			(hide yes)
			(effects
				(font
					(size 0.7 0.7)
					(thickness 0.15)
				)
				(justify right top)
			)
		)
		(property "Datasheet" "https://media.digikey.com/pdf/Data%20Sheets/Lite-On%20PDFs/LTST-C190GKT.pdf"
			(at 0 0 0)
			(layer "F.Fab")
			(hide yes)
			(effects
				(font
					(size 1.27 1.27)
					(thickness 0.15)
				)
			)
		)
		(property "Description" "LED, Green, SMD, 0603, 20 mA, 2.1 V, 569 nm"
			(at 0 0 0)
			(layer "F.Fab")
			(hide yes)
			(effects
				(font
					(size 1.27 1.27)
					(thickness 0.15)
				)
			)
		)
		(property "Author" "Antmicro"
			(at 0 0 0)
			(layer "F.Fab")
			(hide yes)
			(effects
				(font
					(size 1 1)
					(thickness 0.15)
				)
			)
		)
		(property "License" "Apache-2.0"
			(at 0 0 0)
			(layer "F.Fab")
			(hide yes)
			(effects
				(font
					(size 1 1)
					(thickness 0.15)
				)
			)
		)
		(property "MPN" "LTST-C190GKT"
			(at 0 0 0)
			(layer "F.Fab")
			(hide yes)
			(effects
				(font
					(size 1 1)
					(thickness 0.15)
				)
			)
		)
		(property "Manufacturer" "Lite-On"
			(at 0 0 0)
			(layer "F.Fab")
			(hide yes)
			(effects
				(font
					(size 1 1)
					(thickness 0.15)
				)
			)
		)
		(property "Color" "Green"
			(at 0 0 180)
			(unlocked yes)
			(layer "F.Fab")
			(hide yes)
			(effects
				(font
					(size 1 1)
					(thickness 0.15)
				)
			)
		)
		(sheetname "/Peripherals/")
		(sheetfile "peripherals.kicad_sch")
		(attr smd)
		(fp_line
			(start 0.22 0.35)
			(end -0.22 0.35)
			(stroke
				(width 0.15)
				(type solid)
			)
			(layer "F.SilkS")
		)
		(fp_line
			(start 0.22 -0.35)
			(end -0.22 -0.35)
			(stroke
				(width 0.15)
				(type solid)
			)
			(layer "F.SilkS")
		)
		(fp_line
			(start 0.105328 0.201008)
			(end 0.105328 -0.198992)
			(stroke
				(width 0.1)
				(type solid)
			)
			(layer "F.SilkS")
		)
		(fp_line
			(start 0.105328 0.201008)
			(end -0.094672 0.001008)
			(stroke
				(width 0.1)
				(type solid)
			)
			(layer "F.SilkS")
		)
		(fp_line
			(start 0.105328 0.001008)
			(end 0.24 0.001)
			(stroke
				(width 0.1)
				(type solid)
			)
			(layer "F.SilkS")
		)
		(fp_line
			(start -0.094672 0.201008)
			(end -0.094672 -0.198992)
			(stroke
				(width 0.1)
				(type solid)
			)
			(layer "F.SilkS")
		)
		(fp_line
			(start -0.094672 0.001008)
			(end 0.105328 -0.198992)
			(stroke
				(width 0.1)
				(type solid)
			)
			(layer "F.SilkS")
		)
		(fp_line
			(start -0.094672 0.001008)
			(end -0.24 0.001008)
			(stroke
				(width 0.1)
				(type solid)
			)
			(layer "F.SilkS")
		)
		(fp_line
			(start -1.18 -0.319)
			(end -1.18 0.321)
			(stroke
				(width 0.15)
				(type solid)
			)
			(layer "F.SilkS")
		)
		(fp_rect
			(start 1.25 0.65)
			(end -1.25 -0.65)
			(stroke
				(width 0.05)
				(type solid)
			)
			(fill no)
			(layer "F.CrtYd")
		)
		(fp_line
			(start 0.599 0)
			(end 0.201 0)
			(stroke
				(width 0.15)
				(type solid)
			)
			(layer "F.Fab")
		)
		(fp_line
			(start 0.201 0.2)
			(end 0.201 0)
			(stroke
				(width 0.15)
				(type solid)
			)
			(layer "F.Fab")
		)
		(fp_line
			(start 0.201 0)
			(end 0.201 -0.202)
			(stroke
				(width 0.15)
				(type solid)
			)
			(layer "F.Fab")
		)
		(fp_line
			(start 0.201 -0.202)
			(end -0.101 0)
			(stroke
				(width 0.15)
				(type solid)
			)
			(layer "F.Fab")
		)
		(fp_line
			(start -0.101 0)
			(end 0.201 0.2)
			(stroke
				(width 0.15)
				(type solid)
			)
			(layer "F.Fab")
		)
		(fp_line
			(start -0.199 0.2)
			(end -0.199 0.1)
			(stroke
				(width 0.15)
				(type solid)
			)
			(layer "F.Fab")
		)
		(fp_line
			(start -0.199 0)
			(end -0.597 0)
			(stroke
				(width 0.15)
				(type solid)
			)
			(layer "F.Fab")
		)
		(fp_line
			(start -0.199 -0.202)
			(end -0.199 0.1)
			(stroke
				(width 0.15)
				(type solid)
			)
			(layer "F.Fab")
		)
		(fp_rect
			(start 0.848 0.4)
			(end -0.85 -0.402)
			(stroke
				(width 0.15)
				(type solid)
			)
			(fill no)
			(layer "F.Fab")
		)
		(fp_text user "Author: Antmicro"
			(at -1.4224 4.799 0)
			(layer "F.Fab")
			(effects
				(font
					(size 0.7 0.7)
					(thickness 0.15)
				)
				(justify right top)
			)
		)
		(fp_text user "${REFERENCE}"
			(at -1.4224 5.999 0)
			(layer "F.Fab")
			(effects
				(font
					(size 0.7 0.7)
					(thickness 0.15)
				)
				(justify right top)
			)
		)
		(fp_text user "License: Apache-2.0"
			(at -1.4224 3.599 0)
			(layer "F.Fab")
			(effects
				(font
					(size 0.7 0.7)
					(thickness 0.15)
				)
				(justify right top)
			)
		)
		(pad "1" smd roundrect
			(at -0.7 0)
			(size 0.8 1)
			(layers "F.Cu" "F.Mask" "F.Paste")
			(roundrect_rratio 0.2)
			(net 1 "GND")
			(pinfunction "C")
			(pintype "passive")
		)
		(pad "2" smd roundrect
			(at 0.7 0)
			(size 0.8 1)
			(layers "F.Cu" "F.Mask" "F.Paste")
			(roundrect_rratio 0.2)
			(net 255 "Net-(D9-A)")
			(pinfunction "A")
			(pintype "passive")
		)
	)
	(footprint "antmicro-footprints:TP_SMD_0.75mm"
		(layer "F.Cu")
		(at 96.18 84.37)
		(property "Reference" "TP13"
			(at -3.05 0.27 0)
			(layer "F.SilkS")
			(effects
				(font
					(size 0.65 0.65)
					(thickness 0.15)
				)
				(justify left bottom)
			)
		)
		(property "Value" "TP_0.75mm_SMD"
			(at 0 1.2 0)
			(layer "F.Fab")
			(hide yes)
			(effects
				(font
					(size 0.7 0.7)
					(thickness 0.15)
				)
				(justify left bottom)
			)
		)
		(property "Description" "SMT test point"
			(at 0 0 0)
			(layer "F.Fab")
			(hide yes)
			(effects
				(font
					(size 1.27 1.27)
					(thickness 0.15)
				)
			)
		)
		(property "Author" "Antmicro"
			(at 0 0 0)
			(layer "F.Fab")
			(hide yes)
			(effects
				(font
					(size 1 1)
					(thickness 0.15)
				)
			)
		)
		(property "License" "Apache-2.0"
			(at 0 0 0)
			(layer "F.Fab")
			(hide yes)
			(effects
				(font
					(size 1 1)
					(thickness 0.15)
				)
			)
		)
		(property "MPN" ""
			(at 0 0 0)
			(layer "F.Fab")
			(hide yes)
			(effects
				(font
					(size 1 1)
					(thickness 0.15)
				)
			)
		)
		(property "Manufacturer" ""
			(at 0 0 0)
			(layer "F.Fab")
			(hide yes)
			(effects
				(font
					(size 1 1)
					(thickness 0.15)
				)
			)
		)
		(sheetname "/SDI/")
		(sheetfile "sdi.kicad_sch")
		(attr exclude_from_pos_files)
		(fp_circle
			(center 0 0)
			(end 0.475 0)
			(stroke
				(width 0.05)
				(type default)
			)
			(fill no)
			(layer "F.CrtYd")
		)
		(fp_text user "Author: Antmicro"
			(at -0.4 3.901 0)
			(layer "F.Fab")
			(effects
				(font
					(size 0.7 0.7)
					(thickness 0.15)
				)
				(justify left bottom)
			)
		)
		(fp_text user "${REFERENCE}"
			(at -0.4 2.7 0)
			(layer "F.Fab")
			(effects
				(font
					(size 0.7 0.7)
					(thickness 0.15)
				)
				(justify left bottom)
			)
		)
		(fp_text user "License: Apache-2.0"
			(at -0.4 5.101 0)
			(layer "F.Fab")
			(effects
				(font
					(size 0.7 0.7)
					(thickness 0.15)
				)
				(justify left bottom)
			)
		)
		(pad "1" smd circle
			(at 0 0)
			(size 0.75 0.75)
			(layers "F.Cu" "F.Mask")
			(net 377 "Net-(U15B-XTAL_OUT)")
			(pinfunction "1")
			(pintype "passive")
		)
	)
	(footprint "antmicro-footprints:R_0402_1005Metric"
		(layer "F.Cu")
		(at 110.63 105.55)
		(descr "Resistor SMD 0402")
		(tags "resistor SMD 0402")
		(property "Reference" "R79"
			(at 1 0.39 0)
			(layer "F.SilkS")
			(effects
				(font
					(size 0.65 0.65)
					(thickness 0.15)
				)
				(justify left bottom)
			)
		)
		(property "Value" "R_1k_0402"
			(at 0 1.4 0)
			(layer "F.Fab")
			(hide yes)
			(effects
				(font
					(size 0.7 0.7)
					(thickness 0.15)
				)
				(justify left bottom)
			)
		)
		(property "Datasheet" "https://www.bourns.com/docs/product-datasheets/cr.pdf"
			(at 0 0 0)
			(layer "F.Fab")
			(hide yes)
			(effects
				(font
					(size 1.27 1.27)
					(thickness 0.15)
				)
			)
		)
		(property "Description" "SMD Chip Resistor, 1 kohm, ± 1%, 63 mW, 0402 [1005 Metric], Thick Film, General Purpose"
			(at 0 0 0)
			(layer "F.Fab")
			(hide yes)
			(effects
				(font
					(size 1.27 1.27)
					(thickness 0.15)
				)
			)
		)
		(property "Author" "Antmicro"
			(at 0 0 0)
			(layer "F.Fab")
			(hide yes)
			(effects
				(font
					(size 1 1)
					(thickness 0.15)
				)
			)
		)
		(property "License" "Apache-2.0"
			(at 0 0 0)
			(layer "F.Fab")
			(hide yes)
			(effects
				(font
					(size 1 1)
					(thickness 0.15)
				)
			)
		)
		(property "MPN" "CR0402-FX-1001GLF"
			(at 0 0 0)
			(layer "F.Fab")
			(hide yes)
			(effects
				(font
					(size 1 1)
					(thickness 0.15)
				)
			)
		)
		(property "Manufacturer" "Bourns"
			(at 0 0 0)
			(layer "F.Fab")
			(hide yes)
			(effects
				(font
					(size 1 1)
					(thickness 0.15)
				)
			)
		)
		(property "Tolerance" "1%"
			(at 0 0 0)
			(layer "F.Fab")
			(hide yes)
			(effects
				(font
					(size 1 1)
					(thickness 0.15)
				)
			)
		)
		(property "Val" "1k"
			(at 0 0 0)
			(layer "F.Fab")
			(hide yes)
			(effects
				(font
					(size 1 1)
					(thickness 0.15)
				)
			)
		)
		(sheetname "/FPGA/")
		(sheetfile "fpga.kicad_sch")
		(attr smd)
		(fp_rect
			(start -0.925 -0.47)
			(end 0.925 0.47)
			(stroke
				(width 0.05)
				(type default)
			)
			(fill no)
			(layer "F.CrtYd")
		)
		(fp_rect
			(start -0.5 -0.25)
			(end 0.5 0.25)
			(stroke
				(width 0.15)
				(type solid)
			)
			(fill no)
			(layer "F.Fab")
		)
		(fp_text user "${REFERENCE}"
			(at -0.95 3.168 0)
			(layer "F.Fab")
			(effects
				(font
					(size 0.7 0.7)
					(thickness 0.15)
				)
				(justify left bottom)
			)
		)
		(fp_text user "Author: Antmicro"
			(at -0.95 4.169 0)
			(layer "F.Fab")
			(effects
				(font
					(size 0.7 0.7)
					(thickness 0.15)
				)
				(justify left bottom)
			)
		)
		(fp_text user "License: Apache-2.0"
			(at -0.95 5.169 0)
			(layer "F.Fab")
			(effects
				(font
					(size 0.7 0.7)
					(thickness 0.15)
				)
				(justify left bottom)
			)
		)
		(pad "1" smd roundrect
			(at -0.48 0)
			(size 0.59 0.64)
			(layers "F.Cu" "F.Mask" "F.Paste")
			(roundrect_rratio 0.25)
			(net 309 "Net-(U17-~{INT})")
			(pintype "passive")
		)
		(pad "2" smd roundrect
			(at 0.48 0)
			(size 0.59 0.64)
			(layers "F.Cu" "F.Mask" "F.Paste")
			(roundrect_rratio 0.25)
			(net 2 "+3V3")
			(pintype "passive")
		)
	)
	(footprint "antmicro-footprints:TP_SMD_0.75mm"
		(layer "F.Cu")
		(at 150.82 69.6008)
		(property "Reference" "TP9"
			(at 0.31 -0.3608 0)
			(layer "F.SilkS")
			(effects
				(font
					(size 0.65 0.65)
					(thickness 0.15)
				)
				(justify left bottom)
			)
		)
		(property "Value" "TP_0.75mm_SMD"
			(at 0 1.2 0)
			(layer "F.Fab")
			(hide yes)
			(effects
				(font
					(size 0.7 0.7)
					(thickness 0.15)
				)
				(justify left bottom)
			)
		)
		(property "Description" "SMT test point"
			(at 0 0 0)
			(layer "F.Fab")
			(hide yes)
			(effects
				(font
					(size 1.27 1.27)
					(thickness 0.15)
				)
			)
		)
		(property "Author" "Antmicro"
			(at 0 0 0)
			(layer "F.Fab")
			(hide yes)
			(effects
				(font
					(size 1 1)
					(thickness 0.15)
				)
			)
		)
		(property "License" "Apache-2.0"
			(at 0 0 0)
			(layer "F.Fab")
			(hide yes)
			(effects
				(font
					(size 1 1)
					(thickness 0.15)
				)
			)
		)
		(property "MPN" ""
			(at 0 0 0)
			(layer "F.Fab")
			(hide yes)
			(effects
				(font
					(size 1 1)
					(thickness 0.15)
				)
			)
		)
		(property "Manufacturer" ""
			(at 0 0 0)
			(layer "F.Fab")
			(hide yes)
			(effects
				(font
					(size 1 1)
					(thickness 0.15)
				)
			)
		)
		(sheetname "/Power Supply/")
		(sheetfile "supply.kicad_sch")
		(attr exclude_from_pos_files)
		(fp_circle
			(center 0 0)
			(end 0.475 0)
			(stroke
				(width 0.05)
				(type default)
			)
			(fill no)
			(layer "F.CrtYd")
		)
		(fp_text user "${REFERENCE}"
			(at -0.4 2.7 0)
			(layer "F.Fab")
			(effects
				(font
					(size 0.7 0.7)
					(thickness 0.15)
				)
				(justify left bottom)
			)
		)
		(fp_text user "Author: Antmicro"
			(at -0.4 3.901 0)
			(layer "F.Fab")
			(effects
				(font
					(size 0.7 0.7)
					(thickness 0.15)
				)
				(justify left bottom)
			)
		)
		(fp_text user "License: Apache-2.0"
			(at -0.4 5.101 0)
			(layer "F.Fab")
			(effects
				(font
					(size 0.7 0.7)
					(thickness 0.15)
				)
				(justify left bottom)
			)
		)
		(pad "1" smd circle
			(at 0 0)
			(size 0.75 0.75)
			(layers "F.Cu" "F.Mask")
			(net 1 "GND")
			(pinfunction "1")
			(pintype "passive")
		)
	)
	(footprint "antmicro-footprints:R_0402_1005Metric"
		(layer "F.Cu")
		(at 122.03 113.15)
		(descr "Resistor SMD 0402")
		(tags "resistor SMD 0402")
		(property "Reference" "R81"
			(at -3.9 0.29 0)
			(layer "F.SilkS")
			(effects
				(font
					(size 0.65 0.65)
					(thickness 0.15)
				)
				(justify left bottom)
			)
		)
		(property "Value" "R_10k_0402"
			(at 0 1.4 0)
			(layer "F.Fab")
			(hide yes)
			(effects
				(font
					(size 0.7 0.7)
					(thickness 0.15)
				)
				(justify left bottom)
			)
		)
		(property "Datasheet" "https://www.bourns.com/docs/product-datasheets/cr.pdf"
			(at 0 0 0)
			(layer "F.Fab")
			(hide yes)
			(effects
				(font
					(size 1.27 1.27)
					(thickness 0.15)
				)
			)
		)
		(property "Description" "SMD Chip Resistor, 10 kohm, ± 1%, 62.5 mW, 0402 [1005 Metric], Thick Film, General Purpose"
			(at 0 0 0)
			(layer "F.Fab")
			(hide yes)
			(effects
				(font
					(size 1.27 1.27)
					(thickness 0.15)
				)
			)
		)
		(property "Author" "Antmicro"
			(at 0 0 0)
			(layer "F.Fab")
			(hide yes)
			(effects
				(font
					(size 1 1)
					(thickness 0.15)
				)
			)
		)
		(property "License" "Apache-2.0"
			(at 0 0 0)
			(layer "F.Fab")
			(hide yes)
			(effects
				(font
					(size 1 1)
					(thickness 0.15)
				)
			)
		)
		(property "MPN" "CR0402-FX-1002GLF"
			(at 0 0 0)
			(layer "F.Fab")
			(hide yes)
			(effects
				(font
					(size 1 1)
					(thickness 0.15)
				)
			)
		)
		(property "Manufacturer" "Bourns"
			(at 0 0 0)
			(layer "F.Fab")
			(hide yes)
			(effects
				(font
					(size 1 1)
					(thickness 0.15)
				)
			)
		)
		(property "Tolerance" "1%"
			(at 0 0 0)
			(layer "F.Fab")
			(hide yes)
			(effects
				(font
					(size 1 1)
					(thickness 0.15)
				)
			)
		)
		(property "Val" "10k"
			(at 0 0 0)
			(layer "F.Fab")
			(hide yes)
			(effects
				(font
					(size 1 1)
					(thickness 0.15)
				)
			)
		)
		(sheetname "/FPGA/")
		(sheetfile "fpga.kicad_sch")
		(attr smd)
		(fp_rect
			(start -0.925 -0.47)
			(end 0.925 0.47)
			(stroke
				(width 0.05)
				(type default)
			)
			(fill no)
			(layer "F.CrtYd")
		)
		(fp_rect
			(start -0.5 -0.25)
			(end 0.5 0.25)
			(stroke
				(width 0.15)
				(type solid)
			)
			(fill no)
			(layer "F.Fab")
		)
		(fp_text user "${REFERENCE}"
			(at -0.95 3.168 0)
			(layer "F.Fab")
			(effects
				(font
					(size 0.7 0.7)
					(thickness 0.15)
				)
				(justify left bottom)
			)
		)
		(fp_text user "License: Apache-2.0"
			(at -0.95 5.169 0)
			(layer "F.Fab")
			(effects
				(font
					(size 0.7 0.7)
					(thickness 0.15)
				)
				(justify left bottom)
			)
		)
		(fp_text user "Author: Antmicro"
			(at -0.95 4.169 0)
			(layer "F.Fab")
			(effects
				(font
					(size 0.7 0.7)
					(thickness 0.15)
				)
				(justify left bottom)
			)
		)
		(pad "1" smd roundrect
			(at -0.48 0)
			(size 0.59 0.64)
			(layers "F.Cu" "F.Mask" "F.Paste")
			(roundrect_rratio 0.25)
			(net 40 "/FPGA/DONE")
			(pintype "passive")
		)
		(pad "2" smd roundrect
			(at 0.48 0)
			(size 0.59 0.64)
			(layers "F.Cu" "F.Mask" "F.Paste")
			(roundrect_rratio 0.25)
			(net 2 "+3V3")
			(pintype "passive")
		)
	)
	(footprint "antmicro-footprints:R_0402_1005Metric"
		(layer "F.Cu")
		(at 127.75 116.75 -90)
		(descr "Resistor SMD 0402")
		(tags "resistor SMD 0402")
		(property "Reference" "R128"
			(at -0.81 -0.28 270)
			(layer "F.SilkS")
			(effects
				(font
					(size 0.65 0.65)
					(thickness 0.15)
				)
				(justify left bottom)
			)
		)
		(property "Value" "R_0R_0402"
			(at 0 1.4 270)
			(layer "F.Fab")
			(hide yes)
			(effects
				(font
					(size 0.7 0.7)
					(thickness 0.15)
				)
				(justify left bottom)
			)
		)
		(property "Datasheet" "https://industrial.panasonic.com/cdbs/www-data/pdf/RDA0000/AOA0000C301.pdf"
			(at 0 0 270)
			(layer "F.Fab")
			(hide yes)
			(effects
				(font
					(size 1.27 1.27)
					(thickness 0.15)
				)
			)
		)
		(property "Description" "SMD Chip Resistor, Jumper, 0 ohm, 100 mW, 0402 [1005 Metric], Thick Film, General Purpose"
			(at 0 0 270)
			(layer "F.Fab")
			(hide yes)
			(effects
				(font
					(size 1.27 1.27)
					(thickness 0.15)
				)
			)
		)
		(property "Author" "Antmicro"
			(at 11 244.5 0)
			(layer "F.Fab")
			(hide yes)
			(effects
				(font
					(size 1 1)
					(thickness 0.15)
				)
			)
		)
		(property "Current" "1A"
			(at 11 244.5 0)
			(layer "F.Fab")
			(hide yes)
			(effects
				(font
					(size 1 1)
					(thickness 0.15)
				)
			)
		)
		(property "License" "Apache-2.0"
			(at 11 244.5 0)
			(layer "F.Fab")
			(hide yes)
			(effects
				(font
					(size 1 1)
					(thickness 0.15)
				)
			)
		)
		(property "MPN" "ERJ2GE0R00X"
			(at 11 244.5 0)
			(layer "F.Fab")
			(hide yes)
			(effects
				(font
					(size 1 1)
					(thickness 0.15)
				)
			)
		)
		(property "Manufacturer" "Panasonic"
			(at 11 244.5 0)
			(layer "F.Fab")
			(hide yes)
			(effects
				(font
					(size 1 1)
					(thickness 0.15)
				)
			)
		)
		(property "Tolerance" "~"
			(at 11 244.5 0)
			(layer "F.Fab")
			(hide yes)
			(effects
				(font
					(size 1 1)
					(thickness 0.15)
				)
			)
		)
		(property "Val" "0R"
			(at 11 244.5 0)
			(layer "F.Fab")
			(hide yes)
			(effects
				(font
					(size 1 1)
					(thickness 0.15)
				)
			)
		)
		(sheetname "/Peripherals/")
		(sheetfile "peripherals.kicad_sch")
		(attr smd)
		(fp_rect
			(start -0.925 -0.47)
			(end 0.925 0.47)
			(stroke
				(width 0.05)
				(type default)
			)
			(fill no)
			(layer "F.CrtYd")
		)
		(fp_rect
			(start -0.5 -0.25)
			(end 0.5 0.25)
			(stroke
				(width 0.15)
				(type solid)
			)
			(fill no)
			(layer "F.Fab")
		)
		(fp_text user "${REFERENCE}"
			(at -0.95 3.168 270)
			(layer "F.Fab")
			(effects
				(font
					(size 0.7 0.7)
					(thickness 0.15)
				)
				(justify left bottom)
			)
		)
		(fp_text user "Author: Antmicro"
			(at -0.95 4.169 270)
			(layer "F.Fab")
			(effects
				(font
					(size 0.7 0.7)
					(thickness 0.15)
				)
				(justify left bottom)
			)
		)
		(fp_text user "License: Apache-2.0"
			(at -0.95 5.169 270)
			(layer "F.Fab")
			(effects
				(font
					(size 0.7 0.7)
					(thickness 0.15)
				)
				(justify left bottom)
			)
		)
		(pad "1" smd roundrect
			(at -0.48 0 270)
			(size 0.59 0.64)
			(layers "F.Cu" "F.Mask" "F.Paste")
			(roundrect_rratio 0.25)
			(net 108 "/Peripherals/FFC2_VSYNC0")
			(pintype "passive")
		)
		(pad "2" smd roundrect
			(at 0.48 0 270)
			(size 0.59 0.64)
			(layers "F.Cu" "F.Mask" "F.Paste")
			(roundrect_rratio 0.25)
			(net 343 "Net-(J6-Pad32)")
			(pintype "passive")
		)
	)
	(footprint "antmicro-footprints:C_0402_1005Metric"
		(layer "F.Cu")
		(at 89.1 78.9 90)
		(descr "Capacitor SMD 0402")
		(tags "capacitor SMD 0402")
		(property "Reference" "C59"
			(at 5.36 -1.17 90)
			(layer "F.SilkS")
			(effects
				(font
					(size 0.65 0.65)
					(thickness 0.15)
				)
				(justify left bottom)
			)
		)
		(property "Value" "C_470n_0402"
			(at 0 1.4 90)
			(layer "F.Fab")
			(hide yes)
			(effects
				(font
					(size 0.7 0.7)
					(thickness 0.15)
				)
				(justify left bottom)
			)
		)
		(property "Datasheet" "https://product.tdk.com/en/search/capacitor/ceramic/mlcc/info?part_no=C1005X5R1E474M050BB"
			(at 0 0 90)
			(layer "F.Fab")
			(hide yes)
			(effects
				(font
					(size 1.27 1.27)
					(thickness 0.15)
				)
			)
		)
		(property "Description" "SMD Multilayer Ceramic Capacitor, 0.47 µF, 25 V, 0402 [1005 Metric], ± 20%, X5R, C"
			(at 0 0 90)
			(layer "F.Fab")
			(hide yes)
			(effects
				(font
					(size 1.27 1.27)
					(thickness 0.15)
				)
			)
		)
		(property "Author" "Antmicro"
			(at 168 -10.2 0)
			(layer "F.Fab")
			(hide yes)
			(effects
				(font
					(size 1 1)
					(thickness 0.15)
				)
			)
		)
		(property "Dielectric" ""
			(at 168 -10.2 0)
			(layer "F.Fab")
			(hide yes)
			(effects
				(font
					(size 1 1)
					(thickness 0.15)
				)
			)
		)
		(property "License" "Apache-2.0"
			(at 168 -10.2 0)
			(layer "F.Fab")
			(hide yes)
			(effects
				(font
					(size 1 1)
					(thickness 0.15)
				)
			)
		)
		(property "MPN" "C1005X5R1E474M050BB"
			(at 168 -10.2 0)
			(layer "F.Fab")
			(hide yes)
			(effects
				(font
					(size 1 1)
					(thickness 0.15)
				)
			)
		)
		(property "Manufacturer" "TDK"
			(at 168 -10.2 0)
			(layer "F.Fab")
			(hide yes)
			(effects
				(font
					(size 1 1)
					(thickness 0.15)
				)
			)
		)
		(property "Val" "470n"
			(at 168 -10.2 0)
			(layer "F.Fab")
			(hide yes)
			(effects
				(font
					(size 1 1)
					(thickness 0.15)
				)
			)
		)
		(property "Voltage" ""
			(at 168 -10.2 0)
			(layer "F.Fab")
			(hide yes)
			(effects
				(font
					(size 1 1)
					(thickness 0.15)
				)
			)
		)
		(sheetname "/SDI/")
		(sheetfile "sdi.kicad_sch")
		(attr smd)
		(fp_rect
			(start -0.925 -0.47)
			(end 0.925 0.47)
			(stroke
				(width 0.05)
				(type default)
			)
			(fill no)
			(layer "F.CrtYd")
		)
		(fp_line
			(start 0.504 -0.25)
			(end 0.504 0.248)
			(stroke
				(width 0.15)
				(type solid)
			)
			(layer "F.Fab")
		)
		(fp_line
			(start -0.494 -0.25)
			(end 0.504 -0.25)
			(stroke
				(width 0.15)
				(type solid)
			)
			(layer "F.Fab")
		)
		(fp_line
			(start 0.504 0.248)
			(end -0.494 0.248)
			(stroke
				(width 0.15)
				(type solid)
			)
			(layer "F.Fab")
		)
		(fp_line
			(start -0.494 0.248)
			(end -0.494 -0.25)
			(stroke
				(width 0.15)
				(type solid)
			)
			(layer "F.Fab")
		)
		(fp_text user "License: Apache-2.0"
			(at -0.939 5.799 90)
			(layer "F.Fab")
			(effects
				(font
					(size 0.7 0.7)
					(thickness 0.15)
				)
				(justify left bottom)
			)
		)
		(fp_text user "Author: Antmicro"
			(at -0.939 3.399 90)
			(layer "F.Fab")
			(effects
				(font
					(size 0.7 0.7)
					(thickness 0.15)
				)
				(justify left bottom)
			)
		)
		(fp_text user "${REFERENCE}"
			(at -0.939 4.599 90)
			(layer "F.Fab")
			(effects
				(font
					(size 0.7 0.7)
					(thickness 0.15)
				)
				(justify left bottom)
			)
		)
		(pad "1" smd roundrect
			(at -0.48 0 90)
			(size 0.59 0.64)
			(layers "F.Cu" "F.Mask" "F.Paste")
			(roundrect_rratio 0.25)
			(net 291 "/SDI/AGC_N")
			(pintype "passive")
		)
		(pad "2" smd roundrect
			(at 0.48 0 90)
			(size 0.59 0.64)
			(layers "F.Cu" "F.Mask" "F.Paste")
			(roundrect_rratio 0.25)
			(net 292 "/SDI/AGC_P")
			(pintype "passive")
		)
	)
	(footprint "antmicro-footprints:QFN-16-1EP_4x4mm_P0.65mm"
		(layer "F.Cu")
		(at 89 105.85 180)
		(property "Reference" "U16"
			(at -3.13 2.61 0)
			(layer "F.SilkS")
			(effects
				(font
					(size 0.65 0.65)
					(thickness 0.15)
				)
				(justify right bottom)
			)
		)
		(property "Value" "GS2988"
			(at 0 3.3 0)
			(layer "F.Fab")
			(hide yes)
			(effects
				(font
					(size 0.7 0.7)
					(thickness 0.15)
				)
				(justify right bottom)
			)
		)
		(property "Datasheet" "https://semtech.my.salesforce.com/sfc/p/#E0000000JelG/a/44000000MDIY/URmNPYk6YrvngFjCh2n.ZRVsjLb90QOH1YLezdH9vhM"
			(at 0 0 180)
			(layer "F.Fab")
			(hide yes)
			(effects
				(font
					(size 1.27 1.27)
					(thickness 0.15)
				)
			)
		)
		(property "Description" "SDI driver"
			(at 0 0 180)
			(layer "F.Fab")
			(hide yes)
			(effects
				(font
					(size 1.27 1.27)
					(thickness 0.15)
				)
			)
		)
		(property "Author" "Antmicro"
			(at 178 211.7 0)
			(layer "F.Fab")
			(hide yes)
			(effects
				(font
					(size 1 1)
					(thickness 0.15)
				)
			)
		)
		(property "License" "Apache-2.0"
			(at 178 211.7 0)
			(layer "F.Fab")
			(hide yes)
			(effects
				(font
					(size 1 1)
					(thickness 0.15)
				)
			)
		)
		(property "MPN" "GS2988-INE3"
			(at 178 211.7 0)
			(layer "F.Fab")
			(hide yes)
			(effects
				(font
					(size 1 1)
					(thickness 0.15)
				)
			)
		)
		(property "Manufacturer" "Semtech"
			(at 178 211.7 0)
			(layer "F.Fab")
			(hide yes)
			(effects
				(font
					(size 1 1)
					(thickness 0.15)
				)
			)
		)
		(sheetname "/SDI/")
		(sheetfile "sdi.kicad_sch")
		(attr smd)
		(fp_line
			(start 2.1 2.1)
			(end 2.1 1.398)
			(stroke
				(width 0.15)
				(type solid)
			)
			(layer "F.SilkS")
		)
		(fp_line
			(start 2.1 -2.101)
			(end 2.1 -1.401)
			(stroke
				(width 0.15)
				(type solid)
			)
			(layer "F.SilkS")
		)
		(fp_line
			(start 1.499 2.1)
			(end 2.1 2.1)
			(stroke
				(width 0.15)
				(type solid)
			)
			(layer "F.SilkS")
		)
		(fp_line
			(start 1.499 -2.101)
			(end 2.1 -2.101)
			(stroke
				(width 0.15)
				(type solid)
			)
			(layer "F.SilkS")
		)
		(fp_line
			(start -1.4 -2.1)
			(end -2.1 -2.1)
			(stroke
				(width 0.15)
				(type solid)
			)
			(layer "F.SilkS")
		)
		(fp_line
			(start -2.1 -2.1)
			(end -2.101 -1.4)
			(stroke
				(width 0.15)
				(type solid)
			)
			(layer "F.SilkS")
		)
		(fp_line
			(start -2.101 2.1)
			(end -1.5 2.1)
			(stroke
				(width 0.15)
				(type solid)
			)
			(layer "F.SilkS")
		)
		(fp_line
			(start -2.101 1.398)
			(end -2.101 2.1)
			(stroke
				(width 0.15)
				(type solid)
			)
			(layer "F.SilkS")
		)
		(fp_circle
			(center -2.35 -1.4)
			(end -2.3 -1.4)
			(stroke
				(width 0.15)
				(type solid)
			)
			(fill yes)
			(layer "F.SilkS")
		)
		(fp_rect
			(start -2.35 -2.35)
			(end 2.35 2.35)
			(stroke
				(width 0.05)
				(type solid)
			)
			(fill no)
			(layer "F.CrtYd")
		)
		(fp_line
			(start -1.5 -2)
			(end -2 -1.5)
			(stroke
				(width 0.15)
				(type solid)
			)
			(layer "F.Fab")
		)
		(fp_rect
			(start 2 2)
			(end -2 -2)
			(stroke
				(width 0.15)
				(type solid)
			)
			(fill no)
			(layer "F.Fab")
		)
		(fp_text user "License: Apache-2.0"
			(at -2.35 7.999 180)
			(layer "F.Fab")
			(effects
				(font
					(size 0.7 0.7)
					(thickness 0.15)
				)
				(justify left bottom)
			)
		)
		(fp_text user "Author: Antmicro"
			(at -2.35 6.799 180)
			(layer "F.Fab")
			(effects
				(font
					(size 0.7 0.7)
					(thickness 0.15)
				)
				(justify left bottom)
			)
		)
		(fp_text user "${REFERENCE}"
			(at -2.35 5.599 180)
			(layer "F.Fab")
			(effects
				(font
					(size 0.7 0.7)
					(thickness 0.15)
				)
				(justify left bottom)
			)
		)
		(pad "1" smd rect
			(at -1.9 -0.975 180)
			(size 0.8 0.4)
			(layers "F.Cu" "F.Mask" "F.Paste")
			(net 47 "/SDI/SDO_P")
			(pinfunction "DDI+")
			(pintype "input")
		)
		(pad "2" smd rect
			(at -1.9 -0.325 180)
			(size 0.8 0.4)
			(layers "F.Cu" "F.Mask" "F.Paste")
			(net 48 "/SDI/SDO_N")
			(pinfunction "DDI-")
			(pintype "input")
		)
		(pad "3" smd rect
			(at -1.9 0.325 180)
			(size 0.8 0.4)
			(layers "F.Cu" "F.Mask" "F.Paste")
			(net 1 "GND")
			(pinfunction "V_{EE}")
			(pintype "power_in")
		)
		(pad "4" smd rect
			(at -1.9 0.975 180)
			(size 0.8 0.4)
			(layers "F.Cu" "F.Mask" "F.Paste")
			(net 289 "Net-(U16-RSET)")
			(pinfunction "RSET")
			(pintype "passive")
		)
		(pad "5" smd rect
			(at -0.975 1.9 180)
			(size 0.4 0.8)
			(layers "F.Cu" "F.Mask" "F.Paste")
			(net 391 "unconnected-(U16-NC-Pad5)")
			(pinfunction "NC")
			(pintype "no_connect")
		)
		(pad "6" smd rect
			(at -0.325 1.9 180)
			(size 0.4 0.8)
			(layers "F.Cu" "F.Mask" "F.Paste")
			(net 184 "/SDI/~{SDO_DISABLE}")
			(pinfunction "~{DISABLE}")
			(pintype "input")
		)
		(pad "7" smd rect
			(at 0.325 1.9 180)
			(size 0.4 0.8)
			(layers "F.Cu" "F.Mask" "F.Paste")
			(net 392 "unconnected-(U16-NC-Pad7)")
			(pinfunction "NC")
			(pintype "no_connect")
		)
		(pad "8" smd rect
			(at 0.975 1.9 180)
			(size 0.4 0.8)
			(layers "F.Cu" "F.Mask" "F.Paste")
			(net 393 "unconnected-(U16-NC-Pad8)")
			(pinfunction "NC")
			(pintype "no_connect")
		)
		(pad "9" smd rect
			(at 1.9 0.975 180)
			(size 0.8 0.4)
			(layers "F.Cu" "F.Mask" "F.Paste")
			(net 2 "+3V3")
			(pinfunction "V_{CC}")
			(pintype "power_in")
		)
		(pad "10" smd rect
			(at 1.9 0.325 180)
			(size 0.8 0.4)
			(layers "F.Cu" "F.Mask" "F.Paste")
			(net 1 "GND")
			(pinfunction "SD/~{HD}")
			(pintype "input")
		)
		(pad "11" smd rect
			(at 1.9 -0.325 180)
			(size 0.8 0.4)
			(layers "F.Cu" "F.Mask" "F.Paste")
			(net 254 "/SDI/SDI_OUT_N")
			(pinfunction "SDO-")
			(pintype "output")
		)
		(pad "12" smd rect
			(at 1.9 -0.975 180)
			(size 0.8 0.4)
			(layers "F.Cu" "F.Mask" "F.Paste")
			(net 249 "/SDI/SDI_OUT_P")
			(pinfunction "SDO+")
			(pintype "output")
		)
		(pad "13" smd rect
			(at 0.975 -1.9 180)
			(size 0.4 0.8)
			(layers "F.Cu" "F.Mask" "F.Paste")
			(net 394 "unconnected-(U16-NC-Pad13)")
			(pinfunction "NC")
			(pintype "no_connect")
		)
		(pad "14" smd rect
			(at 0.325 -1.9 180)
			(size 0.4 0.8)
			(layers "F.Cu" "F.Mask" "F.Paste")
			(net 378 "Net-(U16-~{OSP})")
			(pinfunction "~{OSP}")
			(pintype "output")
		)
		(pad "15" smd rect
			(at -0.325 -1.9 180)
			(size 0.4 0.8)
			(layers "F.Cu" "F.Mask" "F.Paste")
			(net 395 "unconnected-(U16-NC-Pad15)")
			(pinfunction "NC")
			(pintype "no_connect")
		)
		(pad "16" smd rect
			(at -0.975 -1.9 180)
			(size 0.4 0.8)
			(layers "F.Cu" "F.Mask" "F.Paste")
			(net 285 "Net-(U16-~{EQ_EN})")
			(pinfunction "~{EQ_EN}")
			(pintype "input")
		)
		(pad "17" smd rect
			(at 0 0 180)
			(size 2.3 2.3)
			(layers "F.Cu" "F.Mask" "F.Paste")
			(net 1 "GND")
			(pinfunction "EP")
			(pintype "passive")
		)
	)
	(footprint "antmicro-footprints:SOT-23-6"
		(layer "F.Cu")
		(at 163.39 80)
		(property "Reference" "U19"
			(at -3.76 -1.26 0)
			(layer "F.SilkS")
			(effects
				(font
					(size 0.65 0.65)
					(thickness 0.15)
				)
				(justify left bottom)
			)
		)
		(property "Value" "DIO7553ST6"
			(at -1.75 2.75 0)
			(layer "F.Fab")
			(hide yes)
			(effects
				(font
					(size 0.7 0.7)
					(thickness 0.15)
				)
				(justify left bottom)
			)
		)
		(property "Datasheet" "https://www.mouser.com/datasheet/2/802/7e5c577022fb784effcb3cdb25b437c0-1815562.pdf"
			(at 0 0 0)
			(layer "F.Fab")
			(hide yes)
			(effects
				(font
					(size 1.27 1.27)
					(thickness 0.15)
				)
			)
		)
		(property "Description" "Power switch"
			(at 0 0 0)
			(layer "F.Fab")
			(hide yes)
			(effects
				(font
					(size 1.27 1.27)
					(thickness 0.15)
				)
			)
		)
		(property "Author" "Antmicro"
			(at 0 0 0)
			(layer "F.Fab")
			(hide yes)
			(effects
				(font
					(size 1 1)
					(thickness 0.15)
				)
			)
		)
		(property "License" "Apache-2.0"
			(at 0 0 0)
			(layer "F.Fab")
			(hide yes)
			(effects
				(font
					(size 1 1)
					(thickness 0.15)
				)
			)
		)
		(property "MPN" "DIO7553ST6"
			(at 0 0 0)
			(layer "F.Fab")
			(hide yes)
			(effects
				(font
					(size 1 1)
					(thickness 0.15)
				)
			)
		)
		(property "Manufacturer" "DIOO Microcircuits"
			(at 0 0 0)
			(layer "F.Fab")
			(hide yes)
			(effects
				(font
					(size 1 1)
					(thickness 0.15)
				)
			)
		)
		(sheetname "/Peripherals/")
		(sheetfile "peripherals.kicad_sch")
		(attr smd)
		(fp_line
			(start -1.45 -0.757)
			(end -1.45 -0.457)
			(stroke
				(width 0.12)
				(type solid)
			)
			(layer "F.SilkS")
		)
		(fp_line
			(start -1.45 0.643)
			(end -1.45 0.343)
			(stroke
				(width 0.12)
				(type solid)
			)
			(layer "F.SilkS")
		)
		(fp_line
			(start -1.3 -0.757)
			(end -1.45 -0.757)
			(stroke
				(width 0.12)
				(type solid)
			)
			(layer "F.SilkS")
		)
		(fp_line
			(start 1.3 -0.757)
			(end 1.45 -0.757)
			(stroke
				(width 0.12)
				(type solid)
			)
			(layer "F.SilkS")
		)
		(fp_line
			(start 1.3 0.643)
			(end 1.45 0.643)
			(stroke
				(width 0.12)
				(type solid)
			)
			(layer "F.SilkS")
		)
		(fp_line
			(start 1.45 -0.757)
			(end 1.45 -0.457)
			(stroke
				(width 0.12)
				(type solid)
			)
			(layer "F.SilkS")
		)
		(fp_line
			(start 1.45 0.643)
			(end 1.45 0.343)
			(stroke
				(width 0.12)
				(type solid)
			)
			(layer "F.SilkS")
		)
		(fp_rect
			(start -1.55 -1.85)
			(end 1.55 1.75)
			(stroke
				(width 0.05)
				(type solid)
			)
			(fill no)
			(layer "F.CrtYd")
		)
		(fp_line
			(start -1.5 -0.757)
			(end 1.5 -0.757)
			(stroke
				(width 0.1)
				(type solid)
			)
			(layer "F.Fab")
		)
		(fp_line
			(start -1.5 0.643)
			(end -1.5 -0.757)
			(stroke
				(width 0.1)
				(type solid)
			)
			(layer "F.Fab")
		)
		(fp_line
			(start 1.5 -0.757)
			(end 1.5 0.643)
			(stroke
				(width 0.1)
				(type solid)
			)
			(layer "F.Fab")
		)
		(fp_line
			(start 1.5 0.643)
			(end -1.5 0.643)
			(stroke
				(width 0.1)
				(type solid)
			)
			(layer "F.Fab")
		)
		(fp_text user "."
			(at -1.4 1.2 180)
			(layer "F.SilkS")
			(effects
				(font
					(size 1 1)
					(thickness 0.15)
				)
			)
		)
		(fp_text user "${REFERENCE}"
			(at -1.75 4 0)
			(layer "F.Fab")
			(effects
				(font
					(size 0.7 0.7)
					(thickness 0.15)
				)
				(justify left bottom)
			)
		)
		(fp_text user "License: Apache-2.0"
			(at -1.75 6.5 0)
			(layer "F.Fab")
			(effects
				(font
					(size 0.7 0.7)
					(thickness 0.15)
				)
				(justify left bottom)
			)
		)
		(fp_text user "Author: Antmicro"
			(at -1.829 5.25 0)
			(layer "F.Fab")
			(effects
				(font
					(size 0.7 0.7)
					(thickness 0.15)
				)
				(justify left bottom)
			)
		)
		(pad "1" smd roundrect
			(at -0.954 1.1)
			(size 0.55 1)
			(layers "F.Cu" "F.Mask" "F.Paste")
			(roundrect_rratio 0.15)
			(net 2 "+3V3")
			(pinfunction "IN")
			(pintype "power_in")
		)
		(pad "2" smd roundrect
			(at -0.003 1.1)
			(size 0.55 1)
			(layers "F.Cu" "F.Mask" "F.Paste")
			(roundrect_rratio 0.15)
			(net 1 "GND")
			(pinfunction "GND")
			(pintype "power_in")
		)
		(pad "3" smd roundrect
			(at 0.947 1.1)
			(size 0.55 1)
			(layers "F.Cu" "F.Mask" "F.Paste")
			(roundrect_rratio 0.15)
			(net 315 "/Peripherals/QWIIC_PEN")
			(pinfunction "EN")
			(pintype "input")
		)
		(pad "4" smd roundrect
			(at 0.947 -1.214)
			(size 0.55 1)
			(layers "F.Cu" "F.Mask" "F.Paste")
			(roundrect_rratio 0.15)
			(net 314 "/Peripherals/QW_FLT")
			(pinfunction "~{FAULT}")
			(pintype "output")
		)
		(pad "5" smd roundrect
			(at -0.003 -1.214)
			(size 0.55 1)
			(layers "F.Cu" "F.Mask" "F.Paste")
			(roundrect_rratio 0.15)
			(net 356 "Net-(U19-ILIM)")
			(pinfunction "ILIM")
			(pintype "passive")
		)
		(pad "6" smd roundrect
			(at -0.954 -1.214)
			(size 0.55 1)
			(layers "F.Cu" "F.Mask" "F.Paste")
			(roundrect_rratio 0.15)
			(net 310 "/Peripherals/QWIIC_3V3")
			(pinfunction "OUT")
			(pintype "power_out")
		)
	)
	(footprint "antmicro-footprints:TSSOP-16_4.4x5mm_P0.65mm"
		(layer "F.Cu")
		(at 105.79 103.1)
		(property "Reference" "U17"
			(at -6.16 -1.96 0)
			(layer "F.SilkS")
			(effects
				(font
					(size 0.65 0.65)
					(thickness 0.15)
				)
				(justify left bottom)
			)
		)
		(property "Value" "SC18IS602BIPW"
			(at 0 3.749 0)
			(layer "F.Fab")
			(hide yes)
			(effects
				(font
					(size 0.7 0.7)
					(thickness 0.15)
				)
				(justify left bottom)
			)
		)
		(property "Datasheet" "https://www.nxp.com/docs/en/data-sheet/SC18IS602B.pdf"
			(at 0 0 0)
			(layer "F.Fab")
			(hide yes)
			(effects
				(font
					(size 1.27 1.27)
					(thickness 0.15)
				)
			)
		)
		(property "Description" "I²C Controller SPI Interface 16-TSSOP"
			(at 0 0 0)
			(layer "F.Fab")
			(hide yes)
			(effects
				(font
					(size 1.27 1.27)
					(thickness 0.15)
				)
			)
		)
		(property "Author" "Antmicro"
			(at 0 0 0)
			(layer "F.Fab")
			(hide yes)
			(effects
				(font
					(size 1 1)
					(thickness 0.15)
				)
			)
		)
		(property "License" "Apache-2.0"
			(at 0 0 0)
			(layer "F.Fab")
			(hide yes)
			(effects
				(font
					(size 1 1)
					(thickness 0.15)
				)
			)
		)
		(property "MPN" "SC18IS602BIPW"
			(at 0 0 0)
			(layer "F.Fab")
			(hide yes)
			(effects
				(font
					(size 1 1)
					(thickness 0.15)
				)
			)
		)
		(property "Manufacturer" "NXP"
			(at 0 0 0)
			(layer "F.Fab")
			(hide yes)
			(effects
				(font
					(size 1 1)
					(thickness 0.15)
				)
			)
		)
		(sheetname "/FPGA/")
		(sheetfile "fpga.kicad_sch")
		(attr smd)
		(fp_line
			(start -2.149 -2.735)
			(end 2.25 -2.735)
			(stroke
				(width 0.15)
				(type solid)
			)
			(layer "F.SilkS")
		)
		(fp_line
			(start 0.051 2.733)
			(end -2.149 2.733)
			(stroke
				(width 0.15)
				(type solid)
			)
			(layer "F.SilkS")
		)
		(fp_line
			(start 0.051 2.733)
			(end 2.25 2.733)
			(stroke
				(width 0.15)
				(type solid)
			)
			(layer "F.SilkS")
		)
		(fp_circle
			(center -2.81 -2.62)
			(end -2.76 -2.62)
			(stroke
				(width 0.15)
				(type solid)
			)
			(fill yes)
			(layer "F.SilkS")
		)
		(fp_line
			(start -3.81 -2.75)
			(end -3.81 2.74)
			(stroke
				(width 0.05)
				(type solid)
			)
			(layer "F.CrtYd")
		)
		(fp_line
			(start -3.81 2.74)
			(end 3.89 2.74)
			(stroke
				(width 0.05)
				(type solid)
			)
			(layer "F.CrtYd")
		)
		(fp_line
			(start 3.89 -2.75)
			(end -3.81 -2.75)
			(stroke
				(width 0.05)
				(type solid)
			)
			(layer "F.CrtYd")
		)
		(fp_line
			(start 3.89 2.74)
			(end 3.89 -2.75)
			(stroke
				(width 0.05)
				(type solid)
			)
			(layer "F.CrtYd")
		)
		(fp_line
			(start -2.149 -1.5)
			(end -1.15 -2.5)
			(stroke
				(width 0.15)
				(type solid)
			)
			(layer "F.Fab")
		)
		(fp_line
			(start -2.149 2.499)
			(end -2.149 -1.5)
			(stroke
				(width 0.15)
				(type solid)
			)
			(layer "F.Fab")
		)
		(fp_line
			(start -1.15 -2.5)
			(end 2.25 -2.5)
			(stroke
				(width 0.15)
				(type solid)
			)
			(layer "F.Fab")
		)
		(fp_line
			(start 2.25 -2.5)
			(end 2.25 2.499)
			(stroke
				(width 0.15)
				(type solid)
			)
			(layer "F.Fab")
		)
		(fp_line
			(start 2.25 2.499)
			(end -2.149 2.499)
			(stroke
				(width 0.15)
				(type solid)
			)
			(layer "F.Fab")
		)
		(fp_text user "${REFERENCE}"
			(at -3.81 8.149 0)
			(layer "F.Fab")
			(effects
				(font
					(size 0.7 0.7)
					(thickness 0.15)
				)
				(justify left bottom)
			)
		)
		(fp_text user "License: Apache-2.0"
			(at -3.81 5.749 0)
			(layer "F.Fab")
			(effects
				(font
					(size 0.7 0.7)
					(thickness 0.15)
				)
				(justify left bottom)
			)
		)
		(fp_text user "Author: Antmicro"
			(at -3.81 6.949 0)
			(layer "F.Fab")
			(effects
				(font
					(size 0.7 0.7)
					(thickness 0.15)
				)
				(justify left bottom)
			)
		)
		(pad "1" smd rect
			(at -2.815 -2.275)
			(size 1.475 0.4)
			(layers "F.Cu" "F.Mask" "F.Paste")
			(net 29 "/FPGA/~{FLASH_CS_SOFT}")
			(pinfunction "GPIO0/~{SS0}")
			(pintype "bidirectional")
		)
		(pad "2" smd rect
			(at -2.815 -1.625)
			(size 1.475 0.4)
			(layers "F.Cu" "F.Mask" "F.Paste")
			(net 376 "/FPGA/SEL")
			(pinfunction "GPIO1/~{SS1}")
			(pintype "bidirectional")
		)
		(pad "3" smd rect
			(at -2.815 -0.975)
			(size 1.475 0.4)
			(layers "F.Cu" "F.Mask" "F.Paste")
			(net 299 "Net-(U17-~{RESET})")
			(pinfunction "~{RESET}")
			(pintype "input")
		)
		(pad "4" smd rect
			(at -2.815 -0.325)
			(size 1.475 0.4)
			(layers "F.Cu" "F.Mask" "F.Paste")
			(net 1 "GND")
			(pinfunction "V_{SS}")
			(pintype "power_in")
		)
		(pad "5" smd rect
			(at -2.815 0.325)
			(size 1.475 0.4)
			(layers "F.Cu" "F.Mask" "F.Paste")
			(net 31 "/FPGA/MISO_SOFT")
			(pinfunction "MISO")
			(pintype "input")
		)
		(pad "6" smd rect
			(at -2.815 0.975)
			(size 1.475 0.4)
			(layers "F.Cu" "F.Mask" "F.Paste")
			(net 32 "/FPGA/MOSI_SOFT")
			(pinfunction "MOSI")
			(pintype "output")
		)
		(pad "7" smd rect
			(at -2.815 1.625)
			(size 1.475 0.4)
			(layers "F.Cu" "F.Mask" "F.Paste")
			(net 290 "Net-(U17-SDA)")
			(pinfunction "SDA")
			(pintype "bidirectional")
		)
		(pad "8" smd rect
			(at -2.815 2.275)
			(size 1.475 0.4)
			(layers "F.Cu" "F.Mask" "F.Paste")
			(net 298 "Net-(U17-SCL)")
			(pinfunction "SCL")
			(pintype "input")
		)
		(pad "9" smd rect
			(at 2.91 2.275)
			(size 1.475 0.4)
			(layers "F.Cu" "F.Mask" "F.Paste")
			(net 309 "Net-(U17-~{INT})")
			(pinfunction "~{INT}")
			(pintype "output")
		)
		(pad "10" smd rect
			(at 2.91 1.625)
			(size 1.475 0.4)
			(layers "F.Cu" "F.Mask" "F.Paste")
			(net 358 "Net-(U17-GPIO2{slash}~{SS2})")
			(pinfunction "GPIO2/~{SS2}")
			(pintype "bidirectional")
		)
		(pad "11" smd rect
			(at 2.91 0.975)
			(size 1.475 0.4)
			(layers "F.Cu" "F.Mask" "F.Paste")
			(net 33 "/FPGA/SPI_CLK_SOFT")
			(pinfunction "SCLK")
			(pintype "output")
		)
		(pad "12" smd rect
			(at 2.91 0.325)
			(size 1.475 0.4)
			(layers "F.Cu" "F.Mask" "F.Paste")
			(net 2 "+3V3")
			(pinfunction "V_{DD}")
			(pintype "power_in")
		)
		(pad "13" smd rect
			(at 2.91 -0.325)
			(size 1.475 0.4)
			(layers "F.Cu" "F.Mask" "F.Paste")
			(net 372 "Net-(U17-GPIO3{slash}~{SS3})")
			(pinfunction "GPIO3/~{SS3}")
			(pintype "bidirectional")
		)
		(pad "14" smd rect
			(at 2.91 -0.975)
			(size 1.475 0.4)
			(layers "F.Cu" "F.Mask" "F.Paste")
			(net 330 "Net-(U17-A0)")
			(pinfunction "A0")
			(pintype "input")
		)
		(pad "15" smd rect
			(at 2.91 -1.625)
			(size 1.475 0.4)
			(layers "F.Cu" "F.Mask" "F.Paste")
			(net 316 "Net-(U17-A1)")
			(pinfunction "A1")
			(pintype "input")
		)
		(pad "16" smd rect
			(at 2.91 -2.275)
			(size 1.475 0.4)
			(layers "F.Cu" "F.Mask" "F.Paste")
			(net 308 "Net-(U17-A2)")
			(pinfunction "A2")
			(pintype "input")
		)
	)
	(footprint "antmicro-footprints:R_0402_1005Metric"
		(layer "F.Cu")
		(at 139.53 59.34 -90)
		(descr "Resistor SMD 0402")
		(tags "resistor SMD 0402")
		(property "Reference" "R10"
			(at 1.1 0.7 270)
			(layer "F.SilkS")
			(effects
				(font
					(size 0.65 0.65)
					(thickness 0.15)
				)
				(justify left bottom)
			)
		)
		(property "Value" "R_1k3_0402"
			(at 0 1.4 270)
			(layer "F.Fab")
			(hide yes)
			(effects
				(font
					(size 0.7 0.7)
					(thickness 0.15)
				)
				(justify left bottom)
			)
		)
		(property "Datasheet" "https://www.bourns.com/docs/product-datasheets/cr.pdf"
			(at 0 0 270)
			(layer "F.Fab")
			(hide yes)
			(effects
				(font
					(size 1.27 1.27)
					(thickness 0.15)
				)
			)
		)
		(property "Description" "SMD Chip Resistor, 1.3 kohm, ± 1%, 62.5 mW, 0402 [1005 Metric], Thick Film, General Purpose"
			(at 0 0 270)
			(layer "F.Fab")
			(hide yes)
			(effects
				(font
					(size 1.27 1.27)
					(thickness 0.15)
				)
			)
		)
		(property "Author" "Antmicro"
			(at 80.19 198.87 0)
			(layer "F.Fab")
			(hide yes)
			(effects
				(font
					(size 1 1)
					(thickness 0.15)
				)
			)
		)
		(property "License" "Apache-2.0"
			(at 80.19 198.87 0)
			(layer "F.Fab")
			(hide yes)
			(effects
				(font
					(size 1 1)
					(thickness 0.15)
				)
			)
		)
		(property "MPN" "CR0402-FX-1301GLF"
			(at 80.19 198.87 0)
			(layer "F.Fab")
			(hide yes)
			(effects
				(font
					(size 1 1)
					(thickness 0.15)
				)
			)
		)
		(property "Manufacturer" "Bourns"
			(at 80.19 198.87 0)
			(layer "F.Fab")
			(hide yes)
			(effects
				(font
					(size 1 1)
					(thickness 0.15)
				)
			)
		)
		(property "Tolerance" "1%"
			(at 80.19 198.87 0)
			(layer "F.Fab")
			(hide yes)
			(effects
				(font
					(size 1 1)
					(thickness 0.15)
				)
			)
		)
		(property "Val" "1k3"
			(at 80.19 198.87 0)
			(layer "F.Fab")
			(hide yes)
			(effects
				(font
					(size 1 1)
					(thickness 0.15)
				)
			)
		)
		(sheetname "/Power Supply/")
		(sheetfile "supply.kicad_sch")
		(attr smd)
		(fp_rect
			(start -0.925 -0.47)
			(end 0.925 0.47)
			(stroke
				(width 0.05)
				(type default)
			)
			(fill no)
			(layer "F.CrtYd")
		)
		(fp_rect
			(start -0.5 -0.25)
			(end 0.5 0.25)
			(stroke
				(width 0.15)
				(type solid)
			)
			(fill no)
			(layer "F.Fab")
		)
		(fp_text user "Author: Antmicro"
			(at -0.95 4.169 270)
			(layer "F.Fab")
			(effects
				(font
					(size 0.7 0.7)
					(thickness 0.15)
				)
				(justify left bottom)
			)
		)
		(fp_text user "${REFERENCE}"
			(at -0.95 3.168 270)
			(layer "F.Fab")
			(effects
				(font
					(size 0.7 0.7)
					(thickness 0.15)
				)
				(justify left bottom)
			)
		)
		(fp_text user "License: Apache-2.0"
			(at -0.95 5.169 270)
			(layer "F.Fab")
			(effects
				(font
					(size 0.7 0.7)
					(thickness 0.15)
				)
				(justify left bottom)
			)
		)
		(pad "1" smd roundrect
			(at -0.48 0 270)
			(size 0.59 0.64)
			(layers "F.Cu" "F.Mask" "F.Paste")
			(roundrect_rratio 0.25)
			(net 263 "Net-(U6-FB)")
			(pintype "passive")
		)
		(pad "2" smd roundrect
			(at 0.48 0 270)
			(size 0.59 0.64)
			(layers "F.Cu" "F.Mask" "F.Paste")
			(roundrect_rratio 0.25)
			(net 274 "/Power Supply/1V5_OUT")
			(pintype "passive")
		)
	)
	(footprint "antmicro-footprints:C_0402_1005Metric"
		(layer "F.Cu")
		(at 167.33 64.24 -90)
		(descr "Capacitor SMD 0402")
		(tags "capacitor SMD 0402")
		(property "Reference" "C15"
			(at -1.1 -1.4 90)
			(layer "F.SilkS")
			(effects
				(font
					(size 0.65 0.65)
					(thickness 0.15)
				)
				(justify right bottom)
			)
		)
		(property "Value" "C_100n_0402"
			(at 0 1.4 90)
			(layer "F.Fab")
			(hide yes)
			(effects
				(font
					(size 0.7 0.7)
					(thickness 0.15)
				)
				(justify right bottom)
			)
		)
		(property "Datasheet" "https://www.murata.com/products/productdetail?partno=GRM155R61H104KE14%23"
			(at 0 0 270)
			(layer "F.Fab")
			(hide yes)
			(effects
				(font
					(size 1.27 1.27)
					(thickness 0.15)
				)
			)
		)
		(property "Description" "SMD Multilayer Ceramic Capacitor, 0.1 µF, 50 V, 0402 [1005 Metric], ± 10%, X5R, GRM Series"
			(at 0 0 270)
			(layer "F.Fab")
			(hide yes)
			(effects
				(font
					(size 1.27 1.27)
					(thickness 0.15)
				)
			)
		)
		(property "Author" "Antmicro"
			(at 103.09 231.57 0)
			(layer "F.Fab")
			(hide yes)
			(effects
				(font
					(size 1 1)
					(thickness 0.15)
				)
			)
		)
		(property "Dielectric" "X5R"
			(at 103.09 231.57 0)
			(layer "F.Fab")
			(hide yes)
			(effects
				(font
					(size 1 1)
					(thickness 0.15)
				)
			)
		)
		(property "License" "Apache-2.0"
			(at 103.09 231.57 0)
			(layer "F.Fab")
			(hide yes)
			(effects
				(font
					(size 1 1)
					(thickness 0.15)
				)
			)
		)
		(property "MPN" "GRM155R61H104KE14D"
			(at 103.09 231.57 0)
			(layer "F.Fab")
			(hide yes)
			(effects
				(font
					(size 1 1)
					(thickness 0.15)
				)
			)
		)
		(property "Manufacturer" "Murata"
			(at 103.09 231.57 0)
			(layer "F.Fab")
			(hide yes)
			(effects
				(font
					(size 1 1)
					(thickness 0.15)
				)
			)
		)
		(property "Val" "100n"
			(at 103.09 231.57 0)
			(layer "F.Fab")
			(hide yes)
			(effects
				(font
					(size 1 1)
					(thickness 0.15)
				)
			)
		)
		(property "Voltage" "50V"
			(at 103.09 231.57 0)
			(layer "F.Fab")
			(hide yes)
			(effects
				(font
					(size 1 1)
					(thickness 0.15)
				)
			)
		)
		(sheetname "/Power Supply/")
		(sheetfile "supply.kicad_sch")
		(attr smd)
		(fp_rect
			(start -0.925 -0.47)
			(end 0.925 0.47)
			(stroke
				(width 0.05)
				(type default)
			)
			(fill no)
			(layer "F.CrtYd")
		)
		(fp_line
			(start -0.494 0.248)
			(end -0.494 -0.25)
			(stroke
				(width 0.15)
				(type solid)
			)
			(layer "F.Fab")
		)
		(fp_line
			(start 0.504 0.248)
			(end -0.494 0.248)
			(stroke
				(width 0.15)
				(type solid)
			)
			(layer "F.Fab")
		)
		(fp_line
			(start -0.494 -0.25)
			(end 0.504 -0.25)
			(stroke
				(width 0.15)
				(type solid)
			)
			(layer "F.Fab")
		)
		(fp_line
			(start 0.504 -0.25)
			(end 0.504 0.248)
			(stroke
				(width 0.15)
				(type solid)
			)
			(layer "F.Fab")
		)
		(fp_text user "License: Apache-2.0"
			(at -0.939 5.799 270)
			(layer "F.Fab")
			(effects
				(font
					(size 0.7 0.7)
					(thickness 0.15)
				)
				(justify left bottom)
			)
		)
		(fp_text user "${REFERENCE}"
			(at -0.939 4.599 270)
			(layer "F.Fab")
			(effects
				(font
					(size 0.7 0.7)
					(thickness 0.15)
				)
				(justify left bottom)
			)
		)
		(fp_text user "Author: Antmicro"
			(at -0.939 3.399 270)
			(layer "F.Fab")
			(effects
				(font
					(size 0.7 0.7)
					(thickness 0.15)
				)
				(justify left bottom)
			)
		)
		(pad "1" smd roundrect
			(at -0.48 0 270)
			(size 0.59 0.64)
			(layers "F.Cu" "F.Mask" "F.Paste")
			(roundrect_rratio 0.25)
			(net 278 "/Power Supply/3V3_SW")
			(pintype "passive")
		)
		(pad "2" smd roundrect
			(at 0.48 0 270)
			(size 0.59 0.64)
			(layers "F.Cu" "F.Mask" "F.Paste")
			(roundrect_rratio 0.25)
			(net 140 "Net-(U7-BST)")
			(pintype "passive")
		)
	)
	(footprint "antmicro-footprints:C_0603_1608Metric"
		(layer "B.Cu")
		(at 130.76 101.07)
		(descr "Capacitor SMD 0603")
		(tags "capacitor 0603")
		(property "Reference" "C116"
			(at -1.44 1.76 0)
			(layer "B.SilkS")
			(effects
				(font
					(size 0.65 0.65)
					(thickness 0.15)
				)
				(justify right bottom mirror)
			)
		)
		(property "Value" "C_10u_0603"
			(at 0 -1.6 0)
			(layer "B.Fab")
			(hide yes)
			(effects
				(font
					(size 0.7 0.7)
					(thickness 0.15)
				)
				(justify right bottom mirror)
			)
		)
		(property "Datasheet" "https://www.murata.com/products/productdetail?partno=GRM188R61A106KE69%23"
			(at 0 0 0)
			(layer "F.Fab")
			(hide yes)
			(effects
				(font
					(size 1.27 1.27)
					(thickness 0.15)
				)
			)
		)
		(property "Description" "SMD Multilayer Ceramic Capacitor, 10 µF, 10 V, 0603 [1608 Metric], ± 10%, X5R, GRM Series"
			(at 0 0 0)
			(layer "F.Fab")
			(hide yes)
			(effects
				(font
					(size 1.27 1.27)
					(thickness 0.15)
				)
			)
		)
		(property "Author" "Antmicro"
			(at 0 0 0)
			(layer "B.Fab")
			(hide yes)
			(effects
				(font
					(size 1 1)
					(thickness 0.15)
				)
				(justify mirror)
			)
		)
		(property "License" "Apache-2.0"
			(at 0 0 0)
			(layer "B.Fab")
			(hide yes)
			(effects
				(font
					(size 1 1)
					(thickness 0.15)
				)
				(justify mirror)
			)
		)
		(property "MPN" "GRM188R61A106KE69D"
			(at 0 0 0)
			(layer "B.Fab")
			(hide yes)
			(effects
				(font
					(size 1 1)
					(thickness 0.15)
				)
				(justify mirror)
			)
		)
		(property "Manufacturer" "Murata"
			(at 0 0 0)
			(layer "B.Fab")
			(hide yes)
			(effects
				(font
					(size 1 1)
					(thickness 0.15)
				)
				(justify mirror)
			)
		)
		(property "Val" "10u"
			(at 0 0 0)
			(layer "B.Fab")
			(hide yes)
			(effects
				(font
					(size 1 1)
					(thickness 0.15)
				)
				(justify mirror)
			)
		)
		(property "Voltage" ""
			(at 0 0 0)
			(layer "B.Fab")
			(hide yes)
			(effects
				(font
					(size 1 1)
					(thickness 0.15)
				)
				(justify mirror)
			)
		)
		(property "Dielectric" "template_dielectric"
			(at 0 0 0)
			(unlocked yes)
			(layer "B.Fab")
			(hide yes)
			(effects
				(font
					(size 1 1)
					(thickness 0.15)
				)
				(justify mirror)
			)
		)
		(sheetname "/FPGA Power/")
		(sheetfile "FPGA_Power.kicad_sch")
		(attr smd)
		(fp_line
			(start -0.15 -0.4)
			(end 0.15 -0.4)
			(stroke
				(width 0.15)
				(type solid)
			)
			(layer "B.SilkS")
		)
		(fp_line
			(start -0.15 0.4)
			(end 0.15 0.4)
			(stroke
				(width 0.15)
				(type solid)
			)
			(layer "B.SilkS")
		)
		(fp_rect
			(start -1.25 0.65)
			(end 1.25 -0.65)
			(stroke
				(width 0.05)
				(type solid)
			)
			(fill no)
			(layer "B.CrtYd")
		)
		(fp_rect
			(start -0.8 0.4)
			(end 0.8 -0.4)
			(stroke
				(width 0.15)
				(type solid)
			)
			(fill no)
			(layer "B.Fab")
		)
		(fp_text user "Author: Antmicro"
			(at -1.682 -4.894 180)
			(layer "B.Fab")
			(effects
				(font
					(size 0.7 0.7)
					(thickness 0.15)
				)
				(justify left bottom mirror)
			)
		)
		(fp_text user "${REFERENCE}"
			(at -1.682 -3.895 180)
			(layer "B.Fab")
			(effects
				(font
					(size 0.7 0.7)
					(thickness 0.15)
				)
				(justify left bottom mirror)
			)
		)
		(fp_text user "License: Apache-2.0"
			(at -1.682 -5.895 180)
			(layer "B.Fab")
			(effects
				(font
					(size 0.7 0.7)
					(thickness 0.15)
				)
				(justify left bottom mirror)
			)
		)
		(pad "1" smd roundrect
			(at -0.7 0)
			(size 0.8 1)
			(layers "B.Cu" "B.Mask" "B.Paste")
			(roundrect_rratio 0.2)
			(net 1 "GND")
			(pintype "passive")
		)
		(pad "2" smd roundrect
			(at 0.7 0)
			(size 0.8 1)
			(layers "B.Cu" "B.Mask" "B.Paste")
			(roundrect_rratio 0.2)
			(net 4 "1V0_Power")
			(pintype "passive")
		)
	)
	(footprint "antmicro-footprints:C_0402_1005Metric"
		(layer "B.Cu")
		(at 147.2 81.5 90)
		(descr "Capacitor SMD 0402")
		(tags "capacitor SMD 0402")
		(property "Reference" "C121"
			(at 0.96 0.33 90)
			(layer "B.SilkS")
			(effects
				(font
					(size 0.65 0.65)
					(thickness 0.15)
				)
				(justify right bottom mirror)
			)
		)
		(property "Value" "C_47p_0402"
			(at 0 -1.4 90)
			(layer "B.Fab")
			(hide yes)
			(effects
				(font
					(size 0.7 0.7)
					(thickness 0.15)
				)
				(justify right bottom mirror)
			)
		)
		(property "Datasheet" "https://www.kemet.com/en/us/capacitors/product/C0402C470J5GACTU.html"
			(at 0 0 90)
			(layer "F.Fab")
			(hide yes)
			(effects
				(font
					(size 1.27 1.27)
					(thickness 0.15)
				)
			)
		)
		(property "Description" "SMD Multilayer Ceramic Capacitor, 47 pF, 50 V, 0402 [1005 Metric], ± 5%, C0G / NP0, C Series KEMET"
			(at 0 0 90)
			(layer "F.Fab")
			(hide yes)
			(effects
				(font
					(size 1.27 1.27)
					(thickness 0.15)
				)
			)
		)
		(property "Author" "Antmicro"
			(at 228.7 -65.7 0)
			(layer "B.Fab")
			(hide yes)
			(effects
				(font
					(size 1 1)
					(thickness 0.15)
				)
				(justify mirror)
			)
		)
		(property "Dielectric" "C0G"
			(at 228.7 -65.7 0)
			(layer "B.Fab")
			(hide yes)
			(effects
				(font
					(size 1 1)
					(thickness 0.15)
				)
				(justify mirror)
			)
		)
		(property "License" "Apache-2.0"
			(at 228.7 -65.7 0)
			(layer "B.Fab")
			(hide yes)
			(effects
				(font
					(size 1 1)
					(thickness 0.15)
				)
				(justify mirror)
			)
		)
		(property "MPN" "C0402C470J5GACTU"
			(at 228.7 -65.7 0)
			(layer "B.Fab")
			(hide yes)
			(effects
				(font
					(size 1 1)
					(thickness 0.15)
				)
				(justify mirror)
			)
		)
		(property "Manufacturer" "KEMET"
			(at 228.7 -65.7 0)
			(layer "B.Fab")
			(hide yes)
			(effects
				(font
					(size 1 1)
					(thickness 0.15)
				)
				(justify mirror)
			)
		)
		(property "Val" "47p"
			(at 228.7 -65.7 0)
			(layer "B.Fab")
			(hide yes)
			(effects
				(font
					(size 1 1)
					(thickness 0.15)
				)
				(justify mirror)
			)
		)
		(property "Voltage" ""
			(at 228.7 -65.7 0)
			(layer "B.Fab")
			(hide yes)
			(effects
				(font
					(size 1 1)
					(thickness 0.15)
				)
				(justify mirror)
			)
		)
		(sheetname "/Peripherals/")
		(sheetfile "peripherals.kicad_sch")
		(attr smd)
		(fp_rect
			(start -0.925 0.47)
			(end 0.925 -0.47)
			(stroke
				(width 0.05)
				(type default)
			)
			(fill no)
			(layer "B.CrtYd")
		)
		(fp_line
			(start 0.504 -0.248)
			(end -0.494 -0.248)
			(stroke
				(width 0.15)
				(type solid)
			)
			(layer "B.Fab")
		)
		(fp_line
			(start -0.494 -0.248)
			(end -0.494 0.25)
			(stroke
				(width 0.15)
				(type solid)
			)
			(layer "B.Fab")
		)
		(fp_line
			(start 0.504 0.25)
			(end 0.504 -0.248)
			(stroke
				(width 0.15)
				(type solid)
			)
			(layer "B.Fab")
		)
		(fp_line
			(start -0.494 0.25)
			(end 0.504 0.25)
			(stroke
				(width 0.15)
				(type solid)
			)
			(layer "B.Fab")
		)
		(fp_text user "Author: Antmicro"
			(at -0.939 -3.399 270)
			(layer "B.Fab")
			(effects
				(font
					(size 0.7 0.7)
					(thickness 0.15)
				)
				(justify left bottom mirror)
			)
		)
		(fp_text user "${REFERENCE}"
			(at -0.939 -4.599 270)
			(layer "B.Fab")
			(effects
				(font
					(size 0.7 0.7)
					(thickness 0.15)
				)
				(justify left bottom mirror)
			)
		)
		(fp_text user "License: Apache-2.0"
			(at -0.939 -5.799 270)
			(layer "B.Fab")
			(effects
				(font
					(size 0.7 0.7)
					(thickness 0.15)
				)
				(justify left bottom mirror)
			)
		)
		(pad "1" smd roundrect
			(at -0.48 0 90)
			(size 0.59 0.64)
			(layers "B.Cu" "B.Mask" "B.Paste")
			(roundrect_rratio 0.25)
			(net 1 "GND")
			(pintype "passive")
		)
		(pad "2" smd roundrect
			(at 0.48 0 90)
			(size 0.59 0.64)
			(layers "B.Cu" "B.Mask" "B.Paste")
			(roundrect_rratio 0.25)
			(net 360 "/Peripherals/USB_DN")
			(pintype "passive")
		)
	)
	(footprint "antmicro-footprints:C_0402_1005Metric"
		(layer "B.Cu")
		(at 136.02 56.37 180)
		(descr "Capacitor SMD 0402")
		(tags "capacitor SMD 0402")
		(property "Reference" "C6"
			(at -0.41 -1.37 0)
			(layer "B.SilkS")
			(effects
				(font
					(size 0.65 0.65)
					(thickness 0.15)
				)
				(justify left bottom mirror)
			)
		)
		(property "Value" "C_100n_0402"
			(at 0 -1.4 0)
			(layer "B.Fab")
			(hide yes)
			(effects
				(font
					(size 0.7 0.7)
					(thickness 0.15)
				)
				(justify left bottom mirror)
			)
		)
		(property "Datasheet" "https://www.murata.com/products/productdetail?partno=GRM155R61H104KE14%23"
			(at 0 0 180)
			(layer "F.Fab")
			(hide yes)
			(effects
				(font
					(size 1.27 1.27)
					(thickness 0.15)
				)
			)
		)
		(property "Description" "SMD Multilayer Ceramic Capacitor, 0.1 µF, 50 V, 0402 [1005 Metric], ± 10%, X5R, GRM Series"
			(at 0 0 180)
			(layer "F.Fab")
			(hide yes)
			(effects
				(font
					(size 1.27 1.27)
					(thickness 0.15)
				)
			)
		)
		(property "Author" "Antmicro"
			(at 272.04 112.74 0)
			(layer "B.Fab")
			(hide yes)
			(effects
				(font
					(size 1 1)
					(thickness 0.15)
				)
				(justify mirror)
			)
		)
		(property "Dielectric" "X5R"
			(at 272.04 112.74 0)
			(layer "B.Fab")
			(hide yes)
			(effects
				(font
					(size 1 1)
					(thickness 0.15)
				)
				(justify mirror)
			)
		)
		(property "License" "Apache-2.0"
			(at 272.04 112.74 0)
			(layer "B.Fab")
			(hide yes)
			(effects
				(font
					(size 1 1)
					(thickness 0.15)
				)
				(justify mirror)
			)
		)
		(property "MPN" "GRM155R61H104KE14D"
			(at 272.04 112.74 0)
			(layer "B.Fab")
			(hide yes)
			(effects
				(font
					(size 1 1)
					(thickness 0.15)
				)
				(justify mirror)
			)
		)
		(property "Manufacturer" "Murata"
			(at 272.04 112.74 0)
			(layer "B.Fab")
			(hide yes)
			(effects
				(font
					(size 1 1)
					(thickness 0.15)
				)
				(justify mirror)
			)
		)
		(property "Val" "100n"
			(at 272.04 112.74 0)
			(layer "B.Fab")
			(hide yes)
			(effects
				(font
					(size 1 1)
					(thickness 0.15)
				)
				(justify mirror)
			)
		)
		(property "Voltage" "50V"
			(at 272.04 112.74 0)
			(layer "B.Fab")
			(hide yes)
			(effects
				(font
					(size 1 1)
					(thickness 0.15)
				)
				(justify mirror)
			)
		)
		(sheetname "/Power Supply/")
		(sheetfile "supply.kicad_sch")
		(attr smd)
		(fp_rect
			(start -0.925 0.47)
			(end 0.925 -0.47)
			(stroke
				(width 0.05)
				(type default)
			)
			(fill no)
			(layer "B.CrtYd")
		)
		(fp_line
			(start 0.504 0.25)
			(end 0.504 -0.248)
			(stroke
				(width 0.15)
				(type solid)
			)
			(layer "B.Fab")
		)
		(fp_line
			(start 0.504 -0.248)
			(end -0.494 -0.248)
			(stroke
				(width 0.15)
				(type solid)
			)
			(layer "B.Fab")
		)
		(fp_line
			(start -0.494 0.25)
			(end 0.504 0.25)
			(stroke
				(width 0.15)
				(type solid)
			)
			(layer "B.Fab")
		)
		(fp_line
			(start -0.494 -0.248)
			(end -0.494 0.25)
			(stroke
				(width 0.15)
				(type solid)
			)
			(layer "B.Fab")
		)
		(fp_text user "License: Apache-2.0"
			(at -0.939 -5.799 0)
			(layer "B.Fab")
			(effects
				(font
					(size 0.7 0.7)
					(thickness 0.15)
				)
				(justify left bottom mirror)
			)
		)
		(fp_text user "Author: Antmicro"
			(at -0.939 -3.399 0)
			(layer "B.Fab")
			(effects
				(font
					(size 0.7 0.7)
					(thickness 0.15)
				)
				(justify left bottom mirror)
			)
		)
		(fp_text user "${REFERENCE}"
			(at -0.939 -4.599 0)
			(layer "B.Fab")
			(effects
				(font
					(size 0.7 0.7)
					(thickness 0.15)
				)
				(justify left bottom mirror)
			)
		)
		(pad "1" smd roundrect
			(at -0.48 0 180)
			(size 0.59 0.64)
			(layers "B.Cu" "B.Mask" "B.Paste")
			(roundrect_rratio 0.25)
			(net 1 "GND")
			(pintype "passive")
		)
		(pad "2" smd roundrect
			(at 0.48 0 180)
			(size 0.59 0.64)
			(layers "B.Cu" "B.Mask" "B.Paste")
			(roundrect_rratio 0.25)
			(net 5 "Vref")
			(pintype "passive")
		)
	)
	(footprint "antmicro-footprints:R_Array_4x0402"
		(layer "B.Cu")
		(at 124.56 62.74 -90)
		(property "Reference" "R44"
			(at -1 1.13 90)
			(layer "B.SilkS")
			(effects
				(font
					(size 0.65 0.65)
					(thickness 0.15)
				)
				(justify left bottom mirror)
			)
		)
		(property "Value" "R_4x51R_0402_array"
			(at -1.5 -2 90)
			(layer "B.Fab")
			(hide yes)
			(effects
				(font
					(size 0.7 0.7)
					(thickness 0.15)
				)
				(justify left bottom mirror)
			)
		)
		(property "Datasheet" "http://industrial.panasonic.com/cdbs/www-data/pdf/AOC0000/AOC0000C14.pdf"
			(at 0 0 270)
			(layer "F.Fab")
			(hide yes)
			(effects
				(font
					(size 1.27 1.27)
					(thickness 0.15)
				)
			)
		)
		(property "Description" "Fixed Network Resistor, 51 ohm, Isolated, 4 Resistors, 0804 [2010 Metric], Convex, ± 5%"
			(at 0 0 270)
			(layer "F.Fab")
			(hide yes)
			(effects
				(font
					(size 1.27 1.27)
					(thickness 0.15)
				)
			)
		)
		(property "Author" "Antmicro"
			(at 61.82 187.3 0)
			(layer "B.Fab")
			(hide yes)
			(effects
				(font
					(size 1 1)
					(thickness 0.15)
				)
				(justify mirror)
			)
		)
		(property "License" "Apache-2.0"
			(at 61.82 187.3 0)
			(layer "B.Fab")
			(hide yes)
			(effects
				(font
					(size 1 1)
					(thickness 0.15)
				)
				(justify mirror)
			)
		)
		(property "MPN" "EXB28V510JX"
			(at 61.82 187.3 0)
			(layer "B.Fab")
			(hide yes)
			(effects
				(font
					(size 1 1)
					(thickness 0.15)
				)
				(justify mirror)
			)
		)
		(property "Manufacturer" "Panasonic"
			(at 61.82 187.3 0)
			(layer "B.Fab")
			(hide yes)
			(effects
				(font
					(size 1 1)
					(thickness 0.15)
				)
				(justify mirror)
			)
		)
		(property "Val" "R_4x51R_0402"
			(at 61.82 187.3 0)
			(layer "B.Fab")
			(hide yes)
			(effects
				(font
					(size 1 1)
					(thickness 0.15)
				)
				(justify mirror)
			)
		)
		(sheetname "/DDR3/")
		(sheetfile "ddr3.kicad_sch")
		(attr smd)
		(fp_line
			(start -1.17 0.5)
			(end -1.17 -0.498)
			(stroke
				(width 0.15)
				(type solid)
			)
			(layer "B.SilkS")
		)
		(fp_line
			(start 1.167 -0.498)
			(end 1.167 0.5)
			(stroke
				(width 0.15)
				(type solid)
			)
			(layer "B.SilkS")
		)
		(fp_rect
			(start -1.2 0.9)
			(end 1.2 -0.9)
			(stroke
				(width 0.05)
				(type solid)
			)
			(fill no)
			(layer "B.CrtYd")
		)
		(fp_line
			(start -1 0.5)
			(end 0.998 0.5)
			(stroke
				(width 0.15)
				(type solid)
			)
			(layer "B.Fab")
		)
		(fp_line
			(start 0.998 0.5)
			(end 0.998 -0.498)
			(stroke
				(width 0.15)
				(type solid)
			)
			(layer "B.Fab")
		)
		(fp_line
			(start -1 -0.498)
			(end -1 0.5)
			(stroke
				(width 0.15)
				(type solid)
			)
			(layer "B.Fab")
		)
		(fp_line
			(start 0.998 -0.498)
			(end -1 -0.498)
			(stroke
				(width 0.15)
				(type solid)
			)
			(layer "B.Fab")
		)
		(pad "1" smd roundrect
			(at -0.802 -0.45 270)
			(size 0.4 0.5)
			(layers "B.Cu" "B.Mask" "B.Paste")
			(roundrect_rratio 0.25)
			(net 157 "/DDR3/DDR3_BA0")
			(pinfunction "R1.1")
			(pintype "passive")
		)
		(pad "2" smd roundrect
			(at -0.272 -0.45 270)
			(size 0.4 0.5)
			(layers "B.Cu" "B.Mask" "B.Paste")
			(roundrect_rratio 0.25)
			(net 167 "/DDR3/DDR3_BA2")
			(pinfunction "R2.1")
			(pintype "passive")
		)
		(pad "3" smd roundrect
			(at 0.27 -0.45 270)
			(size 0.4 0.5)
			(layers "B.Cu" "B.Mask" "B.Paste")
			(roundrect_rratio 0.25)
			(net 168 "/DDR3/~{DDR3_CS}")
			(pinfunction "R3.1")
			(pintype "passive")
		)
		(pad "4" smd roundrect
			(at 0.8 -0.45 270)
			(size 0.4 0.5)
			(layers "B.Cu" "B.Mask" "B.Paste")
			(roundrect_rratio 0.25)
			(net 163 "/DDR3/~{DDR3_WE}")
			(pinfunction "R4.1")
			(pintype "passive")
		)
		(pad "5" smd roundrect
			(at 0.8 0.452 270)
			(size 0.4 0.5)
			(layers "B.Cu" "B.Mask" "B.Paste")
			(roundrect_rratio 0.25)
			(net 6 "Vtt")
			(pinfunction "R4.2")
			(pintype "passive")
		)
		(pad "6" smd roundrect
			(at 0.27 0.452 270)
			(size 0.4 0.5)
			(layers "B.Cu" "B.Mask" "B.Paste")
			(roundrect_rratio 0.25)
			(net 6 "Vtt")
			(pinfunction "R3.2")
			(pintype "passive")
		)
		(pad "7" smd roundrect
			(at -0.272 0.452 270)
			(size 0.4 0.5)
			(layers "B.Cu" "B.Mask" "B.Paste")
			(roundrect_rratio 0.25)
			(net 6 "Vtt")
			(pinfunction "R2.2")
			(pintype "passive")
		)
		(pad "8" smd roundrect
			(at -0.802 0.452 270)
			(size 0.4 0.5)
			(layers "B.Cu" "B.Mask" "B.Paste")
			(roundrect_rratio 0.25)
			(net 6 "Vtt")
			(pinfunction "R1.2")
			(pintype "passive")
		)
	)
	(footprint "antmicro-footprints:C_0402_1005Metric"
		(layer "B.Cu")
		(at 149.5 83.75 -90)
		(descr "Capacitor SMD 0402")
		(tags "capacitor SMD 0402")
		(property "Reference" "C122"
			(at -1.31 -1.33 90)
			(layer "B.SilkS")
			(effects
				(font
					(size 0.65 0.65)
					(thickness 0.15)
				)
				(justify left bottom mirror)
			)
		)
		(property "Value" "C_100n_0402"
			(at 0 -1.4 90)
			(layer "B.Fab")
			(hide yes)
			(effects
				(font
					(size 0.7 0.7)
					(thickness 0.15)
				)
				(justify left bottom mirror)
			)
		)
		(property "Datasheet" "https://www.murata.com/products/productdetail?partno=GRM155R61H104KE14%23"
			(at 0 0 270)
			(layer "F.Fab")
			(hide yes)
			(effects
				(font
					(size 1.27 1.27)
					(thickness 0.15)
				)
			)
		)
		(property "Description" "SMD Multilayer Ceramic Capacitor, 0.1 µF, 50 V, 0402 [1005 Metric], ± 10%, X5R, GRM Series"
			(at 0 0 270)
			(layer "F.Fab")
			(hide yes)
			(effects
				(font
					(size 1.27 1.27)
					(thickness 0.15)
				)
			)
		)
		(property "Author" "Antmicro"
			(at 65.75 233.25 0)
			(layer "B.Fab")
			(hide yes)
			(effects
				(font
					(size 1 1)
					(thickness 0.15)
				)
				(justify mirror)
			)
		)
		(property "Dielectric" "X5R"
			(at 65.75 233.25 0)
			(layer "B.Fab")
			(hide yes)
			(effects
				(font
					(size 1 1)
					(thickness 0.15)
				)
				(justify mirror)
			)
		)
		(property "License" "Apache-2.0"
			(at 65.75 233.25 0)
			(layer "B.Fab")
			(hide yes)
			(effects
				(font
					(size 1 1)
					(thickness 0.15)
				)
				(justify mirror)
			)
		)
		(property "MPN" "GRM155R61H104KE14D"
			(at 65.75 233.25 0)
			(layer "B.Fab")
			(hide yes)
			(effects
				(font
					(size 1 1)
					(thickness 0.15)
				)
				(justify mirror)
			)
		)
		(property "Manufacturer" "Murata"
			(at 65.75 233.25 0)
			(layer "B.Fab")
			(hide yes)
			(effects
				(font
					(size 1 1)
					(thickness 0.15)
				)
				(justify mirror)
			)
		)
		(property "Val" "100n"
			(at 65.75 233.25 0)
			(layer "B.Fab")
			(hide yes)
			(effects
				(font
					(size 1 1)
					(thickness 0.15)
				)
				(justify mirror)
			)
		)
		(property "Voltage" "50V"
			(at 65.75 233.25 0)
			(layer "B.Fab")
			(hide yes)
			(effects
				(font
					(size 1 1)
					(thickness 0.15)
				)
				(justify mirror)
			)
		)
		(sheetname "/Peripherals/")
		(sheetfile "peripherals.kicad_sch")
		(attr smd)
		(fp_rect
			(start -0.925 0.47)
			(end 0.925 -0.47)
			(stroke
				(width 0.05)
				(type default)
			)
			(fill no)
			(layer "B.CrtYd")
		)
		(fp_line
			(start -0.494 0.25)
			(end 0.504 0.25)
			(stroke
				(width 0.15)
				(type solid)
			)
			(layer "B.Fab")
		)
		(fp_line
			(start 0.504 0.25)
			(end 0.504 -0.248)
			(stroke
				(width 0.15)
				(type solid)
			)
			(layer "B.Fab")
		)
		(fp_line
			(start -0.494 -0.248)
			(end -0.494 0.25)
			(stroke
				(width 0.15)
				(type solid)
			)
			(layer "B.Fab")
		)
		(fp_line
			(start 0.504 -0.248)
			(end -0.494 -0.248)
			(stroke
				(width 0.15)
				(type solid)
			)
			(layer "B.Fab")
		)
		(fp_text user "Author: Antmicro"
			(at -0.939 -3.399 90)
			(layer "B.Fab")
			(effects
				(font
					(size 0.7 0.7)
					(thickness 0.15)
				)
				(justify left bottom mirror)
			)
		)
		(fp_text user "${REFERENCE}"
			(at -0.939 -4.599 90)
			(layer "B.Fab")
			(effects
				(font
					(size 0.7 0.7)
					(thickness 0.15)
				)
				(justify left bottom mirror)
			)
		)
		(fp_text user "License: Apache-2.0"
			(at -0.939 -5.799 90)
			(layer "B.Fab")
			(effects
				(font
					(size 0.7 0.7)
					(thickness 0.15)
				)
				(justify left bottom mirror)
			)
		)
		(pad "1" smd roundrect
			(at -0.48 0 270)
			(size 0.59 0.64)
			(layers "B.Cu" "B.Mask" "B.Paste")
			(roundrect_rratio 0.25)
			(net 1 "GND")
			(pintype "passive")
		)
		(pad "2" smd roundrect
			(at 0.48 0 270)
			(size 0.59 0.64)
			(layers "B.Cu" "B.Mask" "B.Paste")
			(roundrect_rratio 0.25)
			(net 325 "USB_POWER_IN")
			(pintype "passive")
		)
	)
	(footprint "antmicro-footprints:C_0201"
		(layer "B.Cu")
		(at 127.48 92.99 45)
		(descr "Capacitor SMD 0201")
		(tags "capacitor SMD 0201")
		(property "Reference" "C100"
			(at 1.227351 -14.874512 45)
			(layer "B.SilkS")
			(effects
				(font
					(size 0.65 0.65)
					(thickness 0.15)
				)
				(justify right bottom mirror)
			)
		)
		(property "Value" "C_100n_0201"
			(at 0 -1.399999 45)
			(layer "B.Fab")
			(hide yes)
			(effects
				(font
					(size 0.7 0.7)
					(thickness 0.15)
				)
				(justify right bottom mirror)
			)
		)
		(property "Datasheet" "https://www.yageo.com/en/Chart/Download/pdf/CC0201KRX6S5BB104"
			(at 0 0 45)
			(layer "F.Fab")
			(hide yes)
			(effects
				(font
					(size 1.27 1.27)
					(thickness 0.15)
				)
			)
		)
		(property "Description" "SMD Multilayer Ceramic Capacitor, 0.1 µF, 6.3 V, 0201 [0603 Metric], ± 10%, X6S, CC Series"
			(at 0 0 45)
			(layer "F.Fab")
			(hide yes)
			(effects
				(font
					(size 1.27 1.27)
					(thickness 0.15)
				)
			)
		)
		(property "Author" "Antmicro"
			(at 103.091887 -62.905832 0)
			(layer "B.Fab")
			(hide yes)
			(effects
				(font
					(size 1 1)
					(thickness 0.15)
				)
				(justify mirror)
			)
		)
		(property "Dielectric" ""
			(at 103.091887 -62.905832 0)
			(layer "B.Fab")
			(hide yes)
			(effects
				(font
					(size 1 1)
					(thickness 0.15)
				)
				(justify mirror)
			)
		)
		(property "License" "Apache-2.0"
			(at 103.091887 -62.905832 0)
			(layer "B.Fab")
			(hide yes)
			(effects
				(font
					(size 1 1)
					(thickness 0.15)
				)
				(justify mirror)
			)
		)
		(property "MPN" "CC0201KRX6S5BB104"
			(at 103.091887 -62.905832 0)
			(layer "B.Fab")
			(hide yes)
			(effects
				(font
					(size 1 1)
					(thickness 0.15)
				)
				(justify mirror)
			)
		)
		(property "Manufacturer" "YAGEO"
			(at 103.091887 -62.905832 0)
			(layer "B.Fab")
			(hide yes)
			(effects
				(font
					(size 1 1)
					(thickness 0.15)
				)
				(justify mirror)
			)
		)
		(property "Val" "100n"
			(at 103.091887 -62.905832 0)
			(layer "B.Fab")
			(hide yes)
			(effects
				(font
					(size 1 1)
					(thickness 0.15)
				)
				(justify mirror)
			)
		)
		(property "Voltage" ""
			(at 103.091887 -62.905832 0)
			(layer "B.Fab")
			(hide yes)
			(effects
				(font
					(size 1 1)
					(thickness 0.15)
				)
				(justify mirror)
			)
		)
		(property "Public" "False"
			(at 0 0 45)
			(unlocked yes)
			(layer "B.Fab")
			(hide yes)
			(effects
				(font
					(size 1 1)
					(thickness 0.15)
				)
				(justify mirror)
			)
		)
		(sheetname "/FPGA Power/")
		(sheetfile "FPGA_Power.kicad_sch")
		(attr smd)
		(fp_poly
			(pts
				(xy -0.7 0.35) (xy 0.7 0.35) (xy 0.7 -0.35) (xy -0.7 -0.35)
			)
			(stroke
				(width 0.05)
				(type default)
			)
			(fill no)
			(layer "B.CrtYd")
		)
		(fp_poly
			(pts
				(xy 0.3 -0.15) (xy -0.301 -0.15) (xy -0.301 0.149) (xy 0.3 0.149)
			)
			(stroke
				(width 0.15)
				(type solid)
			)
			(fill no)
			(layer "B.Fab")
		)
		(fp_text user "License: Apache-2.0"
			(at -0.72 -4.4 225)
			(layer "B.Fab")
			(effects
				(font
					(size 0.7 0.7)
					(thickness 0.15)
				)
				(justify left bottom mirror)
			)
		)
		(fp_text user "${REFERENCE}"
			(at -0.72 -3.4 225)
			(layer "B.Fab")
			(effects
				(font
					(size 0.7 0.7)
					(thickness 0.15)
				)
				(justify left bottom mirror)
			)
		)
		(fp_text user "Author: Antmicro"
			(at -0.72 -5.400001 225)
			(layer "B.Fab")
			(effects
				(font
					(size 0.7 0.7)
					(thickness 0.15)
				)
				(justify left bottom mirror)
			)
		)
		(pad "" smd roundrect
			(at -0.349 0.002 45)
			(size 0.318 0.36)
			(layers "B.Paste")
			(roundrect_rratio 0.25)
		)
		(pad "" smd roundrect
			(at 0.341 0.002 45)
			(size 0.318 0.36)
			(layers "B.Paste")
			(roundrect_rratio 0.25)
		)
		(pad "1" smd roundrect
			(at -0.321 0.002 45)
			(size 0.46 0.4)
			(layers "B.Cu" "B.Mask")
			(roundrect_rratio 0.25)
			(net 1 "GND")
			(pintype "passive")
		)
		(pad "2" smd roundrect
			(at 0.32 0.002 45)
			(size 0.46 0.4)
			(layers "B.Cu" "B.Mask")
			(roundrect_rratio 0.25)
			(net 10 "/FPGA Power/VCC_AUXA")
			(pintype "passive")
		)
	)
	(footprint "antmicro-footprints:TP_SMD_0.75mm"
		(layer "B.Cu")
		(at 102.19 88.95 90)
		(property "Reference" "TP34"
			(at -0.59 0.44 90)
			(layer "B.SilkS")
			(effects
				(font
					(size 0.65 0.65)
					(thickness 0.15)
				)
				(justify left bottom mirror)
			)
		)
		(property "Value" "TP_0.75mm_SMD"
			(at 0 -1.2 90)
			(layer "B.Fab")
			(hide yes)
			(effects
				(font
					(size 0.7 0.7)
					(thickness 0.15)
				)
				(justify right bottom mirror)
			)
		)
		(property "Description" "SMT test point"
			(at 0 0 90)
			(layer "F.Fab")
			(hide yes)
			(effects
				(font
					(size 1.27 1.27)
					(thickness 0.15)
				)
			)
		)
		(property "Author" "Antmicro"
			(at 191.14 -13.24 0)
			(layer "B.Fab")
			(hide yes)
			(effects
				(font
					(size 1 1)
					(thickness 0.15)
				)
				(justify mirror)
			)
		)
		(property "License" "Apache-2.0"
			(at 191.14 -13.24 0)
			(layer "B.Fab")
			(hide yes)
			(effects
				(font
					(size 1 1)
					(thickness 0.15)
				)
				(justify mirror)
			)
		)
		(property "MPN" ""
			(at 191.14 -13.24 0)
			(layer "B.Fab")
			(hide yes)
			(effects
				(font
					(size 1 1)
					(thickness 0.15)
				)
				(justify mirror)
			)
		)
		(property "Manufacturer" ""
			(at 191.14 -13.24 0)
			(layer "B.Fab")
			(hide yes)
			(effects
				(font
					(size 1 1)
					(thickness 0.15)
				)
				(justify mirror)
			)
		)
		(sheetname "/SDI/")
		(sheetfile "sdi.kicad_sch")
		(attr exclude_from_pos_files)
		(fp_circle
			(center 0 0)
			(end 0.475 0)
			(stroke
				(width 0.05)
				(type default)
			)
			(fill no)
			(layer "B.CrtYd")
		)
		(fp_text user "License: Apache-2.0"
			(at -0.4 -5.101 270)
			(layer "B.Fab")
			(effects
				(font
					(size 0.7 0.7)
					(thickness 0.15)
				)
				(justify left bottom mirror)
			)
		)
		(fp_text user "Author: Antmicro"
			(at -0.4 -3.901 270)
			(layer "B.Fab")
			(effects
				(font
					(size 0.7 0.7)
					(thickness 0.15)
				)
				(justify left bottom mirror)
			)
		)
		(fp_text user "${REFERENCE}"
			(at -0.4 -2.7 270)
			(layer "B.Fab")
			(effects
				(font
					(size 0.7 0.7)
					(thickness 0.15)
				)
				(justify left bottom mirror)
			)
		)
		(pad "1" smd circle
			(at 0 0 90)
			(size 0.75 0.75)
			(layers "B.Cu" "B.Mask")
			(net 208 "/SDI/JTAG{slash}~{HOST}")
			(pinfunction "1")
			(pintype "passive")
		)
	)
	(footprint "antmicro-footprints:C_0402_1005Metric"
		(layer "B.Cu")
		(at 91.62 72.96 90)
		(descr "Capacitor SMD 0402")
		(tags "capacitor SMD 0402")
		(property "Reference" "C55"
			(at 3.02 0.81 270)
			(layer "B.SilkS")
			(effects
				(font
					(size 0.65 0.65)
					(thickness 0.15)
				)
				(justify left bottom mirror)
			)
		)
		(property "Value" "C_47n_0402"
			(at 0 -1.4 270)
			(layer "B.Fab")
			(hide yes)
			(effects
				(font
					(size 0.7 0.7)
					(thickness 0.15)
				)
				(justify left bottom mirror)
			)
		)
		(property "Datasheet" "https://www.murata.com/en-us/products/productdetail?partno=GRM155R61C473KA01%23"
			(at 0 0 90)
			(layer "F.Fab")
			(hide yes)
			(effects
				(font
					(size 1.27 1.27)
					(thickness 0.15)
				)
			)
		)
		(property "Description" "SMD Multilayer Ceramic Capacitor, 47000 pF, 16 V, 0402 [1005 Metric], ± 10%, X5R, MC"
			(at 0 0 90)
			(layer "F.Fab")
			(hide yes)
			(effects
				(font
					(size 1.27 1.27)
					(thickness 0.15)
				)
			)
		)
		(property "Author" "Antmicro"
			(at 164.58 -18.66 0)
			(layer "B.Fab")
			(hide yes)
			(effects
				(font
					(size 1 1)
					(thickness 0.15)
				)
				(justify mirror)
			)
		)
		(property "Dielectric" ""
			(at 164.58 -18.66 0)
			(layer "B.Fab")
			(hide yes)
			(effects
				(font
					(size 1 1)
					(thickness 0.15)
				)
				(justify mirror)
			)
		)
		(property "License" "Apache-2.0"
			(at 164.58 -18.66 0)
			(layer "B.Fab")
			(hide yes)
			(effects
				(font
					(size 1 1)
					(thickness 0.15)
				)
				(justify mirror)
			)
		)
		(property "MPN" "GRM155R61C473KA01D"
			(at 164.58 -18.66 0)
			(layer "B.Fab")
			(hide yes)
			(effects
				(font
					(size 1 1)
					(thickness 0.15)
				)
				(justify mirror)
			)
		)
		(property "Manufacturer" "Murata"
			(at 164.58 -18.66 0)
			(layer "B.Fab")
			(hide yes)
			(effects
				(font
					(size 1 1)
					(thickness 0.15)
				)
				(justify mirror)
			)
		)
		(property "Val" "47n"
			(at 164.58 -18.66 0)
			(layer "B.Fab")
			(hide yes)
			(effects
				(font
					(size 1 1)
					(thickness 0.15)
				)
				(justify mirror)
			)
		)
		(property "Voltage" ""
			(at 164.58 -18.66 0)
			(layer "B.Fab")
			(hide yes)
			(effects
				(font
					(size 1 1)
					(thickness 0.15)
				)
				(justify mirror)
			)
		)
		(sheetname "/SDI/")
		(sheetfile "sdi.kicad_sch")
		(attr smd)
		(fp_rect
			(start -0.925 0.47)
			(end 0.925 -0.47)
			(stroke
				(width 0.05)
				(type default)
			)
			(fill no)
			(layer "B.CrtYd")
		)
		(fp_line
			(start 0.504 -0.248)
			(end -0.494 -0.248)
			(stroke
				(width 0.15)
				(type solid)
			)
			(layer "B.Fab")
		)
		(fp_line
			(start -0.494 -0.248)
			(end -0.494 0.25)
			(stroke
				(width 0.15)
				(type solid)
			)
			(layer "B.Fab")
		)
		(fp_line
			(start 0.504 0.25)
			(end 0.504 -0.248)
			(stroke
				(width 0.15)
				(type solid)
			)
			(layer "B.Fab")
		)
		(fp_line
			(start -0.494 0.25)
			(end 0.504 0.25)
			(stroke
				(width 0.15)
				(type solid)
			)
			(layer "B.Fab")
		)
		(fp_text user "License: Apache-2.0"
			(at -0.939 -5.799 270)
			(layer "B.Fab")
			(effects
				(font
					(size 0.7 0.7)
					(thickness 0.15)
				)
				(justify left bottom mirror)
			)
		)
		(fp_text user "Author: Antmicro"
			(at -0.939 -3.399 270)
			(layer "B.Fab")
			(effects
				(font
					(size 0.7 0.7)
					(thickness 0.15)
				)
				(justify left bottom mirror)
			)
		)
		(fp_text user "${REFERENCE}"
			(at -0.939 -4.599 270)
			(layer "B.Fab")
			(effects
				(font
					(size 0.7 0.7)
					(thickness 0.15)
				)
				(justify left bottom mirror)
			)
		)
		(pad "1" smd roundrect
			(at -0.48 0 90)
			(size 0.59 0.64)
			(layers "B.Cu" "B.Mask" "B.Paste")
			(roundrect_rratio 0.25)
			(net 156 "Net-(U15B-LF)")
			(pintype "passive")
		)
		(pad "2" smd roundrect
			(at 0.48 0 90)
			(size 0.59 0.64)
			(layers "B.Cu" "B.Mask" "B.Paste")
			(roundrect_rratio 0.25)
			(net 1 "GND")
			(pintype "passive")
		)
	)
	(footprint "antmicro-footprints:TP_SMD_0.75mm"
		(layer "B.Cu")
		(at 91.6392 88.95 90)
		(property "Reference" "TP40"
			(at -2.99 0.2908 90)
			(layer "B.SilkS")
			(effects
				(font
					(size 0.65 0.65)
					(thickness 0.15)
				)
				(justify right bottom mirror)
			)
		)
		(property "Value" "TP_0.75mm_SMD"
			(at 0 -1.2 90)
			(layer "B.Fab")
			(hide yes)
			(effects
				(font
					(size 0.7 0.7)
					(thickness 0.15)
				)
				(justify right bottom mirror)
			)
		)
		(property "Description" "SMT test point"
			(at 0 0 90)
			(layer "F.Fab")
			(hide yes)
			(effects
				(font
					(size 1.27 1.27)
					(thickness 0.15)
				)
			)
		)
		(property "Author" "Antmicro"
			(at 180.5892 -2.6892 0)
			(layer "B.Fab")
			(hide yes)
			(effects
				(font
					(size 1 1)
					(thickness 0.15)
				)
				(justify mirror)
			)
		)
		(property "License" "Apache-2.0"
			(at 180.5892 -2.6892 0)
			(layer "B.Fab")
			(hide yes)
			(effects
				(font
					(size 1 1)
					(thickness 0.15)
				)
				(justify mirror)
			)
		)
		(property "MPN" ""
			(at 180.5892 -2.6892 0)
			(layer "B.Fab")
			(hide yes)
			(effects
				(font
					(size 1 1)
					(thickness 0.15)
				)
				(justify mirror)
			)
		)
		(property "Manufacturer" ""
			(at 180.5892 -2.6892 0)
			(layer "B.Fab")
			(hide yes)
			(effects
				(font
					(size 1 1)
					(thickness 0.15)
				)
				(justify mirror)
			)
		)
		(sheetname "/SDI/")
		(sheetfile "sdi.kicad_sch")
		(attr exclude_from_pos_files)
		(fp_circle
			(center 0 0)
			(end 0.475 0)
			(stroke
				(width 0.05)
				(type default)
			)
			(fill no)
			(layer "B.CrtYd")
		)
		(fp_text user "${REFERENCE}"
			(at -0.4 -2.7 270)
			(layer "B.Fab")
			(effects
				(font
					(size 0.7 0.7)
					(thickness 0.15)
				)
				(justify left bottom mirror)
			)
		)
		(fp_text user "Author: Antmicro"
			(at -0.4 -3.901 270)
			(layer "B.Fab")
			(effects
				(font
					(size 0.7 0.7)
					(thickness 0.15)
				)
				(justify left bottom mirror)
			)
		)
		(fp_text user "License: Apache-2.0"
			(at -0.4 -5.101 270)
			(layer "B.Fab")
			(effects
				(font
					(size 0.7 0.7)
					(thickness 0.15)
				)
				(justify left bottom mirror)
			)
		)
		(pad "1" smd circle
			(at 0 0 90)
			(size 0.75 0.75)
			(layers "B.Cu" "B.Mask")
			(net 176 "/SDI/STANDBY")
			(pinfunction "1")
			(pintype "passive")
		)
	)
	(footprint "antmicro-footprints:C_0603_1608Metric"
		(layer "B.Cu")
		(at 134.78 91.12)
		(descr "Capacitor SMD 0603")
		(tags "capacitor 0603")
		(property "Reference" "C88"
			(at -1 -0.98 0)
			(layer "B.SilkS")
			(effects
				(font
					(size 0.65 0.65)
					(thickness 0.15)
				)
				(justify right bottom mirror)
			)
		)
		(property "Value" "C_10u_0603"
			(at 0 -1.6 0)
			(layer "B.Fab")
			(hide yes)
			(effects
				(font
					(size 0.7 0.7)
					(thickness 0.15)
				)
				(justify right bottom mirror)
			)
		)
		(property "Datasheet" "https://www.murata.com/products/productdetail?partno=GRM188R61A106KE69%23"
			(at 0 0 0)
			(layer "F.Fab")
			(hide yes)
			(effects
				(font
					(size 1.27 1.27)
					(thickness 0.15)
				)
			)
		)
		(property "Description" "SMD Multilayer Ceramic Capacitor, 10 µF, 10 V, 0603 [1608 Metric], ± 10%, X5R, GRM Series"
			(at 0 0 0)
			(layer "F.Fab")
			(hide yes)
			(effects
				(font
					(size 1.27 1.27)
					(thickness 0.15)
				)
			)
		)
		(property "Author" "Antmicro"
			(at 0 0 0)
			(layer "B.Fab")
			(hide yes)
			(effects
				(font
					(size 1 1)
					(thickness 0.15)
				)
				(justify mirror)
			)
		)
		(property "License" "Apache-2.0"
			(at 0 0 0)
			(layer "B.Fab")
			(hide yes)
			(effects
				(font
					(size 1 1)
					(thickness 0.15)
				)
				(justify mirror)
			)
		)
		(property "MPN" "GRM188R61A106KE69D"
			(at 0 0 0)
			(layer "B.Fab")
			(hide yes)
			(effects
				(font
					(size 1 1)
					(thickness 0.15)
				)
				(justify mirror)
			)
		)
		(property "Manufacturer" "Murata"
			(at 0 0 0)
			(layer "B.Fab")
			(hide yes)
			(effects
				(font
					(size 1 1)
					(thickness 0.15)
				)
				(justify mirror)
			)
		)
		(property "Val" "10u"
			(at 0 0 0)
			(layer "B.Fab")
			(hide yes)
			(effects
				(font
					(size 1 1)
					(thickness 0.15)
				)
				(justify mirror)
			)
		)
		(property "Voltage" ""
			(at 0 0 0)
			(layer "B.Fab")
			(hide yes)
			(effects
				(font
					(size 1 1)
					(thickness 0.15)
				)
				(justify mirror)
			)
		)
		(property "Dielectric" "template_dielectric"
			(at 0 0 0)
			(unlocked yes)
			(layer "B.Fab")
			(hide yes)
			(effects
				(font
					(size 1 1)
					(thickness 0.15)
				)
				(justify mirror)
			)
		)
		(sheetname "/FPGA Power/")
		(sheetfile "FPGA_Power.kicad_sch")
		(attr smd)
		(fp_line
			(start -0.15 -0.4)
			(end 0.15 -0.4)
			(stroke
				(width 0.15)
				(type solid)
			)
			(layer "B.SilkS")
		)
		(fp_line
			(start -0.15 0.4)
			(end 0.15 0.4)
			(stroke
				(width 0.15)
				(type solid)
			)
			(layer "B.SilkS")
		)
		(fp_rect
			(start -1.25 0.65)
			(end 1.25 -0.65)
			(stroke
				(width 0.05)
				(type solid)
			)
			(fill no)
			(layer "B.CrtYd")
		)
		(fp_rect
			(start -0.8 0.4)
			(end 0.8 -0.4)
			(stroke
				(width 0.15)
				(type solid)
			)
			(fill no)
			(layer "B.Fab")
		)
		(fp_text user "${REFERENCE}"
			(at -1.682 -3.895 180)
			(layer "B.Fab")
			(effects
				(font
					(size 0.7 0.7)
					(thickness 0.15)
				)
				(justify left bottom mirror)
			)
		)
		(fp_text user "Author: Antmicro"
			(at -1.682 -4.894 180)
			(layer "B.Fab")
			(effects
				(font
					(size 0.7 0.7)
					(thickness 0.15)
				)
				(justify left bottom mirror)
			)
		)
		(fp_text user "License: Apache-2.0"
			(at -1.682 -5.895 180)
			(layer "B.Fab")
			(effects
				(font
					(size 0.7 0.7)
					(thickness 0.15)
				)
				(justify left bottom mirror)
			)
		)
		(pad "1" smd roundrect
			(at -0.7 0)
			(size 0.8 1)
			(layers "B.Cu" "B.Mask" "B.Paste")
			(roundrect_rratio 0.2)
			(net 1 "GND")
			(pintype "passive")
		)
		(pad "2" smd roundrect
			(at 0.7 0)
			(size 0.8 1)
			(layers "B.Cu" "B.Mask" "B.Paste")
			(roundrect_rratio 0.2)
			(net 10 "/FPGA Power/VCC_AUXA")
			(pintype "passive")
		)
	)
	(footprint "antmicro-footprints:R_0402_1005Metric"
		(layer "B.Cu")
		(at 155.33 60.25 -90)
		(descr "Resistor SMD 0402")
		(tags "resistor SMD 0402")
		(property "Reference" "R11"
			(at -0.91 -1.3 90)
			(layer "B.SilkS")
			(effects
				(font
					(size 0.65 0.65)
					(thickness 0.15)
				)
				(justify left bottom mirror)
			)
		)
		(property "Value" "R_5k1_0402"
			(at 0 -1.4 90)
			(layer "B.Fab")
			(hide yes)
			(effects
				(font
					(size 0.7 0.7)
					(thickness 0.15)
				)
				(justify left bottom mirror)
			)
		)
		(property "Datasheet" "https://www.bourns.com/docs/product-datasheets/cr.pdf"
			(at 0 0 270)
			(layer "F.Fab")
			(hide yes)
			(effects
				(font
					(size 1.27 1.27)
					(thickness 0.15)
				)
			)
		)
		(property "Description" "SMD Chip Resistor, 5.1 kohm, ± 1%, 63 mW, 0402 [1005 Metric], Thick Film, General Purpose"
			(at 0 0 270)
			(layer "F.Fab")
			(hide yes)
			(effects
				(font
					(size 1.27 1.27)
					(thickness 0.15)
				)
			)
		)
		(property "Author" "Antmicro"
			(at 95.08 215.58 0)
			(layer "B.Fab")
			(hide yes)
			(effects
				(font
					(size 1 1)
					(thickness 0.15)
				)
				(justify mirror)
			)
		)
		(property "License" "Apache-2.0"
			(at 95.08 215.58 0)
			(layer "B.Fab")
			(hide yes)
			(effects
				(font
					(size 1 1)
					(thickness 0.15)
				)
				(justify mirror)
			)
		)
		(property "MPN" "CR0402-FX-5101GLF"
			(at 95.08 215.58 0)
			(layer "B.Fab")
			(hide yes)
			(effects
				(font
					(size 1 1)
					(thickness 0.15)
				)
				(justify mirror)
			)
		)
		(property "Manufacturer" "Bourns"
			(at 95.08 215.58 0)
			(layer "B.Fab")
			(hide yes)
			(effects
				(font
					(size 1 1)
					(thickness 0.15)
				)
				(justify mirror)
			)
		)
		(property "Tolerance" "1%"
			(at 95.08 215.58 0)
			(layer "B.Fab")
			(hide yes)
			(effects
				(font
					(size 1 1)
					(thickness 0.15)
				)
				(justify mirror)
			)
		)
		(property "Val" "5k1"
			(at 95.08 215.58 0)
			(layer "B.Fab")
			(hide yes)
			(effects
				(font
					(size 1 1)
					(thickness 0.15)
				)
				(justify mirror)
			)
		)
		(sheetname "/Peripherals/")
		(sheetfile "peripherals.kicad_sch")
		(attr smd)
		(fp_rect
			(start -0.925 0.47)
			(end 0.925 -0.47)
			(stroke
				(width 0.05)
				(type default)
			)
			(fill no)
			(layer "B.CrtYd")
		)
		(fp_rect
			(start -0.5 0.25)
			(end 0.5 -0.25)
			(stroke
				(width 0.15)
				(type solid)
			)
			(fill no)
			(layer "B.Fab")
		)
		(fp_text user "License: Apache-2.0"
			(at -0.95 -5.169 90)
			(layer "B.Fab")
			(effects
				(font
					(size 0.7 0.7)
					(thickness 0.15)
				)
				(justify left bottom mirror)
			)
		)
		(fp_text user "${REFERENCE}"
			(at -0.95 -3.168 90)
			(layer "B.Fab")
			(effects
				(font
					(size 0.7 0.7)
					(thickness 0.15)
				)
				(justify left bottom mirror)
			)
		)
		(fp_text user "Author: Antmicro"
			(at -0.95 -4.169 90)
			(layer "B.Fab")
			(effects
				(font
					(size 0.7 0.7)
					(thickness 0.15)
				)
				(justify left bottom mirror)
			)
		)
		(pad "1" smd roundrect
			(at -0.48 0 270)
			(size 0.59 0.64)
			(layers "B.Cu" "B.Mask" "B.Paste")
			(roundrect_rratio 0.25)
			(net 1 "GND")
			(pintype "passive")
		)
		(pad "2" smd roundrect
			(at 0.48 0 270)
			(size 0.59 0.64)
			(layers "B.Cu" "B.Mask" "B.Paste")
			(roundrect_rratio 0.25)
			(net 311 "Net-(J1-CC_{1})")
			(pintype "passive")
		)
	)
	(footprint "antmicro-footprints:R_Array_4x0402"
		(layer "B.Cu")
		(at 124.56 65.24 -90)
		(property "Reference" "R50"
			(at 0.1 1.03 90)
			(layer "B.SilkS")
			(effects
				(font
					(size 0.65 0.65)
					(thickness 0.15)
				)
				(justify left bottom mirror)
			)
		)
		(property "Value" "R_4x51R_0402_array"
			(at -1.5 -2 90)
			(layer "B.Fab")
			(hide yes)
			(effects
				(font
					(size 0.7 0.7)
					(thickness 0.15)
				)
				(justify left bottom mirror)
			)
		)
		(property "Datasheet" "http://industrial.panasonic.com/cdbs/www-data/pdf/AOC0000/AOC0000C14.pdf"
			(at 0 0 270)
			(layer "F.Fab")
			(hide yes)
			(effects
				(font
					(size 1.27 1.27)
					(thickness 0.15)
				)
			)
		)
		(property "Description" "Fixed Network Resistor, 51 ohm, Isolated, 4 Resistors, 0804 [2010 Metric], Convex, ± 5%"
			(at 0 0 270)
			(layer "F.Fab")
			(hide yes)
			(effects
				(font
					(size 1.27 1.27)
					(thickness 0.15)
				)
			)
		)
		(property "Author" "Antmicro"
			(at 59.32 189.8 0)
			(layer "B.Fab")
			(hide yes)
			(effects
				(font
					(size 1 1)
					(thickness 0.15)
				)
				(justify mirror)
			)
		)
		(property "License" "Apache-2.0"
			(at 59.32 189.8 0)
			(layer "B.Fab")
			(hide yes)
			(effects
				(font
					(size 1 1)
					(thickness 0.15)
				)
				(justify mirror)
			)
		)
		(property "MPN" "EXB28V510JX"
			(at 59.32 189.8 0)
			(layer "B.Fab")
			(hide yes)
			(effects
				(font
					(size 1 1)
					(thickness 0.15)
				)
				(justify mirror)
			)
		)
		(property "Manufacturer" "Panasonic"
			(at 59.32 189.8 0)
			(layer "B.Fab")
			(hide yes)
			(effects
				(font
					(size 1 1)
					(thickness 0.15)
				)
				(justify mirror)
			)
		)
		(property "Val" "R_4x51R_0402"
			(at 59.32 189.8 0)
			(layer "B.Fab")
			(hide yes)
			(effects
				(font
					(size 1 1)
					(thickness 0.15)
				)
				(justify mirror)
			)
		)
		(sheetname "/DDR3/")
		(sheetfile "ddr3.kicad_sch")
		(attr smd)
		(fp_line
			(start -1.17 0.5)
			(end -1.17 -0.498)
			(stroke
				(width 0.15)
				(type solid)
			)
			(layer "B.SilkS")
		)
		(fp_line
			(start 1.167 -0.498)
			(end 1.167 0.5)
			(stroke
				(width 0.15)
				(type solid)
			)
			(layer "B.SilkS")
		)
		(fp_rect
			(start -1.2 0.9)
			(end 1.2 -0.9)
			(stroke
				(width 0.05)
				(type solid)
			)
			(fill no)
			(layer "B.CrtYd")
		)
		(fp_line
			(start -1 0.5)
			(end 0.998 0.5)
			(stroke
				(width 0.15)
				(type solid)
			)
			(layer "B.Fab")
		)
		(fp_line
			(start 0.998 0.5)
			(end 0.998 -0.498)
			(stroke
				(width 0.15)
				(type solid)
			)
			(layer "B.Fab")
		)
		(fp_line
			(start -1 -0.498)
			(end -1 0.5)
			(stroke
				(width 0.15)
				(type solid)
			)
			(layer "B.Fab")
		)
		(fp_line
			(start 0.998 -0.498)
			(end -1 -0.498)
			(stroke
				(width 0.15)
				(type solid)
			)
			(layer "B.Fab")
		)
		(pad "1" smd roundrect
			(at -0.802 -0.45 270)
			(size 0.4 0.5)
			(layers "B.Cu" "B.Mask" "B.Paste")
			(roundrect_rratio 0.25)
			(net 166 "/DDR3/DDR3_ODT")
			(pinfunction "R1.1")
			(pintype "passive")
		)
		(pad "2" smd roundrect
			(at -0.272 -0.45 270)
			(size 0.4 0.5)
			(layers "B.Cu" "B.Mask" "B.Paste")
			(roundrect_rratio 0.25)
			(net 161 "/DDR3/~{DDR3_CAS}")
			(pinfunction "R2.1")
			(pintype "passive")
		)
		(pad "3" smd roundrect
			(at 0.27 -0.45 270)
			(size 0.4 0.5)
			(layers "B.Cu" "B.Mask" "B.Paste")
			(roundrect_rratio 0.25)
			(net 162 "/DDR3/~{DDR3_RAS}")
			(pinfunction "R3.1")
			(pintype "passive")
		)
		(pad "4" smd roundrect
			(at 0.8 -0.45 270)
			(size 0.4 0.5)
			(layers "B.Cu" "B.Mask" "B.Paste")
			(roundrect_rratio 0.25)
			(net 165 "/DDR3/DDR3_CKE")
			(pinfunction "R4.1")
			(pintype "passive")
		)
		(pad "5" smd roundrect
			(at 0.8 0.452 270)
			(size 0.4 0.5)
			(layers "B.Cu" "B.Mask" "B.Paste")
			(roundrect_rratio 0.25)
			(net 6 "Vtt")
			(pinfunction "R4.2")
			(pintype "passive")
		)
		(pad "6" smd roundrect
			(at 0.27 0.452 270)
			(size 0.4 0.5)
			(layers "B.Cu" "B.Mask" "B.Paste")
			(roundrect_rratio 0.25)
			(net 6 "Vtt")
			(pinfunction "R3.2")
			(pintype "passive")
		)
		(pad "7" smd roundrect
			(at -0.272 0.452 270)
			(size 0.4 0.5)
			(layers "B.Cu" "B.Mask" "B.Paste")
			(roundrect_rratio 0.25)
			(net 6 "Vtt")
			(pinfunction "R2.2")
			(pintype "passive")
		)
		(pad "8" smd roundrect
			(at -0.802 0.452 270)
			(size 0.4 0.5)
			(layers "B.Cu" "B.Mask" "B.Paste")
			(roundrect_rratio 0.25)
			(net 6 "Vtt")
			(pinfunction "R1.2")
			(pintype "passive")
		)
	)
	(footprint "antmicro-footprints:C_0603_1608Metric"
		(layer "B.Cu")
		(at 124.57 97.78 -90)
		(descr "Capacitor SMD 0603")
		(tags "capacitor 0603")
		(property "Reference" "C86"
			(at -0.89 0.99 90)
			(layer "B.SilkS")
			(effects
				(font
					(size 0.65 0.65)
					(thickness 0.15)
				)
				(justify left bottom mirror)
			)
		)
		(property "Value" "C_10u_0603"
			(at 0 -1.6 90)
			(layer "B.Fab")
			(hide yes)
			(effects
				(font
					(size 0.7 0.7)
					(thickness 0.15)
				)
				(justify left bottom mirror)
			)
		)
		(property "Datasheet" "https://www.murata.com/products/productdetail?partno=GRM188R61A106KE69%23"
			(at 0 0 270)
			(layer "F.Fab")
			(hide yes)
			(effects
				(font
					(size 1.27 1.27)
					(thickness 0.15)
				)
			)
		)
		(property "Description" "SMD Multilayer Ceramic Capacitor, 10 µF, 10 V, 0603 [1608 Metric], ± 10%, X5R, GRM Series"
			(at 0 0 270)
			(layer "F.Fab")
			(hide yes)
			(effects
				(font
					(size 1.27 1.27)
					(thickness 0.15)
				)
			)
		)
		(property "Author" "Antmicro"
			(at 26.74 222.3 0)
			(layer "B.Fab")
			(hide yes)
			(effects
				(font
					(size 1 1)
					(thickness 0.15)
				)
				(justify mirror)
			)
		)
		(property "License" "Apache-2.0"
			(at 26.74 222.3 0)
			(layer "B.Fab")
			(hide yes)
			(effects
				(font
					(size 1 1)
					(thickness 0.15)
				)
				(justify mirror)
			)
		)
		(property "MPN" "GRM188R61A106KE69D"
			(at 26.74 222.3 0)
			(layer "B.Fab")
			(hide yes)
			(effects
				(font
					(size 1 1)
					(thickness 0.15)
				)
				(justify mirror)
			)
		)
		(property "Manufacturer" "Murata"
			(at 26.74 222.3 0)
			(layer "B.Fab")
			(hide yes)
			(effects
				(font
					(size 1 1)
					(thickness 0.15)
				)
				(justify mirror)
			)
		)
		(property "Val" "10u"
			(at 26.74 222.3 0)
			(layer "B.Fab")
			(hide yes)
			(effects
				(font
					(size 1 1)
					(thickness 0.15)
				)
				(justify mirror)
			)
		)
		(property "Voltage" ""
			(at 26.74 222.3 0)
			(layer "B.Fab")
			(hide yes)
			(effects
				(font
					(size 1 1)
					(thickness 0.15)
				)
				(justify mirror)
			)
		)
		(property "Dielectric" "template_dielectric"
			(at 0 0 270)
			(unlocked yes)
			(layer "B.Fab")
			(hide yes)
			(effects
				(font
					(size 1 1)
					(thickness 0.15)
				)
				(justify mirror)
			)
		)
		(sheetname "/FPGA Power/")
		(sheetfile "FPGA_Power.kicad_sch")
		(attr smd)
		(fp_line
			(start -0.15 0.4)
			(end 0.15 0.4)
			(stroke
				(width 0.15)
				(type solid)
			)
			(layer "B.SilkS")
		)
		(fp_line
			(start -0.15 -0.4)
			(end 0.15 -0.4)
			(stroke
				(width 0.15)
				(type solid)
			)
			(layer "B.SilkS")
		)
		(fp_rect
			(start -1.25 0.65)
			(end 1.25 -0.65)
			(stroke
				(width 0.05)
				(type solid)
			)
			(fill no)
			(layer "B.CrtYd")
		)
		(fp_rect
			(start -0.8 0.4)
			(end 0.8 -0.4)
			(stroke
				(width 0.15)
				(type solid)
			)
			(fill no)
			(layer "B.Fab")
		)
		(fp_text user "Author: Antmicro"
			(at -1.682 -4.894 90)
			(layer "B.Fab")
			(effects
				(font
					(size 0.7 0.7)
					(thickness 0.15)
				)
				(justify left bottom mirror)
			)
		)
		(fp_text user "${REFERENCE}"
			(at -1.682 -3.895 90)
			(layer "B.Fab")
			(effects
				(font
					(size 0.7 0.7)
					(thickness 0.15)
				)
				(justify left bottom mirror)
			)
		)
		(fp_text user "License: Apache-2.0"
			(at -1.682 -5.895 90)
			(layer "B.Fab")
			(effects
				(font
					(size 0.7 0.7)
					(thickness 0.15)
				)
				(justify left bottom mirror)
			)
		)
		(pad "1" smd roundrect
			(at -0.7 0 270)
			(size 0.8 1)
			(layers "B.Cu" "B.Mask" "B.Paste")
			(roundrect_rratio 0.2)
			(net 1 "GND")
			(pintype "passive")
		)
		(pad "2" smd roundrect
			(at 0.7 0 270)
			(size 0.8 1)
			(layers "B.Cu" "B.Mask" "B.Paste")
			(roundrect_rratio 0.2)
			(net 4 "1V0_Power")
			(pintype "passive")
		)
	)
	(footprint "antmicro-footprints:C_0603_1608Metric"
		(layer "B.Cu")
		(at 130.51 57.35 90)
		(descr "Capacitor SMD 0603")
		(tags "capacitor 0603")
		(property "Reference" "C5"
			(at -0.69 -0.88 90)
			(layer "B.SilkS")
			(effects
				(font
					(size 0.65 0.65)
					(thickness 0.15)
				)
				(justify right bottom mirror)
			)
		)
		(property "Value" "C_22u_0603"
			(at 0 -1.6 90)
			(layer "B.Fab")
			(hide yes)
			(effects
				(font
					(size 0.7 0.7)
					(thickness 0.15)
				)
				(justify right bottom mirror)
			)
		)
		(property "Datasheet" "https://www.murata.com/products/productdetail?partno=GRM188R60J226MEA0%23"
			(at 0 0 90)
			(layer "F.Fab")
			(hide yes)
			(effects
				(font
					(size 1.27 1.27)
					(thickness 0.15)
				)
			)
		)
		(property "Description" "SMD Multilayer Ceramic Capacitor, 22 µF, 6.3 V, 0603 [1608 Metric], ± 20%, X5R, GRM Series"
			(at 0 0 90)
			(layer "F.Fab")
			(hide yes)
			(effects
				(font
					(size 1.27 1.27)
					(thickness 0.15)
				)
			)
		)
		(property "Author" "Antmicro"
			(at 187.86 -73.16 0)
			(layer "B.Fab")
			(hide yes)
			(effects
				(font
					(size 1 1)
					(thickness 0.15)
				)
				(justify mirror)
			)
		)
		(property "Dielectric" ""
			(at 187.86 -73.16 0)
			(layer "B.Fab")
			(hide yes)
			(effects
				(font
					(size 1 1)
					(thickness 0.15)
				)
				(justify mirror)
			)
		)
		(property "License" "Apache-2.0"
			(at 187.86 -73.16 0)
			(layer "B.Fab")
			(hide yes)
			(effects
				(font
					(size 1 1)
					(thickness 0.15)
				)
				(justify mirror)
			)
		)
		(property "MPN" "GRM188R60J226MEA0D"
			(at 187.86 -73.16 0)
			(layer "B.Fab")
			(hide yes)
			(effects
				(font
					(size 1 1)
					(thickness 0.15)
				)
				(justify mirror)
			)
		)
		(property "Manufacturer" "Murata"
			(at 187.86 -73.16 0)
			(layer "B.Fab")
			(hide yes)
			(effects
				(font
					(size 1 1)
					(thickness 0.15)
				)
				(justify mirror)
			)
		)
		(property "Val" "22u"
			(at 187.86 -73.16 0)
			(layer "B.Fab")
			(hide yes)
			(effects
				(font
					(size 1 1)
					(thickness 0.15)
				)
				(justify mirror)
			)
		)
		(property "Voltage" ""
			(at 187.86 -73.16 0)
			(layer "B.Fab")
			(hide yes)
			(effects
				(font
					(size 1 1)
					(thickness 0.15)
				)
				(justify mirror)
			)
		)
		(sheetname "/Power Supply/")
		(sheetfile "supply.kicad_sch")
		(attr smd)
		(fp_line
			(start -0.15 -0.4)
			(end 0.15 -0.4)
			(stroke
				(width 0.15)
				(type solid)
			)
			(layer "B.SilkS")
		)
		(fp_line
			(start -0.15 0.4)
			(end 0.15 0.4)
			(stroke
				(width 0.15)
				(type solid)
			)
			(layer "B.SilkS")
		)
		(fp_rect
			(start -1.25 0.65)
			(end 1.25 -0.65)
			(stroke
				(width 0.05)
				(type solid)
			)
			(fill no)
			(layer "B.CrtYd")
		)
		(fp_rect
			(start -0.8 0.4)
			(end 0.8 -0.4)
			(stroke
				(width 0.15)
				(type solid)
			)
			(fill no)
			(layer "B.Fab")
		)
		(fp_text user "License: Apache-2.0"
			(at -1.682 -5.895 270)
			(layer "B.Fab")
			(effects
				(font
					(size 0.7 0.7)
					(thickness 0.15)
				)
				(justify left bottom mirror)
			)
		)
		(fp_text user "Author: Antmicro"
			(at -1.682 -4.894 270)
			(layer "B.Fab")
			(effects
				(font
					(size 0.7 0.7)
					(thickness 0.15)
				)
				(justify left bottom mirror)
			)
		)
		(fp_text user "${REFERENCE}"
			(at -1.682 -3.895 270)
			(layer "B.Fab")
			(effects
				(font
					(size 0.7 0.7)
					(thickness 0.15)
				)
				(justify left bottom mirror)
			)
		)
		(pad "1" smd roundrect
			(at -0.7 0 90)
			(size 0.8 1)
			(layers "B.Cu" "B.Mask" "B.Paste")
			(roundrect_rratio 0.2)
			(net 1 "GND")
			(pintype "passive")
		)
		(pad "2" smd roundrect
			(at 0.7 0 90)
			(size 0.8 1)
			(layers "B.Cu" "B.Mask" "B.Paste")
			(roundrect_rratio 0.2)
			(net 60 "Net-(U1-DDQ)")
			(pintype "passive")
		)
	)
	(footprint "antmicro-footprints:R_0402_1005Metric"
		(layer "B.Cu")
		(at 162.43 102.865 90)
		(descr "Resistor SMD 0402")
		(tags "resistor SMD 0402")
		(property "Reference" "R2"
			(at 0.825 1.3 270)
			(layer "B.SilkS")
			(effects
				(font
					(size 0.65 0.65)
					(thickness 0.15)
				)
				(justify left bottom mirror)
			)
		)
		(property "Value" "R_10k_0402"
			(at 0 -1.4 270)
			(layer "B.Fab")
			(hide yes)
			(effects
				(font
					(size 0.7 0.7)
					(thickness 0.15)
				)
				(justify left bottom mirror)
			)
		)
		(property "Datasheet" "https://www.bourns.com/docs/product-datasheets/cr.pdf"
			(at 0 0 90)
			(layer "F.Fab")
			(hide yes)
			(effects
				(font
					(size 1.27 1.27)
					(thickness 0.15)
				)
			)
		)
		(property "Description" "SMD Chip Resistor, 10 kohm, ± 1%, 62.5 mW, 0402 [1005 Metric], Thick Film, General Purpose"
			(at 0 0 90)
			(layer "F.Fab")
			(hide yes)
			(effects
				(font
					(size 1.27 1.27)
					(thickness 0.15)
				)
			)
		)
		(property "Author" "Antmicro"
			(at 265.295 -59.565 0)
			(layer "B.Fab")
			(hide yes)
			(effects
				(font
					(size 1 1)
					(thickness 0.15)
				)
				(justify mirror)
			)
		)
		(property "License" "Apache-2.0"
			(at 265.295 -59.565 0)
			(layer "B.Fab")
			(hide yes)
			(effects
				(font
					(size 1 1)
					(thickness 0.15)
				)
				(justify mirror)
			)
		)
		(property "MPN" "CR0402-FX-1002GLF"
			(at 265.295 -59.565 0)
			(layer "B.Fab")
			(hide yes)
			(effects
				(font
					(size 1 1)
					(thickness 0.15)
				)
				(justify mirror)
			)
		)
		(property "Manufacturer" "Bourns"
			(at 265.295 -59.565 0)
			(layer "B.Fab")
			(hide yes)
			(effects
				(font
					(size 1 1)
					(thickness 0.15)
				)
				(justify mirror)
			)
		)
		(property "Tolerance" "1%"
			(at 265.295 -59.565 0)
			(layer "B.Fab")
			(hide yes)
			(effects
				(font
					(size 1 1)
					(thickness 0.15)
				)
				(justify mirror)
			)
		)
		(property "Val" "10k"
			(at 265.295 -59.565 0)
			(layer "B.Fab")
			(hide yes)
			(effects
				(font
					(size 1 1)
					(thickness 0.15)
				)
				(justify mirror)
			)
		)
		(sheetname "/Power Supply/")
		(sheetfile "supply.kicad_sch")
		(attr smd)
		(fp_rect
			(start -0.925 0.47)
			(end 0.925 -0.47)
			(stroke
				(width 0.05)
				(type default)
			)
			(fill no)
			(layer "B.CrtYd")
		)
		(fp_rect
			(start -0.5 0.25)
			(end 0.5 -0.25)
			(stroke
				(width 0.15)
				(type solid)
			)
			(fill no)
			(layer "B.Fab")
		)
		(fp_text user "${REFERENCE}"
			(at -0.95 -3.168 270)
			(layer "B.Fab")
			(effects
				(font
					(size 0.7 0.7)
					(thickness 0.15)
				)
				(justify left bottom mirror)
			)
		)
		(fp_text user "Author: Antmicro"
			(at -0.95 -4.169 270)
			(layer "B.Fab")
			(effects
				(font
					(size 0.7 0.7)
					(thickness 0.15)
				)
				(justify left bottom mirror)
			)
		)
		(fp_text user "License: Apache-2.0"
			(at -0.95 -5.169 270)
			(layer "B.Fab")
			(effects
				(font
					(size 0.7 0.7)
					(thickness 0.15)
				)
				(justify left bottom mirror)
			)
		)
		(pad "1" smd roundrect
			(at -0.48 0 90)
			(size 0.59 0.64)
			(layers "B.Cu" "B.Mask" "B.Paste")
			(roundrect_rratio 0.25)
			(net 141 "/Power Supply/VREF_0V45")
			(pintype "passive")
		)
		(pad "2" smd roundrect
			(at 0.48 0 90)
			(size 0.59 0.64)
			(layers "B.Cu" "B.Mask" "B.Paste")
			(roundrect_rratio 0.25)
			(net 14 "+5V")
			(pintype "passive")
		)
	)
	(footprint "antmicro-footprints:TSSOP-14_4.4x5mm_P0.65mm"
		(layer "B.Cu")
		(at 157.53 103.35 180)
		(descr "TSSOP, 14 Pin (JEDEC MO-153 Var AB-1 https://www.jedec.org/document_search?search_api_views_fulltext=MO-153), generated with kicad-footprint-generator ipc_gullwing_generator.py")
		(tags "TSSOP SO")
		(property "Reference" "U2"
			(at -0.9 -3.29 0)
			(layer "B.SilkS")
			(effects
				(font
					(size 0.65 0.65)
					(thickness 0.15)
				)
				(justify left mirror)
			)
		)
		(property "Value" "LM339_TSSOP_Split"
			(at -3.8 -4.3 0)
			(layer "B.Fab")
			(hide yes)
			(effects
				(font
					(size 0.7 0.7)
					(thickness 0.15)
				)
				(justify left bottom mirror)
			)
		)
		(property "Datasheet" "https://www.ti.com/lit/ds/symlink/lm339b.pdf?ts=1679641364820&ref_url=https%253A%252F%252Fwww.google.com%252F"
			(at 0 0 180)
			(layer "F.Fab")
			(hide yes)
			(effects
				(font
					(size 1.27 1.27)
					(thickness 0.15)
				)
			)
		)
		(property "Description" "Analogue Comparator, Differential, 4 Comparators, 300 ns, 2V to 36V, TSSOP, 14 Pins"
			(at 0 0 180)
			(layer "F.Fab")
			(hide yes)
			(effects
				(font
					(size 1.27 1.27)
					(thickness 0.15)
				)
			)
		)
		(property "Author" "Antmicro"
			(at 315.06 206.7 0)
			(layer "B.Fab")
			(hide yes)
			(effects
				(font
					(size 1 1)
					(thickness 0.15)
				)
				(justify mirror)
			)
		)
		(property "License" "Apache-2.0"
			(at 315.06 206.7 0)
			(layer "B.Fab")
			(hide yes)
			(effects
				(font
					(size 1 1)
					(thickness 0.15)
				)
				(justify mirror)
			)
		)
		(property "MPN" "LM339PW"
			(at 315.06 206.7 0)
			(layer "B.Fab")
			(hide yes)
			(effects
				(font
					(size 1 1)
					(thickness 0.15)
				)
				(justify mirror)
			)
		)
		(property "Manufacturer" "Texas Instruments"
			(at 315.06 206.7 0)
			(layer "B.Fab")
			(hide yes)
			(effects
				(font
					(size 1 1)
					(thickness 0.15)
				)
				(justify mirror)
			)
		)
		(sheetname "/Power Supply/")
		(sheetfile "supply.kicad_sch")
		(attr smd)
		(fp_line
			(start 2.3 2.3)
			(end 2.3 2.605)
			(stroke
				(width 0.15)
				(type solid)
			)
			(layer "B.SilkS")
		)
		(fp_line
			(start 2.3 -2.3)
			(end 2.3 -2.6)
			(stroke
				(width 0.15)
				(type solid)
			)
			(layer "B.SilkS")
		)
		(fp_line
			(start 2.3 -2.6)
			(end -2.3 -2.6)
			(stroke
				(width 0.15)
				(type solid)
			)
			(layer "B.SilkS")
		)
		(fp_line
			(start -2.3 2.61)
			(end 2.3 2.605)
			(stroke
				(width 0.15)
				(type solid)
			)
			(layer "B.SilkS")
		)
		(fp_line
			(start -2.3 2.61)
			(end -2.3 2.3)
			(stroke
				(width 0.15)
				(type solid)
			)
			(layer "B.SilkS")
		)
		(fp_line
			(start -2.3 -2.6)
			(end -2.3 -2.3)
			(stroke
				(width 0.15)
				(type solid)
			)
			(layer "B.SilkS")
		)
		(fp_line
			(start -2.9 2.3)
			(end -2.3 2.3)
			(stroke
				(width 0.15)
				(type solid)
			)
			(layer "B.SilkS")
		)
		(fp_line
			(start 3.7 2.6)
			(end -3.7 2.6)
			(stroke
				(width 0.05)
				(type solid)
			)
			(layer "B.CrtYd")
		)
		(fp_line
			(start 3.7 -2.6)
			(end 3.7 2.6)
			(stroke
				(width 0.05)
				(type solid)
			)
			(layer "B.CrtYd")
		)
		(fp_line
			(start -3.7 2.6)
			(end -3.7 -2.6)
			(stroke
				(width 0.05)
				(type solid)
			)
			(layer "B.CrtYd")
		)
		(fp_line
			(start -3.7 -2.6)
			(end 3.7 -2.6)
			(stroke
				(width 0.05)
				(type solid)
			)
			(layer "B.CrtYd")
		)
		(fp_line
			(start 2.2 2.5)
			(end 2.2 -2.499)
			(stroke
				(width 0.15)
				(type solid)
			)
			(layer "B.Fab")
		)
		(fp_line
			(start 2.2 -2.499)
			(end -2.202 -2.499)
			(stroke
				(width 0.15)
				(type solid)
			)
			(layer "B.Fab")
		)
		(fp_line
			(start -1.2 2.5)
			(end 2.2 2.5)
			(stroke
				(width 0.15)
				(type solid)
			)
			(layer "B.Fab")
		)
		(fp_line
			(start -2.202 1.5)
			(end -1.2 2.5)
			(stroke
				(width 0.15)
				(type solid)
			)
			(layer "B.Fab")
		)
		(fp_line
			(start -2.202 -2.499)
			(end -2.202 1.5)
			(stroke
				(width 0.15)
				(type solid)
			)
			(layer "B.Fab")
		)
		(fp_text user "."
			(at -3.7 2.8 0)
			(layer "B.SilkS")
			(effects
				(font
					(size 1 1)
					(thickness 0.15)
				)
				(justify left mirror)
			)
		)
		(pad "1" smd roundrect
			(at -2.863 1.95 180)
			(size 1.475 0.4)
			(layers "B.Cu" "B.Mask" "B.Paste")
			(roundrect_rratio 0.25)
			(net 58 "Net-(D1-A)")
			(pintype "output")
		)
		(pad "2" smd roundrect
			(at -2.863 1.301 180)
			(size 1.475 0.4)
			(layers "B.Cu" "B.Mask" "B.Paste")
			(roundrect_rratio 0.25)
			(net 58 "Net-(D1-A)")
			(pintype "output")
		)
		(pad "3" smd roundrect
			(at -2.863 0.652 180)
			(size 1.475 0.4)
			(layers "B.Cu" "B.Mask" "B.Paste")
			(roundrect_rratio 0.25)
			(net 14 "+5V")
			(pinfunction "V+")
			(pintype "power_in")
		)
		(pad "4" smd roundrect
			(at -2.863 0 180)
			(size 1.475 0.4)
			(layers "B.Cu" "B.Mask" "B.Paste")
			(roundrect_rratio 0.25)
			(net 141 "/Power Supply/VREF_0V45")
			(pintype "input")
		)
		(pad "5" smd roundrect
			(at -2.863 -0.65 180)
			(size 1.475 0.4)
			(layers "B.Cu" "B.Mask" "B.Paste")
			(roundrect_rratio 0.25)
			(net 2 "+3V3")
			(pintype "input")
		)
		(pad "6" smd roundrect
			(at -2.863 -1.3 180)
			(size 1.475 0.4)
			(layers "B.Cu" "B.Mask" "B.Paste")
			(roundrect_rratio 0.25)
			(net 141 "/Power Supply/VREF_0V45")
			(pintype "input")
		)
		(pad "7" smd roundrect
			(at -2.863 -1.949 180)
			(size 1.475 0.4)
			(layers "B.Cu" "B.Mask" "B.Paste")
			(roundrect_rratio 0.25)
			(net 4 "1V0_Power")
			(pintype "input")
		)
		(pad "8" smd roundrect
			(at 2.862 -1.949 180)
			(size 1.475 0.4)
			(layers "B.Cu" "B.Mask" "B.Paste")
			(roundrect_rratio 0.25)
			(net 141 "/Power Supply/VREF_0V45")
			(pintype "input")
		)
		(pad "9" smd roundrect
			(at 2.862 -1.3 180)
			(size 1.475 0.4)
			(layers "B.Cu" "B.Mask" "B.Paste")
			(roundrect_rratio 0.25)
			(net 49 "1V0_Clean")
			(pintype "input")
		)
		(pad "10" smd roundrect
			(at 2.862 -0.65 180)
			(size 1.475 0.4)
			(layers "B.Cu" "B.Mask" "B.Paste")
			(roundrect_rratio 0.25)
			(net 141 "/Power Supply/VREF_0V45")
			(pintype "input")
		)
		(pad "11" smd roundrect
			(at 2.862 0 180)
			(size 1.475 0.4)
			(layers "B.Cu" "B.Mask" "B.Paste")
			(roundrect_rratio 0.25)
			(net 50 "+1V8")
			(pintype "input")
		)
		(pad "12" smd roundrect
			(at 2.862 0.652 180)
			(size 1.475 0.4)
			(layers "B.Cu" "B.Mask" "B.Paste")
			(roundrect_rratio 0.25)
			(net 1 "GND")
			(pinfunction "V-")
			(pintype "power_in")
		)
		(pad "13" smd roundrect
			(at 2.862 1.301 180)
			(size 1.475 0.4)
			(layers "B.Cu" "B.Mask" "B.Paste")
			(roundrect_rratio 0.25)
			(net 58 "Net-(D1-A)")
			(pintype "output")
		)
		(pad "14" smd roundrect
			(at 2.862 1.95 180)
			(size 1.475 0.4)
			(layers "B.Cu" "B.Mask" "B.Paste")
			(roundrect_rratio 0.25)
			(net 58 "Net-(D1-A)")
			(pintype "output")
		)
	)
	(footprint "antmicro-footprints:C_0402_1005Metric"
		(layer "B.Cu")
		(at 97.1 71.7 -90)
		(descr "Capacitor SMD 0402")
		(tags "capacitor SMD 0402")
		(property "Reference" "C69"
			(at -0.96 0.67 90)
			(layer "B.SilkS")
			(effects
				(font
					(size 0.65 0.65)
					(thickness 0.15)
				)
				(justify left bottom mirror)
			)
		)
		(property "Value" "C_100n_0402"
			(at 0 -1.4 90)
			(layer "B.Fab")
			(hide yes)
			(effects
				(font
					(size 0.7 0.7)
					(thickness 0.15)
				)
				(justify left bottom mirror)
			)
		)
		(property "Datasheet" "https://www.murata.com/products/productdetail?partno=GRM155R61H104KE14%23"
			(at 0 0 270)
			(layer "F.Fab")
			(hide yes)
			(effects
				(font
					(size 1.27 1.27)
					(thickness 0.15)
				)
			)
		)
		(property "Description" "SMD Multilayer Ceramic Capacitor, 0.1 µF, 50 V, 0402 [1005 Metric], ± 10%, X5R, GRM Series"
			(at 0 0 270)
			(layer "F.Fab")
			(hide yes)
			(effects
				(font
					(size 1.27 1.27)
					(thickness 0.15)
				)
			)
		)
		(property "Author" "Antmicro"
			(at 25.4 168.8 0)
			(layer "B.Fab")
			(hide yes)
			(effects
				(font
					(size 1 1)
					(thickness 0.15)
				)
				(justify mirror)
			)
		)
		(property "Dielectric" "X5R"
			(at 25.4 168.8 0)
			(layer "B.Fab")
			(hide yes)
			(effects
				(font
					(size 1 1)
					(thickness 0.15)
				)
				(justify mirror)
			)
		)
		(property "License" "Apache-2.0"
			(at 25.4 168.8 0)
			(layer "B.Fab")
			(hide yes)
			(effects
				(font
					(size 1 1)
					(thickness 0.15)
				)
				(justify mirror)
			)
		)
		(property "MPN" "GRM155R61H104KE14D"
			(at 25.4 168.8 0)
			(layer "B.Fab")
			(hide yes)
			(effects
				(font
					(size 1 1)
					(thickness 0.15)
				)
				(justify mirror)
			)
		)
		(property "Manufacturer" "Murata"
			(at 25.4 168.8 0)
			(layer "B.Fab")
			(hide yes)
			(effects
				(font
					(size 1 1)
					(thickness 0.15)
				)
				(justify mirror)
			)
		)
		(property "Val" "100n"
			(at 25.4 168.8 0)
			(layer "B.Fab")
			(hide yes)
			(effects
				(font
					(size 1 1)
					(thickness 0.15)
				)
				(justify mirror)
			)
		)
		(property "Voltage" "50V"
			(at 25.4 168.8 0)
			(layer "B.Fab")
			(hide yes)
			(effects
				(font
					(size 1 1)
					(thickness 0.15)
				)
				(justify mirror)
			)
		)
		(sheetname "/SDI/")
		(sheetfile "sdi.kicad_sch")
		(attr smd)
		(fp_rect
			(start -0.925 0.47)
			(end 0.925 -0.47)
			(stroke
				(width 0.05)
				(type default)
			)
			(fill no)
			(layer "B.CrtYd")
		)
		(fp_line
			(start -0.494 0.25)
			(end 0.504 0.25)
			(stroke
				(width 0.15)
				(type solid)
			)
			(layer "B.Fab")
		)
		(fp_line
			(start 0.504 0.25)
			(end 0.504 -0.248)
			(stroke
				(width 0.15)
				(type solid)
			)
			(layer "B.Fab")
		)
		(fp_line
			(start -0.494 -0.248)
			(end -0.494 0.25)
			(stroke
				(width 0.15)
				(type solid)
			)
			(layer "B.Fab")
		)
		(fp_line
			(start 0.504 -0.248)
			(end -0.494 -0.248)
			(stroke
				(width 0.15)
				(type solid)
			)
			(layer "B.Fab")
		)
		(fp_text user "${REFERENCE}"
			(at -0.939 -4.599 90)
			(layer "B.Fab")
			(effects
				(font
					(size 0.7 0.7)
					(thickness 0.15)
				)
				(justify left bottom mirror)
			)
		)
		(fp_text user "Author: Antmicro"
			(at -0.939 -3.399 90)
			(layer "B.Fab")
			(effects
				(font
					(size 0.7 0.7)
					(thickness 0.15)
				)
				(justify left bottom mirror)
			)
		)
		(fp_text user "License: Apache-2.0"
			(at -0.939 -5.799 90)
			(layer "B.Fab")
			(effects
				(font
					(size 0.7 0.7)
					(thickness 0.15)
				)
				(justify left bottom mirror)
			)
		)
		(pad "1" smd roundrect
			(at -0.48 0 270)
			(size 0.59 0.64)
			(layers "B.Cu" "B.Mask" "B.Paste")
			(roundrect_rratio 0.25)
			(net 1 "GND")
			(pintype "passive")
		)
		(pad "2" smd roundrect
			(at 0.48 0 270)
			(size 0.59 0.64)
			(layers "B.Cu" "B.Mask" "B.Paste")
			(roundrect_rratio 0.25)
			(net 2 "+3V3")
			(pintype "passive")
		)
	)
	(footprint "antmicro-footprints:FB_0603_1608Metric"
		(layer "B.Cu")
		(at 129.94 99.63)
		(property "Reference" "FB3"
			(at 3.34 0.51 180)
			(layer "B.SilkS")
			(effects
				(font
					(size 0.65 0.65)
					(thickness 0.15)
				)
				(justify left bottom mirror)
			)
		)
		(property "Value" "FB_120Z_2A_0603"
			(at 0 -1.5 180)
			(layer "B.Fab")
			(hide yes)
			(effects
				(font
					(size 0.7 0.7)
					(thickness 0.15)
				)
				(justify left bottom mirror)
			)
		)
		(property "Datasheet" "https://www.murata.com/en-us/products/productdata/8796738650142/ENFA0003.pdf"
			(at 0 0 0)
			(layer "F.Fab")
			(hide yes)
			(effects
				(font
					(size 1.27 1.27)
					(thickness 0.15)
				)
			)
		)
		(property "Description" "Ferrite Bead, 0603 [1608 Metric], 120 ohm, 2 A, BLM18P, 0.05 ohm, ± 25%, DC power line"
			(at 0 0 0)
			(layer "F.Fab")
			(hide yes)
			(effects
				(font
					(size 1.27 1.27)
					(thickness 0.15)
				)
			)
		)
		(property "Author" "Antmicro"
			(at 0 0 0)
			(layer "B.Fab")
			(hide yes)
			(effects
				(font
					(size 1 1)
					(thickness 0.15)
				)
				(justify mirror)
			)
		)
		(property "License" "Apache-2.0"
			(at 0 0 0)
			(layer "B.Fab")
			(hide yes)
			(effects
				(font
					(size 1 1)
					(thickness 0.15)
				)
				(justify mirror)
			)
		)
		(property "MPN" "BLM18PG121SN1D"
			(at 0 0 0)
			(layer "B.Fab")
			(hide yes)
			(effects
				(font
					(size 1 1)
					(thickness 0.15)
				)
				(justify mirror)
			)
		)
		(property "Manufacturer" "Murata"
			(at 0 0 0)
			(layer "B.Fab")
			(hide yes)
			(effects
				(font
					(size 1 1)
					(thickness 0.15)
				)
				(justify mirror)
			)
		)
		(property "Val" "120Z/2A"
			(at 0 0 0)
			(unlocked yes)
			(layer "B.Fab")
			(hide yes)
			(effects
				(font
					(size 1 1)
					(thickness 0.15)
				)
				(justify mirror)
			)
		)
		(property "Current" ""
			(at 0 0 0)
			(unlocked yes)
			(layer "B.Fab")
			(hide yes)
			(effects
				(font
					(size 1 1)
					(thickness 0.15)
				)
				(justify mirror)
			)
		)
		(sheetname "/FPGA Power/")
		(sheetfile "FPGA_Power.kicad_sch")
		(attr smd)
		(fp_line
			(start -0.15 -0.4)
			(end 0.15 -0.4)
			(stroke
				(width 0.15)
				(type solid)
			)
			(layer "B.SilkS")
		)
		(fp_line
			(start -0.15 0.4)
			(end 0.15 0.4)
			(stroke
				(width 0.15)
				(type solid)
			)
			(layer "B.SilkS")
		)
		(fp_rect
			(start -1.25 0.65)
			(end 1.25 -0.65)
			(stroke
				(width 0.05)
				(type solid)
			)
			(fill no)
			(layer "B.CrtYd")
		)
		(fp_line
			(start -0.803 -0.406)
			(end -0.803 0.408)
			(stroke
				(width 0.15)
				(type solid)
			)
			(layer "B.Fab")
		)
		(fp_line
			(start 0.8 -0.406)
			(end -0.803 -0.406)
			(stroke
				(width 0.15)
				(type solid)
			)
			(layer "B.Fab")
		)
		(fp_line
			(start 0.8 0.408)
			(end -0.803 0.408)
			(stroke
				(width 0.15)
				(type solid)
			)
			(layer "B.Fab")
		)
		(fp_line
			(start 0.8 0.408)
			(end 0.8 -0.406)
			(stroke
				(width 0.15)
				(type solid)
			)
			(layer "B.Fab")
		)
		(fp_text user "${REFERENCE}"
			(at -1.653 -4.6 180)
			(layer "B.Fab")
			(effects
				(font
					(size 0.7 0.7)
					(thickness 0.15)
				)
				(justify left bottom mirror)
			)
		)
		(fp_text user "Author: Antmicro"
			(at -1.653 -3.162 180)
			(layer "B.Fab")
			(effects
				(font
					(size 0.7 0.7)
					(thickness 0.15)
				)
				(justify left bottom mirror)
			)
		)
		(fp_text user "License: Apache-2.0"
			(at -1.653 -5.9 180)
			(layer "B.Fab")
			(effects
				(font
					(size 0.7 0.7)
					(thickness 0.15)
				)
				(justify left bottom mirror)
			)
		)
		(pad "1" smd roundrect
			(at -0.7 0)
			(size 0.8 1)
			(layers "B.Cu" "B.Mask" "B.Paste")
			(roundrect_rratio 0.2)
			(net 11 "/FPGA Power/VCC_DPHY")
			(pintype "passive")
		)
		(pad "2" smd roundrect
			(at 0.7 0)
			(size 0.8 1)
			(layers "B.Cu" "B.Mask" "B.Paste")
			(roundrect_rratio 0.2)
			(net 49 "1V0_Clean")
			(pintype "passive")
		)
	)
	(footprint "antmicro-footprints:TP_SMD_0.75mm"
		(layer "B.Cu")
		(at 100.69 88.95 90)
		(property "Reference" "TP28"
			(at -0.59 0.34 90)
			(layer "B.SilkS")
			(effects
				(font
					(size 0.65 0.65)
					(thickness 0.15)
				)
				(justify left bottom mirror)
			)
		)
		(property "Value" "TP_0.75mm_SMD"
			(at 0 -1.2 90)
			(layer "B.Fab")
			(hide yes)
			(effects
				(font
					(size 0.7 0.7)
					(thickness 0.15)
				)
				(justify right bottom mirror)
			)
		)
		(property "Description" "SMT test point"
			(at 0 0 90)
			(layer "F.Fab")
			(hide yes)
			(effects
				(font
					(size 1.27 1.27)
					(thickness 0.15)
				)
			)
		)
		(property "Author" "Antmicro"
			(at 189.64 -11.74 0)
			(layer "B.Fab")
			(hide yes)
			(effects
				(font
					(size 1 1)
					(thickness 0.15)
				)
				(justify mirror)
			)
		)
		(property "License" "Apache-2.0"
			(at 189.64 -11.74 0)
			(layer "B.Fab")
			(hide yes)
			(effects
				(font
					(size 1 1)
					(thickness 0.15)
				)
				(justify mirror)
			)
		)
		(property "MPN" ""
			(at 189.64 -11.74 0)
			(layer "B.Fab")
			(hide yes)
			(effects
				(font
					(size 1 1)
					(thickness 0.15)
				)
				(justify mirror)
			)
		)
		(property "Manufacturer" ""
			(at 189.64 -11.74 0)
			(layer "B.Fab")
			(hide yes)
			(effects
				(font
					(size 1 1)
					(thickness 0.15)
				)
				(justify mirror)
			)
		)
		(sheetname "/SDI/")
		(sheetfile "sdi.kicad_sch")
		(attr exclude_from_pos_files)
		(fp_circle
			(center 0 0)
			(end 0.475 0)
			(stroke
				(width 0.05)
				(type default)
			)
			(fill no)
			(layer "B.CrtYd")
		)
		(fp_text user "License: Apache-2.0"
			(at -0.4 -5.101 270)
			(layer "B.Fab")
			(effects
				(font
					(size 0.7 0.7)
					(thickness 0.15)
				)
				(justify left bottom mirror)
			)
		)
		(fp_text user "${REFERENCE}"
			(at -0.4 -2.7 270)
			(layer "B.Fab")
			(effects
				(font
					(size 0.7 0.7)
					(thickness 0.15)
				)
				(justify left bottom mirror)
			)
		)
		(fp_text user "Author: Antmicro"
			(at -0.4 -3.901 270)
			(layer "B.Fab")
			(effects
				(font
					(size 0.7 0.7)
					(thickness 0.15)
				)
				(justify left bottom mirror)
			)
		)
		(pad "1" smd circle
			(at 0 0 90)
			(size 0.75 0.75)
			(layers "B.Cu" "B.Mask")
			(net 193 "/SDI/DVB_ASI")
			(pinfunction "1")
			(pintype "passive")
		)
	)
	(footprint "antmicro-footprints:C_0201"
		(layer "B.Cu")
		(at 129.1 91.9 180)
		(descr "Capacitor SMD 0201")
		(tags "capacitor SMD 0201")
		(property "Reference" "C58"
			(at 8.27 12.695736 0)
			(layer "B.SilkS")
			(effects
				(font
					(size 0.65 0.65)
					(thickness 0.15)
				)
				(justify left bottom mirror)
			)
		)
		(property "Value" "C_100n_0201"
			(at 0 -1.4 0)
			(layer "B.Fab")
			(hide yes)
			(effects
				(font
					(size 0.7 0.7)
					(thickness 0.15)
				)
				(justify left bottom mirror)
			)
		)
		(property "Datasheet" "https://www.yageo.com/en/Chart/Download/pdf/CC0201KRX6S5BB104"
			(at 0 0 180)
			(layer "F.Fab")
			(hide yes)
			(effects
				(font
					(size 1.27 1.27)
					(thickness 0.15)
				)
			)
		)
		(property "Description" "SMD Multilayer Ceramic Capacitor, 0.1 µF, 6.3 V, 0201 [0603 Metric], ± 10%, X6S, CC Series"
			(at 0 0 180)
			(layer "F.Fab")
			(hide yes)
			(effects
				(font
					(size 1.27 1.27)
					(thickness 0.15)
				)
			)
		)
		(property "Author" "Antmicro"
			(at 258.2 183.8 0)
			(layer "B.Fab")
			(hide yes)
			(effects
				(font
					(size 1 1)
					(thickness 0.15)
				)
				(justify mirror)
			)
		)
		(property "Dielectric" ""
			(at 258.2 183.8 0)
			(layer "B.Fab")
			(hide yes)
			(effects
				(font
					(size 1 1)
					(thickness 0.15)
				)
				(justify mirror)
			)
		)
		(property "License" "Apache-2.0"
			(at 258.2 183.8 0)
			(layer "B.Fab")
			(hide yes)
			(effects
				(font
					(size 1 1)
					(thickness 0.15)
				)
				(justify mirror)
			)
		)
		(property "MPN" "CC0201KRX6S5BB104"
			(at 258.2 183.8 0)
			(layer "B.Fab")
			(hide yes)
			(effects
				(font
					(size 1 1)
					(thickness 0.15)
				)
				(justify mirror)
			)
		)
		(property "Manufacturer" "YAGEO"
			(at 258.2 183.8 0)
			(layer "B.Fab")
			(hide yes)
			(effects
				(font
					(size 1 1)
					(thickness 0.15)
				)
				(justify mirror)
			)
		)
		(property "Val" "100n"
			(at 258.2 183.8 0)
			(layer "B.Fab")
			(hide yes)
			(effects
				(font
					(size 1 1)
					(thickness 0.15)
				)
				(justify mirror)
			)
		)
		(property "Voltage" ""
			(at 258.2 183.8 0)
			(layer "B.Fab")
			(hide yes)
			(effects
				(font
					(size 1 1)
					(thickness 0.15)
				)
				(justify mirror)
			)
		)
		(property "Public" "False"
			(at 0 0 180)
			(unlocked yes)
			(layer "B.Fab")
			(hide yes)
			(effects
				(font
					(size 1 1)
					(thickness 0.15)
				)
				(justify mirror)
			)
		)
		(sheetname "/SDI/")
		(sheetfile "sdi.kicad_sch")
		(attr smd)
		(fp_rect
			(start -0.7 0.35)
			(end 0.7 -0.35)
			(stroke
				(width 0.05)
				(type default)
			)
			(fill no)
			(layer "B.CrtYd")
		)
		(fp_rect
			(start 0.3 -0.15)
			(end -0.301 0.149)
			(stroke
				(width 0.15)
				(type solid)
			)
			(fill no)
			(layer "B.Fab")
		)
		(fp_text user "${REFERENCE}"
			(at -0.72 -3.4 0)
			(layer "B.Fab")
			(effects
				(font
					(size 0.7 0.7)
					(thickness 0.15)
				)
				(justify left bottom mirror)
			)
		)
		(fp_text user "Author: Antmicro"
			(at -0.72 -5.4 0)
			(layer "B.Fab")
			(effects
				(font
					(size 0.7 0.7)
					(thickness 0.15)
				)
				(justify left bottom mirror)
			)
		)
		(fp_text user "License: Apache-2.0"
			(at -0.72 -4.4 0)
			(layer "B.Fab")
			(effects
				(font
					(size 0.7 0.7)
					(thickness 0.15)
				)
				(justify left bottom mirror)
			)
		)
		(pad "" smd roundrect
			(at -0.349 0.002 180)
			(size 0.318 0.36)
			(layers "B.Paste")
			(roundrect_rratio 0.25)
		)
		(pad "" smd roundrect
			(at 0.341 0.002 180)
			(size 0.318 0.36)
			(layers "B.Paste")
			(roundrect_rratio 0.25)
		)
		(pad "1" smd roundrect
			(at -0.321 0.002 180)
			(size 0.46 0.4)
			(layers "B.Cu" "B.Mask")
			(roundrect_rratio 0.25)
			(net 1 "GND")
			(pintype "passive")
		)
		(pad "2" smd roundrect
			(at 0.32 0.002 180)
			(size 0.46 0.4)
			(layers "B.Cu" "B.Mask")
			(roundrect_rratio 0.25)
			(net 2 "+3V3")
			(pintype "passive")
		)
	)
	(footprint "antmicro-footprints:C_0402_1005Metric"
		(layer "B.Cu")
		(at 120.32 61.44 180)
		(descr "Capacitor SMD 0402")
		(tags "capacitor SMD 0402")
		(property "Reference" "C49"
			(at 0.99 -0.3 0)
			(layer "B.SilkS")
			(effects
				(font
					(size 0.65 0.65)
					(thickness 0.15)
				)
				(justify left bottom mirror)
			)
		)
		(property "Value" "C_100n_0402"
			(at 0 -1.4 0)
			(layer "B.Fab")
			(hide yes)
			(effects
				(font
					(size 0.7 0.7)
					(thickness 0.15)
				)
				(justify left bottom mirror)
			)
		)
		(property "Datasheet" "https://www.murata.com/products/productdetail?partno=GRM155R61H104KE14%23"
			(at 0 0 180)
			(layer "F.Fab")
			(hide yes)
			(effects
				(font
					(size 1.27 1.27)
					(thickness 0.15)
				)
			)
		)
		(property "Description" "SMD Multilayer Ceramic Capacitor, 0.1 µF, 50 V, 0402 [1005 Metric], ± 10%, X5R, GRM Series"
			(at 0 0 180)
			(layer "F.Fab")
			(hide yes)
			(effects
				(font
					(size 1.27 1.27)
					(thickness 0.15)
				)
			)
		)
		(property "Author" "Antmicro"
			(at 240.64 122.88 0)
			(layer "B.Fab")
			(hide yes)
			(effects
				(font
					(size 1 1)
					(thickness 0.15)
				)
				(justify mirror)
			)
		)
		(property "Dielectric" "X5R"
			(at 240.64 122.88 0)
			(layer "B.Fab")
			(hide yes)
			(effects
				(font
					(size 1 1)
					(thickness 0.15)
				)
				(justify mirror)
			)
		)
		(property "License" "Apache-2.0"
			(at 240.64 122.88 0)
			(layer "B.Fab")
			(hide yes)
			(effects
				(font
					(size 1 1)
					(thickness 0.15)
				)
				(justify mirror)
			)
		)
		(property "MPN" "GRM155R61H104KE14D"
			(at 240.64 122.88 0)
			(layer "B.Fab")
			(hide yes)
			(effects
				(font
					(size 1 1)
					(thickness 0.15)
				)
				(justify mirror)
			)
		)
		(property "Manufacturer" "Murata"
			(at 240.64 122.88 0)
			(layer "B.Fab")
			(hide yes)
			(effects
				(font
					(size 1 1)
					(thickness 0.15)
				)
				(justify mirror)
			)
		)
		(property "Val" "100n"
			(at 240.64 122.88 0)
			(layer "B.Fab")
			(hide yes)
			(effects
				(font
					(size 1 1)
					(thickness 0.15)
				)
				(justify mirror)
			)
		)
		(property "Voltage" "50V"
			(at 240.64 122.88 0)
			(layer "B.Fab")
			(hide yes)
			(effects
				(font
					(size 1 1)
					(thickness 0.15)
				)
				(justify mirror)
			)
		)
		(sheetname "/DDR3/")
		(sheetfile "ddr3.kicad_sch")
		(attr smd)
		(fp_rect
			(start -0.925 0.47)
			(end 0.925 -0.47)
			(stroke
				(width 0.05)
				(type default)
			)
			(fill no)
			(layer "B.CrtYd")
		)
		(fp_line
			(start 0.504 0.25)
			(end 0.504 -0.248)
			(stroke
				(width 0.15)
				(type solid)
			)
			(layer "B.Fab")
		)
		(fp_line
			(start 0.504 -0.248)
			(end -0.494 -0.248)
			(stroke
				(width 0.15)
				(type solid)
			)
			(layer "B.Fab")
		)
		(fp_line
			(start -0.494 0.25)
			(end 0.504 0.25)
			(stroke
				(width 0.15)
				(type solid)
			)
			(layer "B.Fab")
		)
		(fp_line
			(start -0.494 -0.248)
			(end -0.494 0.25)
			(stroke
				(width 0.15)
				(type solid)
			)
			(layer "B.Fab")
		)
		(fp_text user "Author: Antmicro"
			(at -0.939 -3.399 0)
			(layer "B.Fab")
			(effects
				(font
					(size 0.7 0.7)
					(thickness 0.15)
				)
				(justify left bottom mirror)
			)
		)
		(fp_text user "License: Apache-2.0"
			(at -0.939 -5.799 0)
			(layer "B.Fab")
			(effects
				(font
					(size 0.7 0.7)
					(thickness 0.15)
				)
				(justify left bottom mirror)
			)
		)
		(fp_text user "${REFERENCE}"
			(at -0.939 -4.599 0)
			(layer "B.Fab")
			(effects
				(font
					(size 0.7 0.7)
					(thickness 0.15)
				)
				(justify left bottom mirror)
			)
		)
		(pad "1" smd roundrect
			(at -0.48 0 180)
			(size 0.59 0.64)
			(layers "B.Cu" "B.Mask" "B.Paste")
			(roundrect_rratio 0.25)
			(net 5 "Vref")
			(pintype "passive")
		)
		(pad "2" smd roundrect
			(at 0.48 0 180)
			(size 0.59 0.64)
			(layers "B.Cu" "B.Mask" "B.Paste")
			(roundrect_rratio 0.25)
			(net 248 "+1V5")
			(pintype "passive")
		)
	)
	(footprint "antmicro-footprints:C_0402_1005Metric"
		(layer "B.Cu")
		(at 95.58 75.07 -90)
		(descr "Capacitor SMD 0402")
		(tags "capacitor SMD 0402")
		(property "Reference" "C70"
			(at -0.93 0.55 90)
			(layer "B.SilkS")
			(effects
				(font
					(size 0.65 0.65)
					(thickness 0.15)
				)
				(justify left bottom mirror)
			)
		)
		(property "Value" "C_100n_0402"
			(at 0 -1.4 90)
			(layer "B.Fab")
			(hide yes)
			(effects
				(font
					(size 0.7 0.7)
					(thickness 0.15)
				)
				(justify left bottom mirror)
			)
		)
		(property "Datasheet" "https://www.murata.com/products/productdetail?partno=GRM155R61H104KE14%23"
			(at 0 0 270)
			(layer "F.Fab")
			(hide yes)
			(effects
				(font
					(size 1.27 1.27)
					(thickness 0.15)
				)
			)
		)
		(property "Description" "SMD Multilayer Ceramic Capacitor, 0.1 µF, 50 V, 0402 [1005 Metric], ± 10%, X5R, GRM Series"
			(at 0 0 270)
			(layer "F.Fab")
			(hide yes)
			(effects
				(font
					(size 1.27 1.27)
					(thickness 0.15)
				)
			)
		)
		(property "Author" "Antmicro"
			(at 20.51 170.65 0)
			(layer "B.Fab")
			(hide yes)
			(effects
				(font
					(size 1 1)
					(thickness 0.15)
				)
				(justify mirror)
			)
		)
		(property "Dielectric" "X5R"
			(at 20.51 170.65 0)
			(layer "B.Fab")
			(hide yes)
			(effects
				(font
					(size 1 1)
					(thickness 0.15)
				)
				(justify mirror)
			)
		)
		(property "License" "Apache-2.0"
			(at 20.51 170.65 0)
			(layer "B.Fab")
			(hide yes)
			(effects
				(font
					(size 1 1)
					(thickness 0.15)
				)
				(justify mirror)
			)
		)
		(property "MPN" "GRM155R61H104KE14D"
			(at 20.51 170.65 0)
			(layer "B.Fab")
			(hide yes)
			(effects
				(font
					(size 1 1)
					(thickness 0.15)
				)
				(justify mirror)
			)
		)
		(property "Manufacturer" "Murata"
			(at 20.51 170.65 0)
			(layer "B.Fab")
			(hide yes)
			(effects
				(font
					(size 1 1)
					(thickness 0.15)
				)
				(justify mirror)
			)
		)
		(property "Val" "100n"
			(at 20.51 170.65 0)
			(layer "B.Fab")
			(hide yes)
			(effects
				(font
					(size 1 1)
					(thickness 0.15)
				)
				(justify mirror)
			)
		)
		(property "Voltage" "50V"
			(at 20.51 170.65 0)
			(layer "B.Fab")
			(hide yes)
			(effects
				(font
					(size 1 1)
					(thickness 0.15)
				)
				(justify mirror)
			)
		)
		(sheetname "/SDI/")
		(sheetfile "sdi.kicad_sch")
		(attr smd)
		(fp_rect
			(start -0.925 0.47)
			(end 0.925 -0.47)
			(stroke
				(width 0.05)
				(type default)
			)
			(fill no)
			(layer "B.CrtYd")
		)
		(fp_line
			(start -0.494 0.25)
			(end 0.504 0.25)
			(stroke
				(width 0.15)
				(type solid)
			)
			(layer "B.Fab")
		)
		(fp_line
			(start 0.504 0.25)
			(end 0.504 -0.248)
			(stroke
				(width 0.15)
				(type solid)
			)
			(layer "B.Fab")
		)
		(fp_line
			(start -0.494 -0.248)
			(end -0.494 0.25)
			(stroke
				(width 0.15)
				(type solid)
			)
			(layer "B.Fab")
		)
		(fp_line
			(start 0.504 -0.248)
			(end -0.494 -0.248)
			(stroke
				(width 0.15)
				(type solid)
			)
			(layer "B.Fab")
		)
		(fp_text user "${REFERENCE}"
			(at -0.939 -4.599 90)
			(layer "B.Fab")
			(effects
				(font
					(size 0.7 0.7)
					(thickness 0.15)
				)
				(justify left bottom mirror)
			)
		)
		(fp_text user "Author: Antmicro"
			(at -0.939 -3.399 90)
			(layer "B.Fab")
			(effects
				(font
					(size 0.7 0.7)
					(thickness 0.15)
				)
				(justify left bottom mirror)
			)
		)
		(fp_text user "License: Apache-2.0"
			(at -0.939 -5.799 90)
			(layer "B.Fab")
			(effects
				(font
					(size 0.7 0.7)
					(thickness 0.15)
				)
				(justify left bottom mirror)
			)
		)
		(pad "1" smd roundrect
			(at -0.48 0 270)
			(size 0.59 0.64)
			(layers "B.Cu" "B.Mask" "B.Paste")
			(roundrect_rratio 0.25)
			(net 1 "GND")
			(pintype "passive")
		)
		(pad "2" smd roundrect
			(at 0.48 0 270)
			(size 0.59 0.64)
			(layers "B.Cu" "B.Mask" "B.Paste")
			(roundrect_rratio 0.25)
			(net 3 "+1V2")
			(pintype "passive")
		)
	)
	(footprint "antmicro-footprints:TP_SMD_0.75mm"
		(layer "B.Cu")
		(at 95.44 88.2 90)
		(property "Reference" "TP43"
			(at 0.76 0.39 90)
			(layer "B.SilkS")
			(effects
				(font
					(size 0.65 0.65)
					(thickness 0.15)
				)
				(justify right bottom mirror)
			)
		)
		(property "Value" "TP_0.75mm_SMD"
			(at 0 -1.2 90)
			(layer "B.Fab")
			(hide yes)
			(effects
				(font
					(size 0.7 0.7)
					(thickness 0.15)
				)
				(justify right bottom mirror)
			)
		)
		(property "Description" "SMT test point"
			(at 0 0 90)
			(layer "F.Fab")
			(hide yes)
			(effects
				(font
					(size 1.27 1.27)
					(thickness 0.15)
				)
			)
		)
		(property "Author" "Antmicro"
			(at 183.64 -7.24 0)
			(layer "B.Fab")
			(hide yes)
			(effects
				(font
					(size 1 1)
					(thickness 0.15)
				)
				(justify mirror)
			)
		)
		(property "License" "Apache-2.0"
			(at 183.64 -7.24 0)
			(layer "B.Fab")
			(hide yes)
			(effects
				(font
					(size 1 1)
					(thickness 0.15)
				)
				(justify mirror)
			)
		)
		(property "MPN" ""
			(at 183.64 -7.24 0)
			(layer "B.Fab")
			(hide yes)
			(effects
				(font
					(size 1 1)
					(thickness 0.15)
				)
				(justify mirror)
			)
		)
		(property "Manufacturer" ""
			(at 183.64 -7.24 0)
			(layer "B.Fab")
			(hide yes)
			(effects
				(font
					(size 1 1)
					(thickness 0.15)
				)
				(justify mirror)
			)
		)
		(sheetname "/SDI/")
		(sheetfile "sdi.kicad_sch")
		(attr exclude_from_pos_files)
		(fp_circle
			(center 0 0)
			(end 0.475 0)
			(stroke
				(width 0.05)
				(type default)
			)
			(fill no)
			(layer "B.CrtYd")
		)
		(fp_text user "${REFERENCE}"
			(at -0.4 -2.7 270)
			(layer "B.Fab")
			(effects
				(font
					(size 0.7 0.7)
					(thickness 0.15)
				)
				(justify left bottom mirror)
			)
		)
		(fp_text user "Author: Antmicro"
			(at -0.4 -3.901 270)
			(layer "B.Fab")
			(effects
				(font
					(size 0.7 0.7)
					(thickness 0.15)
				)
				(justify left bottom mirror)
			)
		)
		(fp_text user "License: Apache-2.0"
			(at -0.4 -5.101 270)
			(layer "B.Fab")
			(effects
				(font
					(size 0.7 0.7)
					(thickness 0.15)
				)
				(justify left bottom mirror)
			)
		)
		(pad "1" smd circle
			(at 0 0 90)
			(size 0.75 0.75)
			(layers "B.Cu" "B.Mask")
			(net 181 "/SDI/SDOUT_TDO")
			(pinfunction "1")
			(pintype "passive")
		)
	)
	(footprint "antmicro-footprints:C_0603_1608Metric"
		(layer "B.Cu")
		(at 134.39 95.48)
		(descr "Capacitor SMD 0603")
		(tags "capacitor 0603")
		(property "Reference" "C90"
			(at -0.86 -0.84 0)
			(layer "B.SilkS")
			(effects
				(font
					(size 0.65 0.65)
					(thickness 0.15)
				)
				(justify right bottom mirror)
			)
		)
		(property "Value" "C_10u_0603"
			(at 0 -1.6 0)
			(layer "B.Fab")
			(hide yes)
			(effects
				(font
					(size 0.7 0.7)
					(thickness 0.15)
				)
				(justify right bottom mirror)
			)
		)
		(property "Datasheet" "https://www.murata.com/products/productdetail?partno=GRM188R61A106KE69%23"
			(at 0 0 0)
			(layer "F.Fab")
			(hide yes)
			(effects
				(font
					(size 1.27 1.27)
					(thickness 0.15)
				)
			)
		)
		(property "Description" "SMD Multilayer Ceramic Capacitor, 10 µF, 10 V, 0603 [1608 Metric], ± 10%, X5R, GRM Series"
			(at 0 0 0)
			(layer "F.Fab")
			(hide yes)
			(effects
				(font
					(size 1.27 1.27)
					(thickness 0.15)
				)
			)
		)
		(property "Author" "Antmicro"
			(at 0 0 0)
			(layer "B.Fab")
			(hide yes)
			(effects
				(font
					(size 1 1)
					(thickness 0.15)
				)
				(justify mirror)
			)
		)
		(property "License" "Apache-2.0"
			(at 0 0 0)
			(layer "B.Fab")
			(hide yes)
			(effects
				(font
					(size 1 1)
					(thickness 0.15)
				)
				(justify mirror)
			)
		)
		(property "MPN" "GRM188R61A106KE69D"
			(at 0 0 0)
			(layer "B.Fab")
			(hide yes)
			(effects
				(font
					(size 1 1)
					(thickness 0.15)
				)
				(justify mirror)
			)
		)
		(property "Manufacturer" "Murata"
			(at 0 0 0)
			(layer "B.Fab")
			(hide yes)
			(effects
				(font
					(size 1 1)
					(thickness 0.15)
				)
				(justify mirror)
			)
		)
		(property "Val" "10u"
			(at 0 0 0)
			(layer "B.Fab")
			(hide yes)
			(effects
				(font
					(size 1 1)
					(thickness 0.15)
				)
				(justify mirror)
			)
		)
		(property "Voltage" ""
			(at 0 0 0)
			(layer "B.Fab")
			(hide yes)
			(effects
				(font
					(size 1 1)
					(thickness 0.15)
				)
				(justify mirror)
			)
		)
		(property "Dielectric" "template_dielectric"
			(at 0 0 0)
			(unlocked yes)
			(layer "B.Fab")
			(hide yes)
			(effects
				(font
					(size 1 1)
					(thickness 0.15)
				)
				(justify mirror)
			)
		)
		(sheetname "/FPGA Power/")
		(sheetfile "FPGA_Power.kicad_sch")
		(attr smd)
		(fp_line
			(start -0.15 -0.4)
			(end 0.15 -0.4)
			(stroke
				(width 0.15)
				(type solid)
			)
			(layer "B.SilkS")
		)
		(fp_line
			(start -0.15 0.4)
			(end 0.15 0.4)
			(stroke
				(width 0.15)
				(type solid)
			)
			(layer "B.SilkS")
		)
		(fp_rect
			(start -1.25 0.65)
			(end 1.25 -0.65)
			(stroke
				(width 0.05)
				(type solid)
			)
			(fill no)
			(layer "B.CrtYd")
		)
		(fp_rect
			(start -0.8 0.4)
			(end 0.8 -0.4)
			(stroke
				(width 0.15)
				(type solid)
			)
			(fill no)
			(layer "B.Fab")
		)
		(fp_text user "${REFERENCE}"
			(at -1.682 -3.895 180)
			(layer "B.Fab")
			(effects
				(font
					(size 0.7 0.7)
					(thickness 0.15)
				)
				(justify left bottom mirror)
			)
		)
		(fp_text user "License: Apache-2.0"
			(at -1.682 -5.895 180)
			(layer "B.Fab")
			(effects
				(font
					(size 0.7 0.7)
					(thickness 0.15)
				)
				(justify left bottom mirror)
			)
		)
		(fp_text user "Author: Antmicro"
			(at -1.682 -4.894 180)
			(layer "B.Fab")
			(effects
				(font
					(size 0.7 0.7)
					(thickness 0.15)
				)
				(justify left bottom mirror)
			)
		)
		(pad "1" smd roundrect
			(at -0.7 0)
			(size 0.8 1)
			(layers "B.Cu" "B.Mask" "B.Paste")
			(roundrect_rratio 0.2)
			(net 1 "GND")
			(pintype "passive")
		)
		(pad "2" smd roundrect
			(at 0.7 0)
			(size 0.8 1)
			(layers "B.Cu" "B.Mask" "B.Paste")
			(roundrect_rratio 0.2)
			(net 12 "/FPGA Power/VCC_ADPHY")
			(pintype "passive")
		)
	)
	(footprint "antmicro-footprints:C_0201"
		(layer "B.Cu")
		(at 128.3 87.1 180)
		(descr "Capacitor SMD 0201")
		(tags "capacitor SMD 0201")
		(property "Reference" "C36"
			(at 8.47 12.295736 0)
			(layer "B.SilkS")
			(effects
				(font
					(size 0.65 0.65)
					(thickness 0.15)
				)
				(justify left bottom mirror)
			)
		)
		(property "Value" "C_100n_0201"
			(at 0 -1.4 0)
			(layer "B.Fab")
			(hide yes)
			(effects
				(font
					(size 0.7 0.7)
					(thickness 0.15)
				)
				(justify left bottom mirror)
			)
		)
		(property "Datasheet" "https://www.yageo.com/en/Chart/Download/pdf/CC0201KRX6S5BB104"
			(at 0 0 180)
			(layer "F.Fab")
			(hide yes)
			(effects
				(font
					(size 1.27 1.27)
					(thickness 0.15)
				)
			)
		)
		(property "Description" "SMD Multilayer Ceramic Capacitor, 0.1 µF, 6.3 V, 0201 [0603 Metric], ± 10%, X6S, CC Series"
			(at 0 0 180)
			(layer "F.Fab")
			(hide yes)
			(effects
				(font
					(size 1.27 1.27)
					(thickness 0.15)
				)
			)
		)
		(property "Author" "Antmicro"
			(at 256.6 174.2 0)
			(layer "B.Fab")
			(hide yes)
			(effects
				(font
					(size 1 1)
					(thickness 0.15)
				)
				(justify mirror)
			)
		)
		(property "Dielectric" ""
			(at 256.6 174.2 0)
			(layer "B.Fab")
			(hide yes)
			(effects
				(font
					(size 1 1)
					(thickness 0.15)
				)
				(justify mirror)
			)
		)
		(property "License" "Apache-2.0"
			(at 256.6 174.2 0)
			(layer "B.Fab")
			(hide yes)
			(effects
				(font
					(size 1 1)
					(thickness 0.15)
				)
				(justify mirror)
			)
		)
		(property "MPN" "CC0201KRX6S5BB104"
			(at 256.6 174.2 0)
			(layer "B.Fab")
			(hide yes)
			(effects
				(font
					(size 1 1)
					(thickness 0.15)
				)
				(justify mirror)
			)
		)
		(property "Manufacturer" "YAGEO"
			(at 256.6 174.2 0)
			(layer "B.Fab")
			(hide yes)
			(effects
				(font
					(size 1 1)
					(thickness 0.15)
				)
				(justify mirror)
			)
		)
		(property "Val" "100n"
			(at 256.6 174.2 0)
			(layer "B.Fab")
			(hide yes)
			(effects
				(font
					(size 1 1)
					(thickness 0.15)
				)
				(justify mirror)
			)
		)
		(property "Voltage" ""
			(at 256.6 174.2 0)
			(layer "B.Fab")
			(hide yes)
			(effects
				(font
					(size 1 1)
					(thickness 0.15)
				)
				(justify mirror)
			)
		)
		(property "Public" "False"
			(at 0 0 180)
			(unlocked yes)
			(layer "B.Fab")
			(hide yes)
			(effects
				(font
					(size 1 1)
					(thickness 0.15)
				)
				(justify mirror)
			)
		)
		(sheetname "/DDR3/")
		(sheetfile "ddr3.kicad_sch")
		(attr smd)
		(fp_rect
			(start -0.7 0.35)
			(end 0.7 -0.35)
			(stroke
				(width 0.05)
				(type default)
			)
			(fill no)
			(layer "B.CrtYd")
		)
		(fp_rect
			(start 0.3 -0.15)
			(end -0.301 0.149)
			(stroke
				(width 0.15)
				(type solid)
			)
			(fill no)
			(layer "B.Fab")
		)
		(fp_text user "Author: Antmicro"
			(at -0.72 -5.4 0)
			(layer "B.Fab")
			(effects
				(font
					(size 0.7 0.7)
					(thickness 0.15)
				)
				(justify left bottom mirror)
			)
		)
		(fp_text user "${REFERENCE}"
			(at -0.72 -3.4 0)
			(layer "B.Fab")
			(effects
				(font
					(size 0.7 0.7)
					(thickness 0.15)
				)
				(justify left bottom mirror)
			)
		)
		(fp_text user "License: Apache-2.0"
			(at -0.72 -4.4 0)
			(layer "B.Fab")
			(effects
				(font
					(size 0.7 0.7)
					(thickness 0.15)
				)
				(justify left bottom mirror)
			)
		)
		(pad "" smd roundrect
			(at -0.349 0.002 180)
			(size 0.318 0.36)
			(layers "B.Paste")
			(roundrect_rratio 0.25)
		)
		(pad "" smd roundrect
			(at 0.341 0.002 180)
			(size 0.318 0.36)
			(layers "B.Paste")
			(roundrect_rratio 0.25)
		)
		(pad "1" smd roundrect
			(at -0.321 0.002 180)
			(size 0.46 0.4)
			(layers "B.Cu" "B.Mask")
			(roundrect_rratio 0.25)
			(net 248 "+1V5")
			(pintype "passive")
		)
		(pad "2" smd roundrect
			(at 0.32 0.002 180)
			(size 0.46 0.4)
			(layers "B.Cu" "B.Mask")
			(roundrect_rratio 0.25)
			(net 1 "GND")
			(pintype "passive")
		)
	)
	(footprint "antmicro-footprints:C_0402_1005Metric"
		(layer "B.Cu")
		(at 142.5 85.75 -90)
		(descr "Capacitor SMD 0402")
		(tags "capacitor SMD 0402")
		(property "Reference" "C123"
			(at -1.21 0.7 90)
			(layer "B.SilkS")
			(effects
				(font
					(size 0.65 0.65)
					(thickness 0.15)
				)
				(justify left bottom mirror)
			)
		)
		(property "Value" "C_100n_0402"
			(at 0 -1.4 90)
			(layer "B.Fab")
			(hide yes)
			(effects
				(font
					(size 0.7 0.7)
					(thickness 0.15)
				)
				(justify left bottom mirror)
			)
		)
		(property "Datasheet" "https://www.murata.com/products/productdetail?partno=GRM155R61H104KE14%23"
			(at 0 0 270)
			(layer "F.Fab")
			(hide yes)
			(effects
				(font
					(size 1.27 1.27)
					(thickness 0.15)
				)
			)
		)
		(property "Description" "SMD Multilayer Ceramic Capacitor, 0.1 µF, 50 V, 0402 [1005 Metric], ± 10%, X5R, GRM Series"
			(at 0 0 270)
			(layer "F.Fab")
			(hide yes)
			(effects
				(font
					(size 1.27 1.27)
					(thickness 0.15)
				)
			)
		)
		(property "Author" "Antmicro"
			(at 56.75 228.25 0)
			(layer "B.Fab")
			(hide yes)
			(effects
				(font
					(size 1 1)
					(thickness 0.15)
				)
				(justify mirror)
			)
		)
		(property "Dielectric" "X5R"
			(at 56.75 228.25 0)
			(layer "B.Fab")
			(hide yes)
			(effects
				(font
					(size 1 1)
					(thickness 0.15)
				)
				(justify mirror)
			)
		)
		(property "License" "Apache-2.0"
			(at 56.75 228.25 0)
			(layer "B.Fab")
			(hide yes)
			(effects
				(font
					(size 1 1)
					(thickness 0.15)
				)
				(justify mirror)
			)
		)
		(property "MPN" "GRM155R61H104KE14D"
			(at 56.75 228.25 0)
			(layer "B.Fab")
			(hide yes)
			(effects
				(font
					(size 1 1)
					(thickness 0.15)
				)
				(justify mirror)
			)
		)
		(property "Manufacturer" "Murata"
			(at 56.75 228.25 0)
			(layer "B.Fab")
			(hide yes)
			(effects
				(font
					(size 1 1)
					(thickness 0.15)
				)
				(justify mirror)
			)
		)
		(property "Val" "100n"
			(at 56.75 228.25 0)
			(layer "B.Fab")
			(hide yes)
			(effects
				(font
					(size 1 1)
					(thickness 0.15)
				)
				(justify mirror)
			)
		)
		(property "Voltage" "50V"
			(at 56.75 228.25 0)
			(layer "B.Fab")
			(hide yes)
			(effects
				(font
					(size 1 1)
					(thickness 0.15)
				)
				(justify mirror)
			)
		)
		(sheetname "/Peripherals/")
		(sheetfile "peripherals.kicad_sch")
		(attr smd)
		(fp_rect
			(start -0.925 0.47)
			(end 0.925 -0.47)
			(stroke
				(width 0.05)
				(type default)
			)
			(fill no)
			(layer "B.CrtYd")
		)
		(fp_line
			(start -0.494 0.25)
			(end 0.504 0.25)
			(stroke
				(width 0.15)
				(type solid)
			)
			(layer "B.Fab")
		)
		(fp_line
			(start 0.504 0.25)
			(end 0.504 -0.248)
			(stroke
				(width 0.15)
				(type solid)
			)
			(layer "B.Fab")
		)
		(fp_line
			(start -0.494 -0.248)
			(end -0.494 0.25)
			(stroke
				(width 0.15)
				(type solid)
			)
			(layer "B.Fab")
		)
		(fp_line
			(start 0.504 -0.248)
			(end -0.494 -0.248)
			(stroke
				(width 0.15)
				(type solid)
			)
			(layer "B.Fab")
		)
		(fp_text user "${REFERENCE}"
			(at -0.939 -4.599 90)
			(layer "B.Fab")
			(effects
				(font
					(size 0.7 0.7)
					(thickness 0.15)
				)
				(justify left bottom mirror)
			)
		)
		(fp_text user "License: Apache-2.0"
			(at -0.939 -5.799 90)
			(layer "B.Fab")
			(effects
				(font
					(size 0.7 0.7)
					(thickness 0.15)
				)
				(justify left bottom mirror)
			)
		)
		(fp_text user "Author: Antmicro"
			(at -0.939 -3.399 90)
			(layer "B.Fab")
			(effects
				(font
					(size 0.7 0.7)
					(thickness 0.15)
				)
				(justify left bottom mirror)
			)
		)
		(pad "1" smd roundrect
			(at -0.48 0 270)
			(size 0.59 0.64)
			(layers "B.Cu" "B.Mask" "B.Paste")
			(roundrect_rratio 0.25)
			(net 1 "GND")
			(pintype "passive")
		)
		(pad "2" smd roundrect
			(at 0.48 0 270)
			(size 0.59 0.64)
			(layers "B.Cu" "B.Mask" "B.Paste")
			(roundrect_rratio 0.25)
			(net 348 "/Peripherals/FTDI_VCCIO")
			(pintype "passive")
		)
	)
	(footprint "antmicro-footprints:C_0603_1608Metric"
		(layer "B.Cu")
		(at 161.49 72.1 90)
		(descr "Capacitor SMD 0603")
		(tags "capacitor 0603")
		(property "Reference" "C4"
			(at -0.34 1.54 90)
			(layer "B.SilkS")
			(effects
				(font
					(size 0.65 0.65)
					(thickness 0.15)
				)
				(justify right bottom mirror)
			)
		)
		(property "Value" "C_1u_0603"
			(at 0 -1.6 90)
			(layer "B.Fab")
			(hide yes)
			(effects
				(font
					(size 0.7 0.7)
					(thickness 0.15)
				)
				(justify right bottom mirror)
			)
		)
		(property "Datasheet" "https://spicat.kyocera-avx.com/product/mlcc/chartview/0603YD105KAT2A/"
			(at 0 0 90)
			(layer "F.Fab")
			(hide yes)
			(effects
				(font
					(size 1.27 1.27)
					(thickness 0.15)
				)
			)
		)
		(property "Description" "SMD Multilayer Ceramic Capacitor, 1 µF, 16 V, 0603 [1608 Metric], ± 10%, X5R, AVX 0603 MLCC"
			(at 0 0 90)
			(layer "F.Fab")
			(hide yes)
			(effects
				(font
					(size 1.27 1.27)
					(thickness 0.15)
				)
			)
		)
		(property "Author" "Antmicro"
			(at 233.59 -89.39 0)
			(layer "B.Fab")
			(hide yes)
			(effects
				(font
					(size 1 1)
					(thickness 0.15)
				)
				(justify mirror)
			)
		)
		(property "Dielectric" ""
			(at 233.59 -89.39 0)
			(layer "B.Fab")
			(hide yes)
			(effects
				(font
					(size 1 1)
					(thickness 0.15)
				)
				(justify mirror)
			)
		)
		(property "License" "Apache-2.0"
			(at 233.59 -89.39 0)
			(layer "B.Fab")
			(hide yes)
			(effects
				(font
					(size 1 1)
					(thickness 0.15)
				)
				(justify mirror)
			)
		)
		(property "MPN" "0603YD105KAT2A"
			(at 233.59 -89.39 0)
			(layer "B.Fab")
			(hide yes)
			(effects
				(font
					(size 1 1)
					(thickness 0.15)
				)
				(justify mirror)
			)
		)
		(property "Manufacturer" "KYOCERA AVX"
			(at 233.59 -89.39 0)
			(layer "B.Fab")
			(hide yes)
			(effects
				(font
					(size 1 1)
					(thickness 0.15)
				)
				(justify mirror)
			)
		)
		(property "Val" "1u"
			(at 233.59 -89.39 0)
			(layer "B.Fab")
			(hide yes)
			(effects
				(font
					(size 1 1)
					(thickness 0.15)
				)
				(justify mirror)
			)
		)
		(property "Voltage" ""
			(at 233.59 -89.39 0)
			(layer "B.Fab")
			(hide yes)
			(effects
				(font
					(size 1 1)
					(thickness 0.15)
				)
				(justify mirror)
			)
		)
		(sheetname "/Power Supply/")
		(sheetfile "supply.kicad_sch")
		(attr smd)
		(fp_line
			(start -0.15 -0.4)
			(end 0.15 -0.4)
			(stroke
				(width 0.15)
				(type solid)
			)
			(layer "B.SilkS")
		)
		(fp_line
			(start -0.15 0.4)
			(end 0.15 0.4)
			(stroke
				(width 0.15)
				(type solid)
			)
			(layer "B.SilkS")
		)
		(fp_rect
			(start -1.25 0.65)
			(end 1.25 -0.65)
			(stroke
				(width 0.05)
				(type solid)
			)
			(fill no)
			(layer "B.CrtYd")
		)
		(fp_rect
			(start -0.8 0.4)
			(end 0.8 -0.4)
			(stroke
				(width 0.15)
				(type solid)
			)
			(fill no)
			(layer "B.Fab")
		)
		(fp_text user "License: Apache-2.0"
			(at -1.682 -5.895 270)
			(layer "B.Fab")
			(effects
				(font
					(size 0.7 0.7)
					(thickness 0.15)
				)
				(justify left bottom mirror)
			)
		)
		(fp_text user "Author: Antmicro"
			(at -1.682 -4.894 270)
			(layer "B.Fab")
			(effects
				(font
					(size 0.7 0.7)
					(thickness 0.15)
				)
				(justify left bottom mirror)
			)
		)
		(fp_text user "${REFERENCE}"
			(at -1.682 -3.895 270)
			(layer "B.Fab")
			(effects
				(font
					(size 0.7 0.7)
					(thickness 0.15)
				)
				(justify left bottom mirror)
			)
		)
		(pad "1" smd roundrect
			(at -0.7 0 90)
			(size 0.8 1)
			(layers "B.Cu" "B.Mask" "B.Paste")
			(roundrect_rratio 0.2)
			(net 1 "GND")
			(pintype "passive")
		)
		(pad "2" smd roundrect
			(at 0.7 0 90)
			(size 0.8 1)
			(layers "B.Cu" "B.Mask" "B.Paste")
			(roundrect_rratio 0.2)
			(net 329 "/Power Supply/FFC2_5V_1")
			(pintype "passive")
		)
	)
	(footprint "antmicro-footprints:R_0402_1005Metric"
		(layer "B.Cu")
		(at 152.23 66.25 -90)
		(descr "Resistor SMD 0402")
		(tags "resistor SMD 0402")
		(property "Reference" "R99"
			(at -1.11 0.7 90)
			(layer "B.SilkS")
			(effects
				(font
					(size 0.65 0.65)
					(thickness 0.15)
				)
				(justify left bottom mirror)
			)
		)
		(property "Value" "R_10k_0402"
			(at 0 -1.4 90)
			(layer "B.Fab")
			(hide yes)
			(effects
				(font
					(size 0.7 0.7)
					(thickness 0.15)
				)
				(justify left bottom mirror)
			)
		)
		(property "Datasheet" "https://www.bourns.com/docs/product-datasheets/cr.pdf"
			(at 0 0 270)
			(layer "F.Fab")
			(hide yes)
			(effects
				(font
					(size 1.27 1.27)
					(thickness 0.15)
				)
			)
		)
		(property "Description" "SMD Chip Resistor, 10 kohm, ± 1%, 62.5 mW, 0402 [1005 Metric], Thick Film, General Purpose"
			(at 0 0 270)
			(layer "F.Fab")
			(hide yes)
			(effects
				(font
					(size 1.27 1.27)
					(thickness 0.15)
				)
			)
		)
		(property "Author" "Antmicro"
			(at 85.98 218.48 0)
			(layer "B.Fab")
			(hide yes)
			(effects
				(font
					(size 1 1)
					(thickness 0.15)
				)
				(justify mirror)
			)
		)
		(property "License" "Apache-2.0"
			(at 85.98 218.48 0)
			(layer "B.Fab")
			(hide yes)
			(effects
				(font
					(size 1 1)
					(thickness 0.15)
				)
				(justify mirror)
			)
		)
		(property "MPN" "CR0402-FX-1002GLF"
			(at 85.98 218.48 0)
			(layer "B.Fab")
			(hide yes)
			(effects
				(font
					(size 1 1)
					(thickness 0.15)
				)
				(justify mirror)
			)
		)
		(property "Manufacturer" "Bourns"
			(at 85.98 218.48 0)
			(layer "B.Fab")
			(hide yes)
			(effects
				(font
					(size 1 1)
					(thickness 0.15)
				)
				(justify mirror)
			)
		)
		(property "Tolerance" "1%"
			(at 85.98 218.48 0)
			(layer "B.Fab")
			(hide yes)
			(effects
				(font
					(size 1 1)
					(thickness 0.15)
				)
				(justify mirror)
			)
		)
		(property "Val" "10k"
			(at 85.98 218.48 0)
			(layer "B.Fab")
			(hide yes)
			(effects
				(font
					(size 1 1)
					(thickness 0.15)
				)
				(justify mirror)
			)
		)
		(sheetname "/Power Supply/")
		(sheetfile "supply.kicad_sch")
		(attr smd)
		(fp_rect
			(start -0.925 0.47)
			(end 0.925 -0.47)
			(stroke
				(width 0.05)
				(type default)
			)
			(fill no)
			(layer "B.CrtYd")
		)
		(fp_rect
			(start -0.5 0.25)
			(end 0.5 -0.25)
			(stroke
				(width 0.15)
				(type solid)
			)
			(fill no)
			(layer "B.Fab")
		)
		(fp_text user "${REFERENCE}"
			(at -0.95 -3.168 90)
			(layer "B.Fab")
			(effects
				(font
					(size 0.7 0.7)
					(thickness 0.15)
				)
				(justify left bottom mirror)
			)
		)
		(fp_text user "License: Apache-2.0"
			(at -0.95 -5.169 90)
			(layer "B.Fab")
			(effects
				(font
					(size 0.7 0.7)
					(thickness 0.15)
				)
				(justify left bottom mirror)
			)
		)
		(fp_text user "Author: Antmicro"
			(at -0.95 -4.169 90)
			(layer "B.Fab")
			(effects
				(font
					(size 0.7 0.7)
					(thickness 0.15)
				)
				(justify left bottom mirror)
			)
		)
		(pad "1" smd roundrect
			(at -0.48 0 270)
			(size 0.59 0.64)
			(layers "B.Cu" "B.Mask" "B.Paste")
			(roundrect_rratio 0.25)
			(net 1 "GND")
			(pintype "passive")
		)
		(pad "2" smd roundrect
			(at 0.48 0 270)
			(size 0.59 0.64)
			(layers "B.Cu" "B.Mask" "B.Paste")
			(roundrect_rratio 0.25)
			(net 260 "Net-(Q3-G)")
			(pintype "passive")
		)
	)
	(footprint "antmicro-footprints:R_Array_4x0402"
		(layer "B.Cu")
		(at 121.56 57.44 180)
		(property "Reference" "R48"
			(at -1.07 1 0)
			(layer "B.SilkS")
			(effects
				(font
					(size 0.65 0.65)
					(thickness 0.15)
				)
				(justify left bottom mirror)
			)
		)
		(property "Value" "R_4x51R_0402_array"
			(at -1.5 -2 0)
			(layer "B.Fab")
			(hide yes)
			(effects
				(font
					(size 0.7 0.7)
					(thickness 0.15)
				)
				(justify left bottom mirror)
			)
		)
		(property "Datasheet" "http://industrial.panasonic.com/cdbs/www-data/pdf/AOC0000/AOC0000C14.pdf"
			(at 0 0 180)
			(layer "F.Fab")
			(hide yes)
			(effects
				(font
					(size 1.27 1.27)
					(thickness 0.15)
				)
			)
		)
		(property "Description" "Fixed Network Resistor, 51 ohm, Isolated, 4 Resistors, 0804 [2010 Metric], Convex, ± 5%"
			(at 0 0 180)
			(layer "F.Fab")
			(hide yes)
			(effects
				(font
					(size 1.27 1.27)
					(thickness 0.15)
				)
			)
		)
		(property "Author" "Antmicro"
			(at 243.12 114.88 0)
			(layer "B.Fab")
			(hide yes)
			(effects
				(font
					(size 1 1)
					(thickness 0.15)
				)
				(justify mirror)
			)
		)
		(property "License" "Apache-2.0"
			(at 243.12 114.88 0)
			(layer "B.Fab")
			(hide yes)
			(effects
				(font
					(size 1 1)
					(thickness 0.15)
				)
				(justify mirror)
			)
		)
		(property "MPN" "EXB28V510JX"
			(at 243.12 114.88 0)
			(layer "B.Fab")
			(hide yes)
			(effects
				(font
					(size 1 1)
					(thickness 0.15)
				)
				(justify mirror)
			)
		)
		(property "Manufacturer" "Panasonic"
			(at 243.12 114.88 0)
			(layer "B.Fab")
			(hide yes)
			(effects
				(font
					(size 1 1)
					(thickness 0.15)
				)
				(justify mirror)
			)
		)
		(property "Val" "R_4x51R_0402"
			(at 243.12 114.88 0)
			(layer "B.Fab")
			(hide yes)
			(effects
				(font
					(size 1 1)
					(thickness 0.15)
				)
				(justify mirror)
			)
		)
		(sheetname "/DDR3/")
		(sheetfile "ddr3.kicad_sch")
		(attr smd)
		(fp_line
			(start 1.167 -0.498)
			(end 1.167 0.5)
			(stroke
				(width 0.15)
				(type solid)
			)
			(layer "B.SilkS")
		)
		(fp_line
			(start -1.17 0.5)
			(end -1.17 -0.498)
			(stroke
				(width 0.15)
				(type solid)
			)
			(layer "B.SilkS")
		)
		(fp_rect
			(start -1.2 0.9)
			(end 1.2 -0.9)
			(stroke
				(width 0.05)
				(type solid)
			)
			(fill no)
			(layer "B.CrtYd")
		)
		(fp_line
			(start 0.998 0.5)
			(end 0.998 -0.498)
			(stroke
				(width 0.15)
				(type solid)
			)
			(layer "B.Fab")
		)
		(fp_line
			(start 0.998 -0.498)
			(end -1 -0.498)
			(stroke
				(width 0.15)
				(type solid)
			)
			(layer "B.Fab")
		)
		(fp_line
			(start -1 0.5)
			(end 0.998 0.5)
			(stroke
				(width 0.15)
				(type solid)
			)
			(layer "B.Fab")
		)
		(fp_line
			(start -1 -0.498)
			(end -1 0.5)
			(stroke
				(width 0.15)
				(type solid)
			)
			(layer "B.Fab")
		)
		(pad "1" smd roundrect
			(at -0.802 -0.45 180)
			(size 0.4 0.5)
			(layers "B.Cu" "B.Mask" "B.Paste")
			(roundrect_rratio 0.25)
			(net 151 "/DDR3/DDR3_A4")
			(pinfunction "R1.1")
			(pintype "passive")
		)
		(pad "2" smd roundrect
			(at -0.272 -0.45 180)
			(size 0.4 0.5)
			(layers "B.Cu" "B.Mask" "B.Paste")
			(roundrect_rratio 0.25)
			(net 154 "/DDR3/DDR3_A11")
			(pinfunction "R2.1")
			(pintype "passive")
		)
		(pad "3" smd roundrect
			(at 0.27 -0.45 180)
			(size 0.4 0.5)
			(layers "B.Cu" "B.Mask" "B.Paste")
			(roundrect_rratio 0.25)
			(net 148 "/DDR3/DDR3_A6")
			(pinfunction "R3.1")
			(pintype "passive")
		)
		(pad "4" smd roundrect
			(at 0.8 -0.45 180)
			(size 0.4 0.5)
			(layers "B.Cu" "B.Mask" "B.Paste")
			(roundrect_rratio 0.25)
			(net 155 "/DDR3/DDR3_A8")
			(pinfunction "R4.1")
			(pintype "passive")
		)
		(pad "5" smd roundrect
			(at 0.8 0.452 180)
			(size 0.4 0.5)
			(layers "B.Cu" "B.Mask" "B.Paste")
			(roundrect_rratio 0.25)
			(net 6 "Vtt")
			(pinfunction "R4.2")
			(pintype "passive")
		)
		(pad "6" smd roundrect
			(at 0.27 0.452 180)
			(size 0.4 0.5)
			(layers "B.Cu" "B.Mask" "B.Paste")
			(roundrect_rratio 0.25)
			(net 6 "Vtt")
			(pinfunction "R3.2")
			(pintype "passive")
		)
		(pad "7" smd roundrect
			(at -0.272 0.452 180)
			(size 0.4 0.5)
			(layers "B.Cu" "B.Mask" "B.Paste")
			(roundrect_rratio 0.25)
			(net 6 "Vtt")
			(pinfunction "R2.2")
			(pintype "passive")
		)
		(pad "8" smd roundrect
			(at -0.802 0.452 180)
			(size 0.4 0.5)
			(layers "B.Cu" "B.Mask" "B.Paste")
			(roundrect_rratio 0.25)
			(net 6 "Vtt")
			(pinfunction "R1.2")
			(pintype "passive")
		)
	)
	(footprint "antmicro-footprints:C_0603_1608Metric"
		(layer "B.Cu")
		(at 127.72 100.54 90)
		(descr "Capacitor SMD 0603")
		(tags "capacitor 0603")
		(property "Reference" "C89"
			(at -3.35 0.31 90)
			(layer "B.SilkS")
			(effects
				(font
					(size 0.65 0.65)
					(thickness 0.15)
				)
				(justify right bottom mirror)
			)
		)
		(property "Value" "C_10u_0603"
			(at 0 -1.6 90)
			(layer "B.Fab")
			(hide yes)
			(effects
				(font
					(size 0.7 0.7)
					(thickness 0.15)
				)
				(justify right bottom mirror)
			)
		)
		(property "Datasheet" "https://www.murata.com/products/productdetail?partno=GRM188R61A106KE69%23"
			(at 0 0 90)
			(layer "F.Fab")
			(hide yes)
			(effects
				(font
					(size 1.27 1.27)
					(thickness 0.15)
				)
			)
		)
		(property "Description" "SMD Multilayer Ceramic Capacitor, 10 µF, 10 V, 0603 [1608 Metric], ± 10%, X5R, GRM Series"
			(at 0 0 90)
			(layer "F.Fab")
			(hide yes)
			(effects
				(font
					(size 1.27 1.27)
					(thickness 0.15)
				)
			)
		)
		(property "Author" "Antmicro"
			(at 228.26 -27.18 0)
			(layer "B.Fab")
			(hide yes)
			(effects
				(font
					(size 1 1)
					(thickness 0.15)
				)
				(justify mirror)
			)
		)
		(property "License" "Apache-2.0"
			(at 228.26 -27.18 0)
			(layer "B.Fab")
			(hide yes)
			(effects
				(font
					(size 1 1)
					(thickness 0.15)
				)
				(justify mirror)
			)
		)
		(property "MPN" "GRM188R61A106KE69D"
			(at 228.26 -27.18 0)
			(layer "B.Fab")
			(hide yes)
			(effects
				(font
					(size 1 1)
					(thickness 0.15)
				)
				(justify mirror)
			)
		)
		(property "Manufacturer" "Murata"
			(at 228.26 -27.18 0)
			(layer "B.Fab")
			(hide yes)
			(effects
				(font
					(size 1 1)
					(thickness 0.15)
				)
				(justify mirror)
			)
		)
		(property "Val" "10u"
			(at 228.26 -27.18 0)
			(layer "B.Fab")
			(hide yes)
			(effects
				(font
					(size 1 1)
					(thickness 0.15)
				)
				(justify mirror)
			)
		)
		(property "Voltage" ""
			(at 228.26 -27.18 0)
			(layer "B.Fab")
			(hide yes)
			(effects
				(font
					(size 1 1)
					(thickness 0.15)
				)
				(justify mirror)
			)
		)
		(property "Dielectric" "template_dielectric"
			(at 0 0 90)
			(unlocked yes)
			(layer "B.Fab")
			(hide yes)
			(effects
				(font
					(size 1 1)
					(thickness 0.15)
				)
				(justify mirror)
			)
		)
		(sheetname "/FPGA Power/")
		(sheetfile "FPGA_Power.kicad_sch")
		(attr smd)
		(fp_line
			(start -0.15 -0.4)
			(end 0.15 -0.4)
			(stroke
				(width 0.15)
				(type solid)
			)
			(layer "B.SilkS")
		)
		(fp_line
			(start -0.15 0.4)
			(end 0.15 0.4)
			(stroke
				(width 0.15)
				(type solid)
			)
			(layer "B.SilkS")
		)
		(fp_rect
			(start -1.25 0.65)
			(end 1.25 -0.65)
			(stroke
				(width 0.05)
				(type solid)
			)
			(fill no)
			(layer "B.CrtYd")
		)
		(fp_rect
			(start -0.8 0.4)
			(end 0.8 -0.4)
			(stroke
				(width 0.15)
				(type solid)
			)
			(fill no)
			(layer "B.Fab")
		)
		(fp_text user "Author: Antmicro"
			(at -1.682 -4.894 270)
			(layer "B.Fab")
			(effects
				(font
					(size 0.7 0.7)
					(thickness 0.15)
				)
				(justify left bottom mirror)
			)
		)
		(fp_text user "${REFERENCE}"
			(at -1.682 -3.895 270)
			(layer "B.Fab")
			(effects
				(font
					(size 0.7 0.7)
					(thickness 0.15)
				)
				(justify left bottom mirror)
			)
		)
		(fp_text user "License: Apache-2.0"
			(at -1.682 -5.895 270)
			(layer "B.Fab")
			(effects
				(font
					(size 0.7 0.7)
					(thickness 0.15)
				)
				(justify left bottom mirror)
			)
		)
		(pad "1" smd roundrect
			(at -0.7 0 90)
			(size 0.8 1)
			(layers "B.Cu" "B.Mask" "B.Paste")
			(roundrect_rratio 0.2)
			(net 1 "GND")
			(pintype "passive")
		)
		(pad "2" smd roundrect
			(at 0.7 0 90)
			(size 0.8 1)
			(layers "B.Cu" "B.Mask" "B.Paste")
			(roundrect_rratio 0.2)
			(net 11 "/FPGA Power/VCC_DPHY")
			(pintype "passive")
		)
	)
	(footprint "antmicro-footprints:PinHeader_1x6_P2.54mm_SMD_Horizontal"
		(layer "B.Cu")
		(at 158.7415 119.14)
		(property "Reference" "J10"
			(at 6.7885 -7.7 180)
			(layer "B.SilkS")
			(effects
				(font
					(size 0.7 0.7)
					(thickness 0.15)
				)
				(justify left bottom mirror)
			)
		)
		(property "Value" "PinHeader_1x6_P2.54mm_SMD_Horizontal"
			(at 0 -8.8 180)
			(layer "B.Fab")
			(effects
				(font
					(size 0.7 0.7)
					(thickness 0.15)
				)
				(justify left bottom mirror)
			)
		)
		(property "Datasheet" "https://www.mouser.com/datasheet/2/527/tsm-2854655.pdf"
			(at 0 0 0)
			(layer "F.Fab")
			(hide yes)
			(effects
				(font
					(size 1.27 1.27)
					(thickness 0.15)
				)
			)
		)
		(property "Description" "Connector Header Surface Mount, Right Angle 6 position 0.100\" (2.54mm)"
			(at 0 0 0)
			(layer "F.Fab")
			(hide yes)
			(effects
				(font
					(size 1.27 1.27)
					(thickness 0.15)
				)
			)
		)
		(property "Author" "Antmicro"
			(at 0 0 0)
			(layer "B.Fab")
			(hide yes)
			(effects
				(font
					(size 1 1)
					(thickness 0.15)
				)
				(justify mirror)
			)
		)
		(property "License" "Apache-2.0"
			(at 0 0 0)
			(layer "B.Fab")
			(hide yes)
			(effects
				(font
					(size 1 1)
					(thickness 0.15)
				)
				(justify mirror)
			)
		)
		(property "MPN" "TSM-106-01-T-SH"
			(at 0 0 0)
			(layer "B.Fab")
			(hide yes)
			(effects
				(font
					(size 1 1)
					(thickness 0.15)
				)
				(justify mirror)
			)
		)
		(property "Manufacturer" "Samtec"
			(at 0 0 0)
			(layer "B.Fab")
			(hide yes)
			(effects
				(font
					(size 1 1)
					(thickness 0.15)
				)
				(justify mirror)
			)
		)
		(sheetname "/Peripherals/")
		(sheetfile "peripherals.kicad_sch")
		(attr smd exclude_from_pos_files exclude_from_bom dnp)
		(fp_line
			(start -7.62 -1.904)
			(end -7.62 0.635)
			(stroke
				(width 0.15)
				(type solid)
			)
			(layer "B.SilkS")
		)
		(fp_line
			(start 7.618 -1.904)
			(end -7.62 -1.904)
			(stroke
				(width 0.15)
				(type solid)
			)
			(layer "B.SilkS")
		)
		(fp_line
			(start 7.618 0.635)
			(end -7.62 0.635)
			(stroke
				(width 0.15)
				(type solid)
			)
			(layer "B.SilkS")
		)
		(fp_line
			(start 7.618 0.635)
			(end 7.618 -1.904)
			(stroke
				(width 0.15)
				(type solid)
			)
			(layer "B.SilkS")
		)
		(fp_circle
			(center -7.321 -5.913)
			(end -7.271 -5.913)
			(stroke
				(width 0.15)
				(type solid)
			)
			(fill yes)
			(layer "B.SilkS")
		)
		(fp_rect
			(start -8 6.8)
			(end 8 -7.8)
			(stroke
				(width 0.05)
				(type solid)
			)
			(fill no)
			(layer "B.CrtYd")
		)
		(fp_line
			(start -7.62 -6.75)
			(end -6.895 -7.475)
			(stroke
				(width 0.15)
				(type solid)
			)
			(layer "B.Fab")
		)
		(fp_line
			(start -7.62 -1.904)
			(end -7.62 -6.75)
			(stroke
				(width 0.15)
				(type solid)
			)
			(layer "B.Fab")
		)
		(fp_line
			(start -7.62 -1.904)
			(end -7.62 6.476)
			(stroke
				(width 0.15)
				(type solid)
			)
			(layer "B.Fab")
		)
		(fp_line
			(start -7.62 0.635)
			(end 7.618 0.635)
			(stroke
				(width 0.15)
				(type solid)
			)
			(layer "B.Fab")
		)
		(fp_line
			(start -7.62 6.476)
			(end 7.618 6.476)
			(stroke
				(width 0.15)
				(type solid)
			)
			(layer "B.Fab")
		)
		(fp_line
			(start -6.895 -7.475)
			(end 7.618 -7.475)
			(stroke
				(width 0.15)
				(type solid)
			)
			(layer "B.Fab")
		)
		(fp_line
			(start 7.618 -7.475)
			(end 7.618 -1.904)
			(stroke
				(width 0.15)
				(type solid)
			)
			(layer "B.Fab")
		)
		(fp_line
			(start 7.618 -1.904)
			(end -7.62 -1.904)
			(stroke
				(width 0.15)
				(type solid)
			)
			(layer "B.Fab")
		)
		(fp_line
			(start 7.618 6.476)
			(end 7.618 -1.904)
			(stroke
				(width 0.15)
				(type solid)
			)
			(layer "B.Fab")
		)
		(fp_text user "License: Apache-2.0"
			(at -8.93 -13.199 180)
			(layer "B.Fab")
			(effects
				(font
					(size 0.7 0.7)
					(thickness 0.15)
				)
				(justify left bottom mirror)
			)
		)
		(fp_text user "${REFERENCE}"
			(at -8.93 -14.4 180)
			(layer "B.Fab")
			(effects
				(font
					(size 0.7 0.7)
					(thickness 0.15)
				)
				(justify left bottom mirror)
			)
		)
		(fp_text user "Author: Antmicro"
			(at -8.93 -12 180)
			(layer "B.Fab")
			(effects
				(font
					(size 0.7 0.7)
					(thickness 0.15)
				)
				(justify left bottom mirror)
			)
		)
		(pad "1" smd roundrect
			(at -6.351 -5.914)
			(size 1.27 3.18)
			(layers "B.Cu" "B.Mask" "B.Paste")
			(roundrect_rratio 0.25)
			(net 331 "/Peripherals/3V3_MISC")
			(pintype "passive")
		)
		(pad "2" smd roundrect
			(at -3.81 -5.914)
			(size 1.27 3.18)
			(layers "B.Cu" "B.Mask" "B.Paste")
			(roundrect_rratio 0.25)
			(net 332 "GPIO0")
			(pintype "passive")
		)
		(pad "3" smd roundrect
			(at -1.27 -5.914)
			(size 1.27 3.18)
			(layers "B.Cu" "B.Mask" "B.Paste")
			(roundrect_rratio 0.25)
			(net 333 "GPIO1")
			(pintype "passive")
		)
		(pad "4" smd roundrect
			(at 1.267 -5.914)
			(size 1.27 3.18)
			(layers "B.Cu" "B.Mask" "B.Paste")
			(roundrect_rratio 0.25)
			(net 334 "GPIO2")
			(pintype "passive")
		)
		(pad "5" smd roundrect
			(at 3.809 -5.914)
			(size 1.27 3.18)
			(layers "B.Cu" "B.Mask" "B.Paste")
			(roundrect_rratio 0.25)
			(net 335 "GPIO3")
			(pintype "passive")
		)
		(pad "6" smd roundrect
			(at 6.349 -5.914)
			(size 1.27 3.18)
			(layers "B.Cu" "B.Mask" "B.Paste")
			(roundrect_rratio 0.25)
			(net 1 "GND")
			(pintype "passive")
		)
	)
	(footprint "antmicro-footprints:C_0603_1608Metric"
		(layer "B.Cu")
		(at 127.82 80.7)
		(descr "Capacitor SMD 0603")
		(tags "capacitor 0603")
		(property "Reference" "C92"
			(at -3.29 0.44 0)
			(layer "B.SilkS")
			(effects
				(font
					(size 0.65 0.65)
					(thickness 0.15)
				)
				(justify right bottom mirror)
			)
		)
		(property "Value" "C_10u_0603"
			(at 0 -1.6 0)
			(layer "B.Fab")
			(hide yes)
			(effects
				(font
					(size 0.7 0.7)
					(thickness 0.15)
				)
				(justify right bottom mirror)
			)
		)
		(property "Datasheet" "https://www.murata.com/products/productdetail?partno=GRM188R61A106KE69%23"
			(at 0 0 0)
			(layer "F.Fab")
			(hide yes)
			(effects
				(font
					(size 1.27 1.27)
					(thickness 0.15)
				)
			)
		)
		(property "Description" "SMD Multilayer Ceramic Capacitor, 10 µF, 10 V, 0603 [1608 Metric], ± 10%, X5R, GRM Series"
			(at 0 0 0)
			(layer "F.Fab")
			(hide yes)
			(effects
				(font
					(size 1.27 1.27)
					(thickness 0.15)
				)
			)
		)
		(property "Author" "Antmicro"
			(at 0 0 0)
			(layer "B.Fab")
			(hide yes)
			(effects
				(font
					(size 1 1)
					(thickness 0.15)
				)
				(justify mirror)
			)
		)
		(property "License" "Apache-2.0"
			(at 0 0 0)
			(layer "B.Fab")
			(hide yes)
			(effects
				(font
					(size 1 1)
					(thickness 0.15)
				)
				(justify mirror)
			)
		)
		(property "MPN" "GRM188R61A106KE69D"
			(at 0 0 0)
			(layer "B.Fab")
			(hide yes)
			(effects
				(font
					(size 1 1)
					(thickness 0.15)
				)
				(justify mirror)
			)
		)
		(property "Manufacturer" "Murata"
			(at 0 0 0)
			(layer "B.Fab")
			(hide yes)
			(effects
				(font
					(size 1 1)
					(thickness 0.15)
				)
				(justify mirror)
			)
		)
		(property "Val" "10u"
			(at 0 0 0)
			(layer "B.Fab")
			(hide yes)
			(effects
				(font
					(size 1 1)
					(thickness 0.15)
				)
				(justify mirror)
			)
		)
		(property "Voltage" ""
			(at 0 0 0)
			(layer "B.Fab")
			(hide yes)
			(effects
				(font
					(size 1 1)
					(thickness 0.15)
				)
				(justify mirror)
			)
		)
		(property "Dielectric" "template_dielectric"
			(at 0 0 0)
			(unlocked yes)
			(layer "B.Fab")
			(hide yes)
			(effects
				(font
					(size 1 1)
					(thickness 0.15)
				)
				(justify mirror)
			)
		)
		(sheetname "/FPGA Power/")
		(sheetfile "FPGA_Power.kicad_sch")
		(attr smd)
		(fp_line
			(start -0.15 -0.4)
			(end 0.15 -0.4)
			(stroke
				(width 0.15)
				(type solid)
			)
			(layer "B.SilkS")
		)
		(fp_line
			(start -0.15 0.4)
			(end 0.15 0.4)
			(stroke
				(width 0.15)
				(type solid)
			)
			(layer "B.SilkS")
		)
		(fp_rect
			(start -1.25 0.65)
			(end 1.25 -0.65)
			(stroke
				(width 0.05)
				(type solid)
			)
			(fill no)
			(layer "B.CrtYd")
		)
		(fp_rect
			(start -0.8 0.4)
			(end 0.8 -0.4)
			(stroke
				(width 0.15)
				(type solid)
			)
			(fill no)
			(layer "B.Fab")
		)
		(fp_text user "Author: Antmicro"
			(at -1.682 -4.894 180)
			(layer "B.Fab")
			(effects
				(font
					(size 0.7 0.7)
					(thickness 0.15)
				)
				(justify left bottom mirror)
			)
		)
		(fp_text user "${REFERENCE}"
			(at -1.682 -3.895 180)
			(layer "B.Fab")
			(effects
				(font
					(size 0.7 0.7)
					(thickness 0.15)
				)
				(justify left bottom mirror)
			)
		)
		(fp_text user "License: Apache-2.0"
			(at -1.682 -5.895 180)
			(layer "B.Fab")
			(effects
				(font
					(size 0.7 0.7)
					(thickness 0.15)
				)
				(justify left bottom mirror)
			)
		)
		(pad "1" smd roundrect
			(at -0.7 0)
			(size 0.8 1)
			(layers "B.Cu" "B.Mask" "B.Paste")
			(roundrect_rratio 0.2)
			(net 1 "GND")
			(pintype "passive")
		)
		(pad "2" smd roundrect
			(at 0.7 0)
			(size 0.8 1)
			(layers "B.Cu" "B.Mask" "B.Paste")
			(roundrect_rratio 0.2)
			(net 9 "/FPGA Power/VCC_AUX")
			(pintype "passive")
		)
	)
	(footprint "antmicro-footprints:C_0402_1005Metric"
		(layer "B.Cu")
		(at 97.39 74.66 -90)
		(descr "Capacitor SMD 0402")
		(tags "capacitor SMD 0402")
		(property "Reference" "C61"
			(at -0.92 -1.35 90)
			(layer "B.SilkS")
			(effects
				(font
					(size 0.65 0.65)
					(thickness 0.15)
				)
				(justify left bottom mirror)
			)
		)
		(property "Value" "C_100n_0402"
			(at 0 -1.4 90)
			(layer "B.Fab")
			(hide yes)
			(effects
				(font
					(size 0.7 0.7)
					(thickness 0.15)
				)
				(justify left bottom mirror)
			)
		)
		(property "Datasheet" "https://www.murata.com/products/productdetail?partno=GRM155R61H104KE14%23"
			(at 0 0 270)
			(layer "F.Fab")
			(hide yes)
			(effects
				(font
					(size 1.27 1.27)
					(thickness 0.15)
				)
			)
		)
		(property "Description" "SMD Multilayer Ceramic Capacitor, 0.1 µF, 50 V, 0402 [1005 Metric], ± 10%, X5R, GRM Series"
			(at 0 0 270)
			(layer "F.Fab")
			(hide yes)
			(effects
				(font
					(size 1.27 1.27)
					(thickness 0.15)
				)
			)
		)
		(property "Author" "Antmicro"
			(at 22.72 172.04 0)
			(layer "B.Fab")
			(hide yes)
			(effects
				(font
					(size 1 1)
					(thickness 0.15)
				)
				(justify mirror)
			)
		)
		(property "Dielectric" "X5R"
			(at 22.72 172.04 0)
			(layer "B.Fab")
			(hide yes)
			(effects
				(font
					(size 1 1)
					(thickness 0.15)
				)
				(justify mirror)
			)
		)
		(property "License" "Apache-2.0"
			(at 22.72 172.04 0)
			(layer "B.Fab")
			(hide yes)
			(effects
				(font
					(size 1 1)
					(thickness 0.15)
				)
				(justify mirror)
			)
		)
		(property "MPN" "GRM155R61H104KE14D"
			(at 22.72 172.04 0)
			(layer "B.Fab")
			(hide yes)
			(effects
				(font
					(size 1 1)
					(thickness 0.15)
				)
				(justify mirror)
			)
		)
		(property "Manufacturer" "Murata"
			(at 22.72 172.04 0)
			(layer "B.Fab")
			(hide yes)
			(effects
				(font
					(size 1 1)
					(thickness 0.15)
				)
				(justify mirror)
			)
		)
		(property "Val" "100n"
			(at 22.72 172.04 0)
			(layer "B.Fab")
			(hide yes)
			(effects
				(font
					(size 1 1)
					(thickness 0.15)
				)
				(justify mirror)
			)
		)
		(property "Voltage" "50V"
			(at 22.72 172.04 0)
			(layer "B.Fab")
			(hide yes)
			(effects
				(font
					(size 1 1)
					(thickness 0.15)
				)
				(justify mirror)
			)
		)
		(sheetname "/SDI/")
		(sheetfile "sdi.kicad_sch")
		(attr smd)
		(fp_rect
			(start -0.925 0.47)
			(end 0.925 -0.47)
			(stroke
				(width 0.05)
				(type default)
			)
			(fill no)
			(layer "B.CrtYd")
		)
		(fp_line
			(start -0.494 0.25)
			(end 0.504 0.25)
			(stroke
				(width 0.15)
				(type solid)
			)
			(layer "B.Fab")
		)
		(fp_line
			(start 0.504 0.25)
			(end 0.504 -0.248)
			(stroke
				(width 0.15)
				(type solid)
			)
			(layer "B.Fab")
		)
		(fp_line
			(start -0.494 -0.248)
			(end -0.494 0.25)
			(stroke
				(width 0.15)
				(type solid)
			)
			(layer "B.Fab")
		)
		(fp_line
			(start 0.504 -0.248)
			(end -0.494 -0.248)
			(stroke
				(width 0.15)
				(type solid)
			)
			(layer "B.Fab")
		)
		(fp_text user "License: Apache-2.0"
			(at -0.939 -5.799 90)
			(layer "B.Fab")
			(effects
				(font
					(size 0.7 0.7)
					(thickness 0.15)
				)
				(justify left bottom mirror)
			)
		)
		(fp_text user "Author: Antmicro"
			(at -0.939 -3.399 90)
			(layer "B.Fab")
			(effects
				(font
					(size 0.7 0.7)
					(thickness 0.15)
				)
				(justify left bottom mirror)
			)
		)
		(fp_text user "${REFERENCE}"
			(at -0.939 -4.599 90)
			(layer "B.Fab")
			(effects
				(font
					(size 0.7 0.7)
					(thickness 0.15)
				)
				(justify left bottom mirror)
			)
		)
		(pad "1" smd roundrect
			(at -0.48 0 270)
			(size 0.59 0.64)
			(layers "B.Cu" "B.Mask" "B.Paste")
			(roundrect_rratio 0.25)
			(net 1 "GND")
			(pintype "passive")
		)
		(pad "2" smd roundrect
			(at 0.48 0 270)
			(size 0.59 0.64)
			(layers "B.Cu" "B.Mask" "B.Paste")
			(roundrect_rratio 0.25)
			(net 3 "+1V2")
			(pintype "passive")
		)
	)
	(footprint "antmicro-footprints:TP_SMD_0.75mm"
		(layer "B.Cu")
		(at 93.1392 88.95 90)
		(property "Reference" "TP31"
			(at -2.99 0.3908 90)
			(layer "B.SilkS")
			(effects
				(font
					(size 0.65 0.65)
					(thickness 0.15)
				)
				(justify right bottom mirror)
			)
		)
		(property "Value" "TP_0.75mm_SMD"
			(at 0 -1.2 90)
			(layer "B.Fab")
			(hide yes)
			(effects
				(font
					(size 0.7 0.7)
					(thickness 0.15)
				)
				(justify right bottom mirror)
			)
		)
		(property "Description" "SMT test point"
			(at 0 0 90)
			(layer "F.Fab")
			(hide yes)
			(effects
				(font
					(size 1.27 1.27)
					(thickness 0.15)
				)
			)
		)
		(property "Author" "Antmicro"
			(at 182.0892 -4.1892 0)
			(layer "B.Fab")
			(hide yes)
			(effects
				(font
					(size 1 1)
					(thickness 0.15)
				)
				(justify mirror)
			)
		)
		(property "License" "Apache-2.0"
			(at 182.0892 -4.1892 0)
			(layer "B.Fab")
			(hide yes)
			(effects
				(font
					(size 1 1)
					(thickness 0.15)
				)
				(justify mirror)
			)
		)
		(property "MPN" ""
			(at 182.0892 -4.1892 0)
			(layer "B.Fab")
			(hide yes)
			(effects
				(font
					(size 1 1)
					(thickness 0.15)
				)
				(justify mirror)
			)
		)
		(property "Manufacturer" ""
			(at 182.0892 -4.1892 0)
			(layer "B.Fab")
			(hide yes)
			(effects
				(font
					(size 1 1)
					(thickness 0.15)
				)
				(justify mirror)
			)
		)
		(sheetname "/SDI/")
		(sheetfile "sdi.kicad_sch")
		(attr exclude_from_pos_files)
		(fp_circle
			(center 0 0)
			(end 0.475 0)
			(stroke
				(width 0.05)
				(type default)
			)
			(fill no)
			(layer "B.CrtYd")
		)
		(fp_text user "License: Apache-2.0"
			(at -0.4 -5.101 270)
			(layer "B.Fab")
			(effects
				(font
					(size 0.7 0.7)
					(thickness 0.15)
				)
				(justify left bottom mirror)
			)
		)
		(fp_text user "Author: Antmicro"
			(at -0.4 -3.901 270)
			(layer "B.Fab")
			(effects
				(font
					(size 0.7 0.7)
					(thickness 0.15)
				)
				(justify left bottom mirror)
			)
		)
		(fp_text user "${REFERENCE}"
			(at -0.4 -2.7 270)
			(layer "B.Fab")
			(effects
				(font
					(size 0.7 0.7)
					(thickness 0.15)
				)
				(justify left bottom mirror)
			)
		)
		(pad "1" smd circle
			(at 0 0 90)
			(size 0.75 0.75)
			(layers "B.Cu" "B.Mask")
			(net 198 "/SDI/AUDIO_EN{slash}~{DIS}")
			(pinfunction "1")
			(pintype "passive")
		)
	)
	(footprint "antmicro-footprints:TP_SMD_0.75mm"
		(layer "B.Cu")
		(at 96.2408 88.95 -90)
		(property "Reference" "TP41"
			(at 0.49 -0.2892 90)
			(layer "B.SilkS")
			(effects
				(font
					(size 0.65 0.65)
					(thickness 0.15)
				)
				(justify left bottom mirror)
			)
		)
		(property "Value" "TP_0.75mm_SMD"
			(at 0 -1.2 90)
			(layer "B.Fab")
			(hide yes)
			(effects
				(font
					(size 0.7 0.7)
					(thickness 0.15)
				)
				(justify left bottom mirror)
			)
		)
		(property "Description" "SMT test point"
			(at 0 0 270)
			(layer "F.Fab")
			(hide yes)
			(effects
				(font
					(size 1.27 1.27)
					(thickness 0.15)
				)
			)
		)
		(property "Author" "Antmicro"
			(at 7.2908 185.1908 0)
			(layer "B.Fab")
			(hide yes)
			(effects
				(font
					(size 1 1)
					(thickness 0.15)
				)
				(justify mirror)
			)
		)
		(property "License" "Apache-2.0"
			(at 7.2908 185.1908 0)
			(layer "B.Fab")
			(hide yes)
			(effects
				(font
					(size 1 1)
					(thickness 0.15)
				)
				(justify mirror)
			)
		)
		(property "MPN" ""
			(at 7.2908 185.1908 0)
			(layer "B.Fab")
			(hide yes)
			(effects
				(font
					(size 1 1)
					(thickness 0.15)
				)
				(justify mirror)
			)
		)
		(property "Manufacturer" ""
			(at 7.2908 185.1908 0)
			(layer "B.Fab")
			(hide yes)
			(effects
				(font
					(size 1 1)
					(thickness 0.15)
				)
				(justify mirror)
			)
		)
		(sheetname "/SDI/")
		(sheetfile "sdi.kicad_sch")
		(attr exclude_from_pos_files)
		(fp_circle
			(center 0 0)
			(end 0.475 0)
			(stroke
				(width 0.05)
				(type default)
			)
			(fill no)
			(layer "B.CrtYd")
		)
		(fp_text user "${REFERENCE}"
			(at -0.4 -2.7 90)
			(layer "B.Fab")
			(effects
				(font
					(size 0.7 0.7)
					(thickness 0.15)
				)
				(justify left bottom mirror)
			)
		)
		(fp_text user "License: Apache-2.0"
			(at -0.4 -5.101 90)
			(layer "B.Fab")
			(effects
				(font
					(size 0.7 0.7)
					(thickness 0.15)
				)
				(justify left bottom mirror)
			)
		)
		(fp_text user "Author: Antmicro"
			(at -0.4 -3.901 90)
			(layer "B.Fab")
			(effects
				(font
					(size 0.7 0.7)
					(thickness 0.15)
				)
				(justify left bottom mirror)
			)
		)
		(pad "1" smd circle
			(at 0 0 270)
			(size 0.75 0.75)
			(layers "B.Cu" "B.Mask")
			(net 177 "/SDI/SW_EN")
			(pinfunction "1")
			(pintype "passive")
		)
	)
	(footprint "antmicro-footprints:C_0201"
		(layer "B.Cu")
		(at 133.4 83.24)
		(descr "Capacitor SMD 0201")
		(tags "capacitor SMD 0201")
		(property "Reference" "C40"
			(at -0.87 -0.6 0)
			(layer "B.SilkS")
			(effects
				(font
					(size 0.65 0.65)
					(thickness 0.15)
				)
				(justify right bottom mirror)
			)
		)
		(property "Value" "C_100n_0201"
			(at 0 -1.4 0)
			(layer "B.Fab")
			(hide yes)
			(effects
				(font
					(size 0.7 0.7)
					(thickness 0.15)
				)
				(justify right bottom mirror)
			)
		)
		(property "Datasheet" "https://www.yageo.com/en/Chart/Download/pdf/CC0201KRX6S5BB104"
			(at 0 0 0)
			(layer "F.Fab")
			(hide yes)
			(effects
				(font
					(size 1.27 1.27)
					(thickness 0.15)
				)
			)
		)
		(property "Description" "SMD Multilayer Ceramic Capacitor, 0.1 µF, 6.3 V, 0201 [0603 Metric], ± 10%, X6S, CC Series"
			(at 0 0 0)
			(layer "F.Fab")
			(hide yes)
			(effects
				(font
					(size 1.27 1.27)
					(thickness 0.15)
				)
			)
		)
		(property "Author" "Antmicro"
			(at 0 0 0)
			(layer "B.Fab")
			(hide yes)
			(effects
				(font
					(size 1 1)
					(thickness 0.15)
				)
				(justify mirror)
			)
		)
		(property "Dielectric" ""
			(at 0 0 0)
			(layer "B.Fab")
			(hide yes)
			(effects
				(font
					(size 1 1)
					(thickness 0.15)
				)
				(justify mirror)
			)
		)
		(property "License" "Apache-2.0"
			(at 0 0 0)
			(layer "B.Fab")
			(hide yes)
			(effects
				(font
					(size 1 1)
					(thickness 0.15)
				)
				(justify mirror)
			)
		)
		(property "MPN" "CC0201KRX6S5BB104"
			(at 0 0 0)
			(layer "B.Fab")
			(hide yes)
			(effects
				(font
					(size 1 1)
					(thickness 0.15)
				)
				(justify mirror)
			)
		)
		(property "Manufacturer" "YAGEO"
			(at 0 0 0)
			(layer "B.Fab")
			(hide yes)
			(effects
				(font
					(size 1 1)
					(thickness 0.15)
				)
				(justify mirror)
			)
		)
		(property "Val" "100n"
			(at 0 0 0)
			(layer "B.Fab")
			(hide yes)
			(effects
				(font
					(size 1 1)
					(thickness 0.15)
				)
				(justify mirror)
			)
		)
		(property "Voltage" ""
			(at 0 0 0)
			(layer "B.Fab")
			(hide yes)
			(effects
				(font
					(size 1 1)
					(thickness 0.15)
				)
				(justify mirror)
			)
		)
		(property "Public" "False"
			(at 0 0 0)
			(unlocked yes)
			(layer "B.Fab")
			(hide yes)
			(effects
				(font
					(size 1 1)
					(thickness 0.15)
				)
				(justify mirror)
			)
		)
		(sheetname "/DDR3/")
		(sheetfile "ddr3.kicad_sch")
		(attr smd)
		(fp_rect
			(start -0.7 0.35)
			(end 0.7 -0.35)
			(stroke
				(width 0.05)
				(type default)
			)
			(fill no)
			(layer "B.CrtYd")
		)
		(fp_rect
			(start 0.3 -0.15)
			(end -0.301 0.149)
			(stroke
				(width 0.15)
				(type solid)
			)
			(fill no)
			(layer "B.Fab")
		)
		(fp_text user "${REFERENCE}"
			(at -0.72 -3.4 180)
			(layer "B.Fab")
			(effects
				(font
					(size 0.7 0.7)
					(thickness 0.15)
				)
				(justify left bottom mirror)
			)
		)
		(fp_text user "Author: Antmicro"
			(at -0.72 -5.4 180)
			(layer "B.Fab")
			(effects
				(font
					(size 0.7 0.7)
					(thickness 0.15)
				)
				(justify left bottom mirror)
			)
		)
		(fp_text user "License: Apache-2.0"
			(at -0.72 -4.4 180)
			(layer "B.Fab")
			(effects
				(font
					(size 0.7 0.7)
					(thickness 0.15)
				)
				(justify left bottom mirror)
			)
		)
		(pad "" smd roundrect
			(at -0.349 0.002)
			(size 0.318 0.36)
			(layers "B.Paste")
			(roundrect_rratio 0.25)
		)
		(pad "" smd roundrect
			(at 0.341 0.002)
			(size 0.318 0.36)
			(layers "B.Paste")
			(roundrect_rratio 0.25)
		)
		(pad "1" smd roundrect
			(at -0.321 0.002)
			(size 0.46 0.4)
			(layers "B.Cu" "B.Mask")
			(roundrect_rratio 0.25)
			(net 1 "GND")
			(pintype "passive")
		)
		(pad "2" smd roundrect
			(at 0.32 0.002)
			(size 0.46 0.4)
			(layers "B.Cu" "B.Mask")
			(roundrect_rratio 0.25)
			(net 5 "Vref")
			(pintype "passive")
		)
	)
	(footprint "antmicro-footprints:R_0402_1005Metric"
		(layer "B.Cu")
		(at 106.19 96.8 90)
		(descr "Resistor SMD 0402")
		(tags "resistor SMD 0402")
		(property "Reference" "R76"
			(at -0.94 0.34 270)
			(layer "B.SilkS")
			(effects
				(font
					(size 0.65 0.65)
					(thickness 0.15)
				)
				(justify left bottom mirror)
			)
		)
		(property "Value" "R_0R_0402"
			(at 0 -1.4 270)
			(layer "B.Fab")
			(hide yes)
			(effects
				(font
					(size 0.7 0.7)
					(thickness 0.15)
				)
				(justify left bottom mirror)
			)
		)
		(property "Datasheet" "https://industrial.panasonic.com/cdbs/www-data/pdf/RDA0000/AOA0000C301.pdf"
			(at 0 0 90)
			(layer "F.Fab")
			(hide yes)
			(effects
				(font
					(size 1.27 1.27)
					(thickness 0.15)
				)
			)
		)
		(property "Description" "SMD Chip Resistor, Jumper, 0 ohm, 100 mW, 0402 [1005 Metric], Thick Film, General Purpose"
			(at 0 0 90)
			(layer "F.Fab")
			(hide yes)
			(effects
				(font
					(size 1.27 1.27)
					(thickness 0.15)
				)
			)
		)
		(property "Author" "Antmicro"
			(at 202.99 -9.39 0)
			(layer "B.Fab")
			(hide yes)
			(effects
				(font
					(size 1 1)
					(thickness 0.15)
				)
				(justify mirror)
			)
		)
		(property "Current" "1A"
			(at 202.99 -9.39 0)
			(layer "B.Fab")
			(hide yes)
			(effects
				(font
					(size 1 1)
					(thickness 0.15)
				)
				(justify mirror)
			)
		)
		(property "License" "Apache-2.0"
			(at 202.99 -9.39 0)
			(layer "B.Fab")
			(hide yes)
			(effects
				(font
					(size 1 1)
					(thickness 0.15)
				)
				(justify mirror)
			)
		)
		(property "MPN" "ERJ2GE0R00X"
			(at 202.99 -9.39 0)
			(layer "B.Fab")
			(hide yes)
			(effects
				(font
					(size 1 1)
					(thickness 0.15)
				)
				(justify mirror)
			)
		)
		(property "Manufacturer" "Panasonic"
			(at 202.99 -9.39 0)
			(layer "B.Fab")
			(hide yes)
			(effects
				(font
					(size 1 1)
					(thickness 0.15)
				)
				(justify mirror)
			)
		)
		(property "Tolerance" "~"
			(at 202.99 -9.39 0)
			(layer "B.Fab")
			(hide yes)
			(effects
				(font
					(size 1 1)
					(thickness 0.15)
				)
				(justify mirror)
			)
		)
		(property "Val" "0R"
			(at 202.99 -9.39 0)
			(layer "B.Fab")
			(hide yes)
			(effects
				(font
					(size 1 1)
					(thickness 0.15)
				)
				(justify mirror)
			)
		)
		(sheetname "/FPGA/")
		(sheetfile "fpga.kicad_sch")
		(attr smd)
		(fp_rect
			(start -0.925 0.47)
			(end 0.925 -0.47)
			(stroke
				(width 0.05)
				(type default)
			)
			(fill no)
			(layer "B.CrtYd")
		)
		(fp_rect
			(start -0.5 0.25)
			(end 0.5 -0.25)
			(stroke
				(width 0.15)
				(type solid)
			)
			(fill no)
			(layer "B.Fab")
		)
		(fp_text user "License: Apache-2.0"
			(at -0.95 -5.169 270)
			(layer "B.Fab")
			(effects
				(font
					(size 0.7 0.7)
					(thickness 0.15)
				)
				(justify left bottom mirror)
			)
		)
		(fp_text user "${REFERENCE}"
			(at -0.95 -3.168 270)
			(layer "B.Fab")
			(effects
				(font
					(size 0.7 0.7)
					(thickness 0.15)
				)
				(justify left bottom mirror)
			)
		)
		(fp_text user "Author: Antmicro"
			(at -0.95 -4.169 270)
			(layer "B.Fab")
			(effects
				(font
					(size 0.7 0.7)
					(thickness 0.15)
				)
				(justify left bottom mirror)
			)
		)
		(pad "1" smd roundrect
			(at -0.48 0 90)
			(size 0.59 0.64)
			(layers "B.Cu" "B.Mask" "B.Paste")
			(roundrect_rratio 0.25)
			(net 41 "/FPGA/~{FLASH_CS}")
			(pintype "passive")
		)
		(pad "2" smd roundrect
			(at 0.48 0 90)
			(size 0.59 0.64)
			(layers "B.Cu" "B.Mask" "B.Paste")
			(roundrect_rratio 0.25)
			(net 306 "Net-(U18-~{CS})")
			(pintype "passive")
		)
	)
	(footprint "antmicro-footprints:TP_SMD_0.75mm"
		(layer "B.Cu")
		(at 101.44 88.2 90)
		(property "Reference" "TP38"
			(at 0.76 0.39 90)
			(layer "B.SilkS")
			(effects
				(font
					(size 0.65 0.65)
					(thickness 0.15)
				)
				(justify right bottom mirror)
			)
		)
		(property "Value" "TP_0.75mm_SMD"
			(at 0 -1.2 90)
			(layer "B.Fab")
			(hide yes)
			(effects
				(font
					(size 0.7 0.7)
					(thickness 0.15)
				)
				(justify right bottom mirror)
			)
		)
		(property "Description" "SMT test point"
			(at 0 0 90)
			(layer "F.Fab")
			(hide yes)
			(effects
				(font
					(size 1.27 1.27)
					(thickness 0.15)
				)
			)
		)
		(property "Author" "Antmicro"
			(at 189.64 -13.24 0)
			(layer "B.Fab")
			(hide yes)
			(effects
				(font
					(size 1 1)
					(thickness 0.15)
				)
				(justify mirror)
			)
		)
		(property "License" "Apache-2.0"
			(at 189.64 -13.24 0)
			(layer "B.Fab")
			(hide yes)
			(effects
				(font
					(size 1 1)
					(thickness 0.15)
				)
				(justify mirror)
			)
		)
		(property "MPN" ""
			(at 189.64 -13.24 0)
			(layer "B.Fab")
			(hide yes)
			(effects
				(font
					(size 1 1)
					(thickness 0.15)
				)
				(justify mirror)
			)
		)
		(property "Manufacturer" ""
			(at 189.64 -13.24 0)
			(layer "B.Fab")
			(hide yes)
			(effects
				(font
					(size 1 1)
					(thickness 0.15)
				)
				(justify mirror)
			)
		)
		(sheetname "/SDI/")
		(sheetfile "sdi.kicad_sch")
		(attr exclude_from_pos_files)
		(fp_circle
			(center 0 0)
			(end 0.475 0)
			(stroke
				(width 0.05)
				(type default)
			)
			(fill no)
			(layer "B.CrtYd")
		)
		(fp_text user "${REFERENCE}"
			(at -0.4 -2.7 270)
			(layer "B.Fab")
			(effects
				(font
					(size 0.7 0.7)
					(thickness 0.15)
				)
				(justify left bottom mirror)
			)
		)
		(fp_text user "Author: Antmicro"
			(at -0.4 -3.901 270)
			(layer "B.Fab")
			(effects
				(font
					(size 0.7 0.7)
					(thickness 0.15)
				)
				(justify left bottom mirror)
			)
		)
		(fp_text user "License: Apache-2.0"
			(at -0.4 -5.101 270)
			(layer "B.Fab")
			(effects
				(font
					(size 0.7 0.7)
					(thickness 0.15)
				)
				(justify left bottom mirror)
			)
		)
		(pad "1" smd circle
			(at 0 0 90)
			(size 0.75 0.75)
			(layers "B.Cu" "B.Mask")
			(net 182 "/SDI/SDIN_TDI")
			(pinfunction "1")
			(pintype "passive")
		)
	)
	(footprint "antmicro-footprints:C_0201"
		(layer "B.Cu")
		(at 126.7 91.01)
		(descr "Capacitor SMD 0201")
		(tags "capacitor SMD 0201")
		(property "Reference" "C98"
			(at -10.47 -12.205736 0)
			(layer "B.SilkS")
			(effects
				(font
					(size 0.65 0.65)
					(thickness 0.15)
				)
				(justify right bottom mirror)
			)
		)
		(property "Value" "C_100n_0201"
			(at 0 -1.4 0)
			(layer "B.Fab")
			(hide yes)
			(effects
				(font
					(size 0.7 0.7)
					(thickness 0.15)
				)
				(justify right bottom mirror)
			)
		)
		(property "Datasheet" "https://www.yageo.com/en/Chart/Download/pdf/CC0201KRX6S5BB104"
			(at 0 0 0)
			(layer "F.Fab")
			(hide yes)
			(effects
				(font
					(size 1.27 1.27)
					(thickness 0.15)
				)
			)
		)
		(property "Description" "SMD Multilayer Ceramic Capacitor, 0.1 µF, 6.3 V, 0201 [0603 Metric], ± 10%, X6S, CC Series"
			(at 0 0 0)
			(layer "F.Fab")
			(hide yes)
			(effects
				(font
					(size 1.27 1.27)
					(thickness 0.15)
				)
			)
		)
		(property "Author" "Antmicro"
			(at 0 0 0)
			(layer "B.Fab")
			(hide yes)
			(effects
				(font
					(size 1 1)
					(thickness 0.15)
				)
				(justify mirror)
			)
		)
		(property "Dielectric" ""
			(at 0 0 0)
			(layer "B.Fab")
			(hide yes)
			(effects
				(font
					(size 1 1)
					(thickness 0.15)
				)
				(justify mirror)
			)
		)
		(property "License" "Apache-2.0"
			(at 0 0 0)
			(layer "B.Fab")
			(hide yes)
			(effects
				(font
					(size 1 1)
					(thickness 0.15)
				)
				(justify mirror)
			)
		)
		(property "MPN" "CC0201KRX6S5BB104"
			(at 0 0 0)
			(layer "B.Fab")
			(hide yes)
			(effects
				(font
					(size 1 1)
					(thickness 0.15)
				)
				(justify mirror)
			)
		)
		(property "Manufacturer" "YAGEO"
			(at 0 0 0)
			(layer "B.Fab")
			(hide yes)
			(effects
				(font
					(size 1 1)
					(thickness 0.15)
				)
				(justify mirror)
			)
		)
		(property "Val" "100n"
			(at 0 0 0)
			(layer "B.Fab")
			(hide yes)
			(effects
				(font
					(size 1 1)
					(thickness 0.15)
				)
				(justify mirror)
			)
		)
		(property "Voltage" ""
			(at 0 0 0)
			(layer "B.Fab")
			(hide yes)
			(effects
				(font
					(size 1 1)
					(thickness 0.15)
				)
				(justify mirror)
			)
		)
		(property "Public" "False"
			(at 0 0 0)
			(unlocked yes)
			(layer "B.Fab")
			(hide yes)
			(effects
				(font
					(size 1 1)
					(thickness 0.15)
				)
				(justify mirror)
			)
		)
		(sheetname "/FPGA Power/")
		(sheetfile "FPGA_Power.kicad_sch")
		(attr smd)
		(fp_rect
			(start -0.7 0.35)
			(end 0.7 -0.35)
			(stroke
				(width 0.05)
				(type default)
			)
			(fill no)
			(layer "B.CrtYd")
		)
		(fp_rect
			(start 0.3 -0.15)
			(end -0.301 0.149)
			(stroke
				(width 0.15)
				(type solid)
			)
			(fill no)
			(layer "B.Fab")
		)
		(fp_text user "Author: Antmicro"
			(at -0.72 -5.4 180)
			(layer "B.Fab")
			(effects
				(font
					(size 0.7 0.7)
					(thickness 0.15)
				)
				(justify left bottom mirror)
			)
		)
		(fp_text user "License: Apache-2.0"
			(at -0.72 -4.4 180)
			(layer "B.Fab")
			(effects
				(font
					(size 0.7 0.7)
					(thickness 0.15)
				)
				(justify left bottom mirror)
			)
		)
		(fp_text user "${REFERENCE}"
			(at -0.72 -3.4 180)
			(layer "B.Fab")
			(effects
				(font
					(size 0.7 0.7)
					(thickness 0.15)
				)
				(justify left bottom mirror)
			)
		)
		(pad "" smd roundrect
			(at -0.349 0.002)
			(size 0.318 0.36)
			(layers "B.Paste")
			(roundrect_rratio 0.25)
		)
		(pad "" smd roundrect
			(at 0.341 0.002)
			(size 0.318 0.36)
			(layers "B.Paste")
			(roundrect_rratio 0.25)
		)
		(pad "1" smd roundrect
			(at -0.321 0.002)
			(size 0.46 0.4)
			(layers "B.Cu" "B.Mask")
			(roundrect_rratio 0.25)
			(net 1 "GND")
			(pintype "passive")
		)
		(pad "2" smd roundrect
			(at 0.32 0.002)
			(size 0.46 0.4)
			(layers "B.Cu" "B.Mask")
			(roundrect_rratio 0.25)
			(net 4 "1V0_Power")
			(pintype "passive")
		)
	)
	(footprint "antmicro-footprints:TP_SMD_0.75mm"
		(layer "B.Cu")
		(at 90.94 88.2 90)
		(property "Reference" "TP39"
			(at 0.76 0.39 90)
			(layer "B.SilkS")
			(effects
				(font
					(size 0.65 0.65)
					(thickness 0.15)
				)
				(justify right bottom mirror)
			)
		)
		(property "Value" "TP_0.75mm_SMD"
			(at 0 -1.2 90)
			(layer "B.Fab")
			(hide yes)
			(effects
				(font
					(size 0.7 0.7)
					(thickness 0.15)
				)
				(justify right bottom mirror)
			)
		)
		(property "Description" "SMT test point"
			(at 0 0 90)
			(layer "F.Fab")
			(hide yes)
			(effects
				(font
					(size 1.27 1.27)
					(thickness 0.15)
				)
			)
		)
		(property "Author" "Antmicro"
			(at 179.14 -2.74 0)
			(layer "B.Fab")
			(hide yes)
			(effects
				(font
					(size 1 1)
					(thickness 0.15)
				)
				(justify mirror)
			)
		)
		(property "License" "Apache-2.0"
			(at 179.14 -2.74 0)
			(layer "B.Fab")
			(hide yes)
			(effects
				(font
					(size 1 1)
					(thickness 0.15)
				)
				(justify mirror)
			)
		)
		(property "MPN" ""
			(at 179.14 -2.74 0)
			(layer "B.Fab")
			(hide yes)
			(effects
				(font
					(size 1 1)
					(thickness 0.15)
				)
				(justify mirror)
			)
		)
		(property "Manufacturer" ""
			(at 179.14 -2.74 0)
			(layer "B.Fab")
			(hide yes)
			(effects
				(font
					(size 1 1)
					(thickness 0.15)
				)
				(justify mirror)
			)
		)
		(sheetname "/SDI/")
		(sheetfile "sdi.kicad_sch")
		(attr exclude_from_pos_files)
		(fp_circle
			(center 0 0)
			(end 0.475 0)
			(stroke
				(width 0.05)
				(type default)
			)
			(fill no)
			(layer "B.CrtYd")
		)
		(fp_text user "${REFERENCE}"
			(at -0.4 -2.7 270)
			(layer "B.Fab")
			(effects
				(font
					(size 0.7 0.7)
					(thickness 0.15)
				)
				(justify left bottom mirror)
			)
		)
		(fp_text user "License: Apache-2.0"
			(at -0.4 -5.101 270)
			(layer "B.Fab")
			(effects
				(font
					(size 0.7 0.7)
					(thickness 0.15)
				)
				(justify left bottom mirror)
			)
		)
		(fp_text user "Author: Antmicro"
			(at -0.4 -3.901 270)
			(layer "B.Fab")
			(effects
				(font
					(size 0.7 0.7)
					(thickness 0.15)
				)
				(justify left bottom mirror)
			)
		)
		(pad "1" smd circle
			(at 0 0 90)
			(size 0.75 0.75)
			(layers "B.Cu" "B.Mask")
			(net 185 "/SDI/SDO_EN{slash}DIS")
			(pinfunction "1")
			(pintype "passive")
		)
	)
	(footprint "antmicro-footprints:R_0402_1005Metric"
		(layer "B.Cu")
		(at 105.89 91.8 90)
		(descr "Resistor SMD 0402")
		(tags "resistor SMD 0402")
		(property "Reference" "R90"
			(at -1.04 0.34 270)
			(layer "B.SilkS")
			(effects
				(font
					(size 0.65 0.65)
					(thickness 0.15)
				)
				(justify left bottom mirror)
			)
		)
		(property "Value" "R_4k7_0402"
			(at 0 -1.4 270)
			(layer "B.Fab")
			(hide yes)
			(effects
				(font
					(size 0.7 0.7)
					(thickness 0.15)
				)
				(justify left bottom mirror)
			)
		)
		(property "Datasheet" "https://www.bourns.com/docs/product-datasheets/cr.pdf"
			(at 0 0 90)
			(layer "F.Fab")
			(hide yes)
			(effects
				(font
					(size 1.27 1.27)
					(thickness 0.15)
				)
			)
		)
		(property "Description" "SMD Chip Resistor, 4.7 kohm, ± 1%, 62.5 mW, 0402 [1005 Metric], Thick Film, General Purpose"
			(at 0 0 90)
			(layer "F.Fab")
			(hide yes)
			(effects
				(font
					(size 1.27 1.27)
					(thickness 0.15)
				)
			)
		)
		(property "Author" "Antmicro"
			(at 197.69 -14.09 0)
			(layer "B.Fab")
			(hide yes)
			(effects
				(font
					(size 1 1)
					(thickness 0.15)
				)
				(justify mirror)
			)
		)
		(property "License" "Apache-2.0"
			(at 197.69 -14.09 0)
			(layer "B.Fab")
			(hide yes)
			(effects
				(font
					(size 1 1)
					(thickness 0.15)
				)
				(justify mirror)
			)
		)
		(property "MPN" "CR0402-FX-4701GLF"
			(at 197.69 -14.09 0)
			(layer "B.Fab")
			(hide yes)
			(effects
				(font
					(size 1 1)
					(thickness 0.15)
				)
				(justify mirror)
			)
		)
		(property "Manufacturer" "Bourns"
			(at 197.69 -14.09 0)
			(layer "B.Fab")
			(hide yes)
			(effects
				(font
					(size 1 1)
					(thickness 0.15)
				)
				(justify mirror)
			)
		)
		(property "Tolerance" "1%"
			(at 197.69 -14.09 0)
			(layer "B.Fab")
			(hide yes)
			(effects
				(font
					(size 1 1)
					(thickness 0.15)
				)
				(justify mirror)
			)
		)
		(property "Val" "4k7"
			(at 197.69 -14.09 0)
			(layer "B.Fab")
			(hide yes)
			(effects
				(font
					(size 1 1)
					(thickness 0.15)
				)
				(justify mirror)
			)
		)
		(sheetname "/FPGA/")
		(sheetfile "fpga.kicad_sch")
		(attr smd)
		(fp_rect
			(start -0.925 0.47)
			(end 0.925 -0.47)
			(stroke
				(width 0.05)
				(type default)
			)
			(fill no)
			(layer "B.CrtYd")
		)
		(fp_rect
			(start -0.5 0.25)
			(end 0.5 -0.25)
			(stroke
				(width 0.15)
				(type solid)
			)
			(fill no)
			(layer "B.Fab")
		)
		(fp_text user "${REFERENCE}"
			(at -0.95 -3.168 270)
			(layer "B.Fab")
			(effects
				(font
					(size 0.7 0.7)
					(thickness 0.15)
				)
				(justify left bottom mirror)
			)
		)
		(fp_text user "Author: Antmicro"
			(at -0.95 -4.169 270)
			(layer "B.Fab")
			(effects
				(font
					(size 0.7 0.7)
					(thickness 0.15)
				)
				(justify left bottom mirror)
			)
		)
		(fp_text user "License: Apache-2.0"
			(at -0.95 -5.169 270)
			(layer "B.Fab")
			(effects
				(font
					(size 0.7 0.7)
					(thickness 0.15)
				)
				(justify left bottom mirror)
			)
		)
		(pad "1" smd roundrect
			(at -0.48 0 90)
			(size 0.59 0.64)
			(layers "B.Cu" "B.Mask" "B.Paste")
			(roundrect_rratio 0.25)
			(net 306 "Net-(U18-~{CS})")
			(pintype "passive")
		)
		(pad "2" smd roundrect
			(at 0.48 0 90)
			(size 0.59 0.64)
			(layers "B.Cu" "B.Mask" "B.Paste")
			(roundrect_rratio 0.25)
			(net 2 "+3V3")
			(pintype "passive")
		)
	)
	(footprint "antmicro-footprints:R_0402_1005Metric"
		(layer "B.Cu")
		(at 161.69 73.9)
		(descr "Resistor SMD 0402")
		(tags "resistor SMD 0402")
		(property "Reference" "R63"
			(at -0.96 0.84 180)
			(layer "B.SilkS")
			(effects
				(font
					(size 0.65 0.65)
					(thickness 0.15)
				)
				(justify left bottom mirror)
			)
		)
		(property "Value" "R_10k_0402"
			(at 0 -1.4 180)
			(layer "B.Fab")
			(hide yes)
			(effects
				(font
					(size 0.7 0.7)
					(thickness 0.15)
				)
				(justify left bottom mirror)
			)
		)
		(property "Datasheet" "https://www.bourns.com/docs/product-datasheets/cr.pdf"
			(at 0 0 0)
			(layer "F.Fab")
			(hide yes)
			(effects
				(font
					(size 1.27 1.27)
					(thickness 0.15)
				)
			)
		)
		(property "Description" "SMD Chip Resistor, 10 kohm, ± 1%, 62.5 mW, 0402 [1005 Metric], Thick Film, General Purpose"
			(at 0 0 0)
			(layer "F.Fab")
			(hide yes)
			(effects
				(font
					(size 1.27 1.27)
					(thickness 0.15)
				)
			)
		)
		(property "Author" "Antmicro"
			(at 0 0 0)
			(layer "B.Fab")
			(hide yes)
			(effects
				(font
					(size 1 1)
					(thickness 0.15)
				)
				(justify mirror)
			)
		)
		(property "License" "Apache-2.0"
			(at 0 0 0)
			(layer "B.Fab")
			(hide yes)
			(effects
				(font
					(size 1 1)
					(thickness 0.15)
				)
				(justify mirror)
			)
		)
		(property "MPN" "CR0402-FX-1002GLF"
			(at 0 0 0)
			(layer "B.Fab")
			(hide yes)
			(effects
				(font
					(size 1 1)
					(thickness 0.15)
				)
				(justify mirror)
			)
		)
		(property "Manufacturer" "Bourns"
			(at 0 0 0)
			(layer "B.Fab")
			(hide yes)
			(effects
				(font
					(size 1 1)
					(thickness 0.15)
				)
				(justify mirror)
			)
		)
		(property "Tolerance" "1%"
			(at 0 0 0)
			(layer "B.Fab")
			(hide yes)
			(effects
				(font
					(size 1 1)
					(thickness 0.15)
				)
				(justify mirror)
			)
		)
		(property "Val" "10k"
			(at 0 0 0)
			(layer "B.Fab")
			(hide yes)
			(effects
				(font
					(size 1 1)
					(thickness 0.15)
				)
				(justify mirror)
			)
		)
		(sheetname "/Power Supply/")
		(sheetfile "supply.kicad_sch")
		(attr smd)
		(fp_rect
			(start -0.925 0.47)
			(end 0.925 -0.47)
			(stroke
				(width 0.05)
				(type default)
			)
			(fill no)
			(layer "B.CrtYd")
		)
		(fp_rect
			(start -0.5 0.25)
			(end 0.5 -0.25)
			(stroke
				(width 0.15)
				(type solid)
			)
			(fill no)
			(layer "B.Fab")
		)
		(fp_text user "${REFERENCE}"
			(at -0.95 -3.168 180)
			(layer "B.Fab")
			(effects
				(font
					(size 0.7 0.7)
					(thickness 0.15)
				)
				(justify left bottom mirror)
			)
		)
		(fp_text user "Author: Antmicro"
			(at -0.95 -4.169 180)
			(layer "B.Fab")
			(effects
				(font
					(size 0.7 0.7)
					(thickness 0.15)
				)
				(justify left bottom mirror)
			)
		)
		(fp_text user "License: Apache-2.0"
			(at -0.95 -5.169 180)
			(layer "B.Fab")
			(effects
				(font
					(size 0.7 0.7)
					(thickness 0.15)
				)
				(justify left bottom mirror)
			)
		)
		(pad "1" smd roundrect
			(at -0.48 0)
			(size 0.59 0.64)
			(layers "B.Cu" "B.Mask" "B.Paste")
			(roundrect_rratio 0.25)
			(net 259 "Net-(Q1-D)")
			(pintype "passive")
		)
		(pad "2" smd roundrect
			(at 0.48 0)
			(size 0.59 0.64)
			(layers "B.Cu" "B.Mask" "B.Paste")
			(roundrect_rratio 0.25)
			(net 329 "/Power Supply/FFC2_5V_1")
			(pintype "passive")
		)
	)
	(footprint "antmicro-footprints:C_0402_1005Metric"
		(layer "B.Cu")
		(at 120.93 62.4)
		(descr "Capacitor SMD 0402")
		(tags "capacitor SMD 0402")
		(property "Reference" "C50"
			(at -4.9 0.34 0)
			(layer "B.SilkS")
			(effects
				(font
					(size 0.65 0.65)
					(thickness 0.15)
				)
				(justify right bottom mirror)
			)
		)
		(property "Value" "C_100n_0402"
			(at 0 -1.4 0)
			(layer "B.Fab")
			(hide yes)
			(effects
				(font
					(size 0.7 0.7)
					(thickness 0.15)
				)
				(justify right bottom mirror)
			)
		)
		(property "Datasheet" "https://www.murata.com/products/productdetail?partno=GRM155R61H104KE14%23"
			(at 0 0 0)
			(layer "F.Fab")
			(hide yes)
			(effects
				(font
					(size 1.27 1.27)
					(thickness 0.15)
				)
			)
		)
		(property "Description" "SMD Multilayer Ceramic Capacitor, 0.1 µF, 50 V, 0402 [1005 Metric], ± 10%, X5R, GRM Series"
			(at 0 0 0)
			(layer "F.Fab")
			(hide yes)
			(effects
				(font
					(size 1.27 1.27)
					(thickness 0.15)
				)
			)
		)
		(property "Author" "Antmicro"
			(at 0 0 0)
			(layer "B.Fab")
			(hide yes)
			(effects
				(font
					(size 1 1)
					(thickness 0.15)
				)
				(justify mirror)
			)
		)
		(property "Dielectric" "X5R"
			(at 0 0 0)
			(layer "B.Fab")
			(hide yes)
			(effects
				(font
					(size 1 1)
					(thickness 0.15)
				)
				(justify mirror)
			)
		)
		(property "License" "Apache-2.0"
			(at 0 0 0)
			(layer "B.Fab")
			(hide yes)
			(effects
				(font
					(size 1 1)
					(thickness 0.15)
				)
				(justify mirror)
			)
		)
		(property "MPN" "GRM155R61H104KE14D"
			(at 0 0 0)
			(layer "B.Fab")
			(hide yes)
			(effects
				(font
					(size 1 1)
					(thickness 0.15)
				)
				(justify mirror)
			)
		)
		(property "Manufacturer" "Murata"
			(at 0 0 0)
			(layer "B.Fab")
			(hide yes)
			(effects
				(font
					(size 1 1)
					(thickness 0.15)
				)
				(justify mirror)
			)
		)
		(property "Val" "100n"
			(at 0 0 0)
			(layer "B.Fab")
			(hide yes)
			(effects
				(font
					(size 1 1)
					(thickness 0.15)
				)
				(justify mirror)
			)
		)
		(property "Voltage" "50V"
			(at 0 0 0)
			(layer "B.Fab")
			(hide yes)
			(effects
				(font
					(size 1 1)
					(thickness 0.15)
				)
				(justify mirror)
			)
		)
		(sheetname "/DDR3/")
		(sheetfile "ddr3.kicad_sch")
		(attr smd)
		(fp_rect
			(start -0.925 0.47)
			(end 0.925 -0.47)
			(stroke
				(width 0.05)
				(type default)
			)
			(fill no)
			(layer "B.CrtYd")
		)
		(fp_line
			(start -0.494 -0.248)
			(end -0.494 0.25)
			(stroke
				(width 0.15)
				(type solid)
			)
			(layer "B.Fab")
		)
		(fp_line
			(start -0.494 0.25)
			(end 0.504 0.25)
			(stroke
				(width 0.15)
				(type solid)
			)
			(layer "B.Fab")
		)
		(fp_line
			(start 0.504 -0.248)
			(end -0.494 -0.248)
			(stroke
				(width 0.15)
				(type solid)
			)
			(layer "B.Fab")
		)
		(fp_line
			(start 0.504 0.25)
			(end 0.504 -0.248)
			(stroke
				(width 0.15)
				(type solid)
			)
			(layer "B.Fab")
		)
		(fp_text user "Author: Antmicro"
			(at -0.939 -3.399 180)
			(layer "B.Fab")
			(effects
				(font
					(size 0.7 0.7)
					(thickness 0.15)
				)
				(justify left bottom mirror)
			)
		)
		(fp_text user "${REFERENCE}"
			(at -0.939 -4.599 180)
			(layer "B.Fab")
			(effects
				(font
					(size 0.7 0.7)
					(thickness 0.15)
				)
				(justify left bottom mirror)
			)
		)
		(fp_text user "License: Apache-2.0"
			(at -0.939 -5.799 180)
			(layer "B.Fab")
			(effects
				(font
					(size 0.7 0.7)
					(thickness 0.15)
				)
				(justify left bottom mirror)
			)
		)
		(pad "1" smd roundrect
			(at -0.48 0)
			(size 0.59 0.64)
			(layers "B.Cu" "B.Mask" "B.Paste")
			(roundrect_rratio 0.25)
			(net 1 "GND")
			(pintype "passive")
		)
		(pad "2" smd roundrect
			(at 0.48 0)
			(size 0.59 0.64)
			(layers "B.Cu" "B.Mask" "B.Paste")
			(roundrect_rratio 0.25)
			(net 5 "Vref")
			(pintype "passive")
		)
	)
	(footprint "antmicro-footprints:TP_SMD_0.75mm"
		(layer "B.Cu")
		(at 94.69 88.95 90)
		(property "Reference" "TP36"
			(at -2.99 0.34 90)
			(layer "B.SilkS")
			(effects
				(font
					(size 0.65 0.65)
					(thickness 0.15)
				)
				(justify right bottom mirror)
			)
		)
		(property "Value" "TP_0.75mm_SMD"
			(at 0 -1.2 90)
			(layer "B.Fab")
			(hide yes)
			(effects
				(font
					(size 0.7 0.7)
					(thickness 0.15)
				)
				(justify right bottom mirror)
			)
		)
		(property "Description" "SMT test point"
			(at 0 0 90)
			(layer "F.Fab")
			(hide yes)
			(effects
				(font
					(size 1.27 1.27)
					(thickness 0.15)
				)
			)
		)
		(property "Author" "Antmicro"
			(at 183.64 -5.74 0)
			(layer "B.Fab")
			(hide yes)
			(effects
				(font
					(size 1 1)
					(thickness 0.15)
				)
				(justify mirror)
			)
		)
		(property "License" "Apache-2.0"
			(at 183.64 -5.74 0)
			(layer "B.Fab")
			(hide yes)
			(effects
				(font
					(size 1 1)
					(thickness 0.15)
				)
				(justify mirror)
			)
		)
		(property "MPN" ""
			(at 183.64 -5.74 0)
			(layer "B.Fab")
			(hide yes)
			(effects
				(font
					(size 1 1)
					(thickness 0.15)
				)
				(justify mirror)
			)
		)
		(property "Manufacturer" ""
			(at 183.64 -5.74 0)
			(layer "B.Fab")
			(hide yes)
			(effects
				(font
					(size 1 1)
					(thickness 0.15)
				)
				(justify mirror)
			)
		)
		(sheetname "/SDI/")
		(sheetfile "sdi.kicad_sch")
		(attr exclude_from_pos_files)
		(fp_circle
			(center 0 0)
			(end 0.475 0)
			(stroke
				(width 0.05)
				(type default)
			)
			(fill no)
			(layer "B.CrtYd")
		)
		(fp_text user "${REFERENCE}"
			(at -0.4 -2.7 270)
			(layer "B.Fab")
			(effects
				(font
					(size 0.7 0.7)
					(thickness 0.15)
				)
				(justify left bottom mirror)
			)
		)
		(fp_text user "Author: Antmicro"
			(at -0.4 -3.901 270)
			(layer "B.Fab")
			(effects
				(font
					(size 0.7 0.7)
					(thickness 0.15)
				)
				(justify left bottom mirror)
			)
		)
		(fp_text user "License: Apache-2.0"
			(at -0.4 -5.101 270)
			(layer "B.Fab")
			(effects
				(font
					(size 0.7 0.7)
					(thickness 0.15)
				)
				(justify left bottom mirror)
			)
		)
		(pad "1" smd circle
			(at 0 0 90)
			(size 0.75 0.75)
			(layers "B.Cu" "B.Mask")
			(net 175 "/SDI/RESET_TRST")
			(pinfunction "1")
			(pintype "passive")
		)
	)
	(footprint "antmicro-footprints:C_0201"
		(layer "B.Cu")
		(at 121.9 93.9 45)
		(descr "Capacitor SMD 0201")
		(tags "capacitor SMD 0201")
		(property "Reference" "C75"
			(at 1.29099 -15.249278 45)
			(layer "B.SilkS")
			(effects
				(font
					(size 0.65 0.65)
					(thickness 0.15)
				)
				(justify right bottom mirror)
			)
		)
		(property "Value" "C_100n_0201"
			(at 0 -1.399999 45)
			(layer "B.Fab")
			(hide yes)
			(effects
				(font
					(size 0.7 0.7)
					(thickness 0.15)
				)
				(justify right bottom mirror)
			)
		)
		(property "Datasheet" "https://www.yageo.com/en/Chart/Download/pdf/CC0201KRX6S5BB104"
			(at 0 0 45)
			(layer "F.Fab")
			(hide yes)
			(effects
				(font
					(size 1.27 1.27)
					(thickness 0.15)
				)
			)
		)
		(property "Description" "SMD Multilayer Ceramic Capacitor, 0.1 µF, 6.3 V, 0201 [0603 Metric], ± 10%, X6S, CC Series"
			(at 0 0 45)
			(layer "F.Fab")
			(hide yes)
			(effects
				(font
					(size 1.27 1.27)
					(thickness 0.15)
				)
			)
		)
		(property "Author" "Antmicro"
			(at 102.10101 -58.693644 0)
			(layer "B.Fab")
			(hide yes)
			(effects
				(font
					(size 1 1)
					(thickness 0.15)
				)
				(justify mirror)
			)
		)
		(property "Dielectric" ""
			(at 102.10101 -58.693644 0)
			(layer "B.Fab")
			(hide yes)
			(effects
				(font
					(size 1 1)
					(thickness 0.15)
				)
				(justify mirror)
			)
		)
		(property "License" "Apache-2.0"
			(at 102.10101 -58.693644 0)
			(layer "B.Fab")
			(hide yes)
			(effects
				(font
					(size 1 1)
					(thickness 0.15)
				)
				(justify mirror)
			)
		)
		(property "MPN" "CC0201KRX6S5BB104"
			(at 102.10101 -58.693644 0)
			(layer "B.Fab")
			(hide yes)
			(effects
				(font
					(size 1 1)
					(thickness 0.15)
				)
				(justify mirror)
			)
		)
		(property "Manufacturer" "YAGEO"
			(at 102.10101 -58.693644 0)
			(layer "B.Fab")
			(hide yes)
			(effects
				(font
					(size 1 1)
					(thickness 0.15)
				)
				(justify mirror)
			)
		)
		(property "Val" "100n"
			(at 102.10101 -58.693644 0)
			(layer "B.Fab")
			(hide yes)
			(effects
				(font
					(size 1 1)
					(thickness 0.15)
				)
				(justify mirror)
			)
		)
		(property "Voltage" ""
			(at 102.10101 -58.693644 0)
			(layer "B.Fab")
			(hide yes)
			(effects
				(font
					(size 1 1)
					(thickness 0.15)
				)
				(justify mirror)
			)
		)
		(property "Public" "False"
			(at 0 0 45)
			(unlocked yes)
			(layer "B.Fab")
			(hide yes)
			(effects
				(font
					(size 1 1)
					(thickness 0.15)
				)
				(justify mirror)
			)
		)
		(sheetname "/FPGA/")
		(sheetfile "fpga.kicad_sch")
		(attr smd)
		(fp_poly
			(pts
				(xy -0.7 0.35) (xy 0.7 0.35) (xy 0.7 -0.35) (xy -0.7 -0.35)
			)
			(stroke
				(width 0.05)
				(type default)
			)
			(fill no)
			(layer "B.CrtYd")
		)
		(fp_poly
			(pts
				(xy 0.3 -0.15) (xy -0.301 -0.15) (xy -0.301 0.149) (xy 0.3 0.149)
			)
			(stroke
				(width 0.15)
				(type solid)
			)
			(fill no)
			(layer "B.Fab")
		)
		(fp_text user "License: Apache-2.0"
			(at -0.72 -4.4 225)
			(layer "B.Fab")
			(effects
				(font
					(size 0.7 0.7)
					(thickness 0.15)
				)
				(justify left bottom mirror)
			)
		)
		(fp_text user "${REFERENCE}"
			(at -0.72 -3.4 225)
			(layer "B.Fab")
			(effects
				(font
					(size 0.7 0.7)
					(thickness 0.15)
				)
				(justify left bottom mirror)
			)
		)
		(fp_text user "Author: Antmicro"
			(at -0.72 -5.400001 225)
			(layer "B.Fab")
			(effects
				(font
					(size 0.7 0.7)
					(thickness 0.15)
				)
				(justify left bottom mirror)
			)
		)
		(pad "" smd roundrect
			(at -0.349 0.002 45)
			(size 0.318 0.36)
			(layers "B.Paste")
			(roundrect_rratio 0.25)
		)
		(pad "" smd roundrect
			(at 0.341 0.002 45)
			(size 0.318 0.36)
			(layers "B.Paste")
			(roundrect_rratio 0.25)
		)
		(pad "1" smd roundrect
			(at -0.321 0.002 45)
			(size 0.46 0.4)
			(layers "B.Cu" "B.Mask")
			(roundrect_rratio 0.25)
			(net 1 "GND")
			(pintype "passive")
		)
		(pad "2" smd roundrect
			(at 0.32 0.002 45)
			(size 0.46 0.4)
			(layers "B.Cu" "B.Mask")
			(roundrect_rratio 0.25)
			(net 2 "+3V3")
			(pintype "passive")
		)
	)
	(footprint "antmicro-footprints:R_0402_1005Metric"
		(layer "B.Cu")
		(at 137.49 57.35)
		(descr "Resistor SMD 0402")
		(tags "resistor SMD 0402")
		(property "Reference" "R1"
			(at 2.34 0.39 180)
			(layer "B.SilkS")
			(effects
				(font
					(size 0.65 0.65)
					(thickness 0.15)
				)
				(justify left bottom mirror)
			)
		)
		(property "Value" "R_100k_0402"
			(at 0 -1.4 180)
			(layer "B.Fab")
			(hide yes)
			(effects
				(font
					(size 0.7 0.7)
					(thickness 0.15)
				)
				(justify left bottom mirror)
			)
		)
		(property "Datasheet" "https://www.bourns.com/docs/product-datasheets/cr.pdf"
			(at 0 0 0)
			(layer "F.Fab")
			(hide yes)
			(effects
				(font
					(size 1.27 1.27)
					(thickness 0.15)
				)
			)
		)
		(property "Description" "SMD Chip Resistor, 100 kohm, ± 1%, 62.5 mW, 0402 [1005 Metric], Thick Film, General Purpose"
			(at 0 0 0)
			(layer "F.Fab")
			(hide yes)
			(effects
				(font
					(size 1.27 1.27)
					(thickness 0.15)
				)
			)
		)
		(property "Author" "Antmicro"
			(at 0 0 0)
			(layer "B.Fab")
			(hide yes)
			(effects
				(font
					(size 1 1)
					(thickness 0.15)
				)
				(justify mirror)
			)
		)
		(property "License" "Apache-2.0"
			(at 0 0 0)
			(layer "B.Fab")
			(hide yes)
			(effects
				(font
					(size 1 1)
					(thickness 0.15)
				)
				(justify mirror)
			)
		)
		(property "MPN" "CR0402-FX-1003GLF"
			(at 0 0 0)
			(layer "B.Fab")
			(hide yes)
			(effects
				(font
					(size 1 1)
					(thickness 0.15)
				)
				(justify mirror)
			)
		)
		(property "Manufacturer" "Bourns"
			(at 0 0 0)
			(layer "B.Fab")
			(hide yes)
			(effects
				(font
					(size 1 1)
					(thickness 0.15)
				)
				(justify mirror)
			)
		)
		(property "Tolerance" "1%"
			(at 0 0 0)
			(layer "B.Fab")
			(hide yes)
			(effects
				(font
					(size 1 1)
					(thickness 0.15)
				)
				(justify mirror)
			)
		)
		(property "Val" "100k"
			(at 0 0 0)
			(layer "B.Fab")
			(hide yes)
			(effects
				(font
					(size 1 1)
					(thickness 0.15)
				)
				(justify mirror)
			)
		)
		(sheetname "/Power Supply/")
		(sheetfile "supply.kicad_sch")
		(attr smd)
		(fp_rect
			(start -0.925 0.47)
			(end 0.925 -0.47)
			(stroke
				(width 0.05)
				(type default)
			)
			(fill no)
			(layer "B.CrtYd")
		)
		(fp_rect
			(start -0.5 0.25)
			(end 0.5 -0.25)
			(stroke
				(width 0.15)
				(type solid)
			)
			(fill no)
			(layer "B.Fab")
		)
		(fp_text user "Author: Antmicro"
			(at -0.95 -4.169 180)
			(layer "B.Fab")
			(effects
				(font
					(size 0.7 0.7)
					(thickness 0.15)
				)
				(justify left bottom mirror)
			)
		)
		(fp_text user "License: Apache-2.0"
			(at -0.95 -5.169 180)
			(layer "B.Fab")
			(effects
				(font
					(size 0.7 0.7)
					(thickness 0.15)
				)
				(justify left bottom mirror)
			)
		)
		(fp_text user "${REFERENCE}"
			(at -0.95 -3.168 180)
			(layer "B.Fab")
			(effects
				(font
					(size 0.7 0.7)
					(thickness 0.15)
				)
				(justify left bottom mirror)
			)
		)
		(pad "1" smd roundrect
			(at -0.48 0)
			(size 0.59 0.64)
			(layers "B.Cu" "B.Mask" "B.Paste")
			(roundrect_rratio 0.25)
			(net 262 "Net-(U1-V_{TT_EN})")
			(pintype "passive")
		)
		(pad "2" smd roundrect
			(at 0.48 0)
			(size 0.59 0.64)
			(layers "B.Cu" "B.Mask" "B.Paste")
			(roundrect_rratio 0.25)
			(net 2 "+3V3")
			(pintype "passive")
		)
	)
	(footprint "antmicro-footprints:C_0201"
		(layer "B.Cu")
		(at 125.9 95.1)
		(descr "Capacitor SMD 0201")
		(tags "capacitor SMD 0201")
		(property "Reference" "C96"
			(at -10.27 -12.095736 0)
			(layer "B.SilkS")
			(effects
				(font
					(size 0.65 0.65)
					(thickness 0.15)
				)
				(justify right bottom mirror)
			)
		)
		(property "Value" "C_100n_0201"
			(at 0 -1.4 0)
			(layer "B.Fab")
			(hide yes)
			(effects
				(font
					(size 0.7 0.7)
					(thickness 0.15)
				)
				(justify right bottom mirror)
			)
		)
		(property "Datasheet" "https://www.yageo.com/en/Chart/Download/pdf/CC0201KRX6S5BB104"
			(at 0 0 0)
			(layer "F.Fab")
			(hide yes)
			(effects
				(font
					(size 1.27 1.27)
					(thickness 0.15)
				)
			)
		)
		(property "Description" "SMD Multilayer Ceramic Capacitor, 0.1 µF, 6.3 V, 0201 [0603 Metric], ± 10%, X6S, CC Series"
			(at 0 0 0)
			(layer "F.Fab")
			(hide yes)
			(effects
				(font
					(size 1.27 1.27)
					(thickness 0.15)
				)
			)
		)
		(property "Author" "Antmicro"
			(at 0 0 0)
			(layer "B.Fab")
			(hide yes)
			(effects
				(font
					(size 1 1)
					(thickness 0.15)
				)
				(justify mirror)
			)
		)
		(property "Dielectric" ""
			(at 0 0 0)
			(layer "B.Fab")
			(hide yes)
			(effects
				(font
					(size 1 1)
					(thickness 0.15)
				)
				(justify mirror)
			)
		)
		(property "License" "Apache-2.0"
			(at 0 0 0)
			(layer "B.Fab")
			(hide yes)
			(effects
				(font
					(size 1 1)
					(thickness 0.15)
				)
				(justify mirror)
			)
		)
		(property "MPN" "CC0201KRX6S5BB104"
			(at 0 0 0)
			(layer "B.Fab")
			(hide yes)
			(effects
				(font
					(size 1 1)
					(thickness 0.15)
				)
				(justify mirror)
			)
		)
		(property "Manufacturer" "YAGEO"
			(at 0 0 0)
			(layer "B.Fab")
			(hide yes)
			(effects
				(font
					(size 1 1)
					(thickness 0.15)
				)
				(justify mirror)
			)
		)
		(property "Val" "100n"
			(at 0 0 0)
			(layer "B.Fab")
			(hide yes)
			(effects
				(font
					(size 1 1)
					(thickness 0.15)
				)
				(justify mirror)
			)
		)
		(property "Voltage" ""
			(at 0 0 0)
			(layer "B.Fab")
			(hide yes)
			(effects
				(font
					(size 1 1)
					(thickness 0.15)
				)
				(justify mirror)
			)
		)
		(property "Public" "False"
			(at 0 0 0)
			(unlocked yes)
			(layer "B.Fab")
			(hide yes)
			(effects
				(font
					(size 1 1)
					(thickness 0.15)
				)
				(justify mirror)
			)
		)
		(sheetname "/FPGA Power/")
		(sheetfile "FPGA_Power.kicad_sch")
		(attr smd)
		(fp_rect
			(start -0.7 0.35)
			(end 0.7 -0.35)
			(stroke
				(width 0.05)
				(type default)
			)
			(fill no)
			(layer "B.CrtYd")
		)
		(fp_rect
			(start 0.3 -0.15)
			(end -0.301 0.149)
			(stroke
				(width 0.15)
				(type solid)
			)
			(fill no)
			(layer "B.Fab")
		)
		(fp_text user "License: Apache-2.0"
			(at -0.72 -4.4 180)
			(layer "B.Fab")
			(effects
				(font
					(size 0.7 0.7)
					(thickness 0.15)
				)
				(justify left bottom mirror)
			)
		)
		(fp_text user "Author: Antmicro"
			(at -0.72 -5.4 180)
			(layer "B.Fab")
			(effects
				(font
					(size 0.7 0.7)
					(thickness 0.15)
				)
				(justify left bottom mirror)
			)
		)
		(fp_text user "${REFERENCE}"
			(at -0.72 -3.4 180)
			(layer "B.Fab")
			(effects
				(font
					(size 0.7 0.7)
					(thickness 0.15)
				)
				(justify left bottom mirror)
			)
		)
		(pad "" smd roundrect
			(at -0.349 0.002)
			(size 0.318 0.36)
			(layers "B.Paste")
			(roundrect_rratio 0.25)
		)
		(pad "" smd roundrect
			(at 0.341 0.002)
			(size 0.318 0.36)
			(layers "B.Paste")
			(roundrect_rratio 0.25)
		)
		(pad "1" smd roundrect
			(at -0.321 0.002)
			(size 0.46 0.4)
			(layers "B.Cu" "B.Mask")
			(roundrect_rratio 0.25)
			(net 1 "GND")
			(pintype "passive")
		)
		(pad "2" smd roundrect
			(at 0.32 0.002)
			(size 0.46 0.4)
			(layers "B.Cu" "B.Mask")
			(roundrect_rratio 0.25)
			(net 12 "/FPGA Power/VCC_ADPHY")
			(pintype "passive")
		)
	)
	(footprint "antmicro-footprints:R_0402_1005Metric"
		(layer "B.Cu")
		(at 94.27 92.25 180)
		(descr "Resistor SMD 0402")
		(tags "resistor SMD 0402")
		(property "Reference" "R139"
			(at 1.04 -0.39 0)
			(layer "B.SilkS")
			(effects
				(font
					(size 0.65 0.65)
					(thickness 0.15)
				)
				(justify left bottom mirror)
			)
		)
		(property "Value" "R_1k_0402"
			(at 0 -1.4 0)
			(layer "B.Fab")
			(hide yes)
			(effects
				(font
					(size 0.7 0.7)
					(thickness 0.15)
				)
				(justify left bottom mirror)
			)
		)
		(property "Datasheet" "https://www.bourns.com/docs/product-datasheets/cr.pdf"
			(at 0 0 180)
			(layer "F.Fab")
			(hide yes)
			(effects
				(font
					(size 1.27 1.27)
					(thickness 0.15)
				)
			)
		)
		(property "Description" "SMD Chip Resistor, 1 kohm, ± 1%, 63 mW, 0402 [1005 Metric], Thick Film, General Purpose"
			(at 0 0 180)
			(layer "F.Fab")
			(hide yes)
			(effects
				(font
					(size 1.27 1.27)
					(thickness 0.15)
				)
			)
		)
		(property "Author" "Antmicro"
			(at 188.54 184.5 0)
			(layer "B.Fab")
			(hide yes)
			(effects
				(font
					(size 1 1)
					(thickness 0.15)
				)
				(justify mirror)
			)
		)
		(property "License" "Apache-2.0"
			(at 188.54 184.5 0)
			(layer "B.Fab")
			(hide yes)
			(effects
				(font
					(size 1 1)
					(thickness 0.15)
				)
				(justify mirror)
			)
		)
		(property "MPN" "CR0402-FX-1001GLF"
			(at 188.54 184.5 0)
			(layer "B.Fab")
			(hide yes)
			(effects
				(font
					(size 1 1)
					(thickness 0.15)
				)
				(justify mirror)
			)
		)
		(property "Manufacturer" "Bourns"
			(at 188.54 184.5 0)
			(layer "B.Fab")
			(hide yes)
			(effects
				(font
					(size 1 1)
					(thickness 0.15)
				)
				(justify mirror)
			)
		)
		(property "Tolerance" "1%"
			(at 188.54 184.5 0)
			(layer "B.Fab")
			(hide yes)
			(effects
				(font
					(size 1 1)
					(thickness 0.15)
				)
				(justify mirror)
			)
		)
		(property "Val" "1k"
			(at 188.54 184.5 0)
			(layer "B.Fab")
			(hide yes)
			(effects
				(font
					(size 1 1)
					(thickness 0.15)
				)
				(justify mirror)
			)
		)
		(sheetname "/SDI/")
		(sheetfile "sdi.kicad_sch")
		(attr smd)
		(fp_rect
			(start -0.925 0.47)
			(end 0.925 -0.47)
			(stroke
				(width 0.05)
				(type default)
			)
			(fill no)
			(layer "B.CrtYd")
		)
		(fp_rect
			(start -0.5 0.25)
			(end 0.5 -0.25)
			(stroke
				(width 0.15)
				(type solid)
			)
			(fill no)
			(layer "B.Fab")
		)
		(fp_text user "Author: Antmicro"
			(at -0.95 -4.169 0)
			(layer "B.Fab")
			(effects
				(font
					(size 0.7 0.7)
					(thickness 0.15)
				)
				(justify left bottom mirror)
			)
		)
		(fp_text user "${REFERENCE}"
			(at -0.95 -3.168 0)
			(layer "B.Fab")
			(effects
				(font
					(size 0.7 0.7)
					(thickness 0.15)
				)
				(justify left bottom mirror)
			)
		)
		(fp_text user "License: Apache-2.0"
			(at -0.95 -5.169 0)
			(layer "B.Fab")
			(effects
				(font
					(size 0.7 0.7)
					(thickness 0.15)
				)
				(justify left bottom mirror)
			)
		)
		(pad "1" smd roundrect
			(at -0.48 0 180)
			(size 0.59 0.64)
			(layers "B.Cu" "B.Mask" "B.Paste")
			(roundrect_rratio 0.25)
			(net 198 "/SDI/AUDIO_EN{slash}~{DIS}")
			(pintype "passive")
		)
		(pad "2" smd roundrect
			(at 0.48 0 180)
			(size 0.59 0.64)
			(layers "B.Cu" "B.Mask" "B.Paste")
			(roundrect_rratio 0.25)
			(net 2 "+3V3")
			(pintype "passive")
		)
	)
	(footprint "antmicro-footprints:TSSOP-14_4.4x5mm_P0.65mm"
		(layer "B.Cu")
		(at 157.53 97.15)
		(descr "TSSOP, 14 Pin (JEDEC MO-153 Var AB-1 https://www.jedec.org/document_search?search_api_views_fulltext=MO-153), generated with kicad-footprint-generator ipc_gullwing_generator.py")
		(tags "TSSOP SO")
		(property "Reference" "U3"
			(at -0.5 -3.21 0)
			(layer "B.SilkS")
			(effects
				(font
					(size 0.65 0.65)
					(thickness 0.15)
				)
				(justify right mirror)
			)
		)
		(property "Value" "LM339_TSSOP_Split"
			(at -3.8 -4.3 0)
			(layer "B.Fab")
			(hide yes)
			(effects
				(font
					(size 0.7 0.7)
					(thickness 0.15)
				)
				(justify right bottom mirror)
			)
		)
		(property "Datasheet" "https://www.ti.com/lit/ds/symlink/lm339b.pdf?ts=1679641364820&ref_url=https%253A%252F%252Fwww.google.com%252F"
			(at 0 0 0)
			(layer "F.Fab")
			(hide yes)
			(effects
				(font
					(size 1.27 1.27)
					(thickness 0.15)
				)
			)
		)
		(property "Description" "Analogue Comparator, Differential, 4 Comparators, 300 ns, 2V to 36V, TSSOP, 14 Pins"
			(at 0 0 0)
			(layer "F.Fab")
			(hide yes)
			(effects
				(font
					(size 1.27 1.27)
					(thickness 0.15)
				)
			)
		)
		(property "Author" "Antmicro"
			(at 0 0 0)
			(layer "B.Fab")
			(hide yes)
			(effects
				(font
					(size 1 1)
					(thickness 0.15)
				)
				(justify mirror)
			)
		)
		(property "License" "Apache-2.0"
			(at 0 0 0)
			(layer "B.Fab")
			(hide yes)
			(effects
				(font
					(size 1 1)
					(thickness 0.15)
				)
				(justify mirror)
			)
		)
		(property "MPN" "LM339PW"
			(at 0 0 0)
			(layer "B.Fab")
			(hide yes)
			(effects
				(font
					(size 1 1)
					(thickness 0.15)
				)
				(justify mirror)
			)
		)
		(property "Manufacturer" "Texas Instruments"
			(at 0 0 0)
			(layer "B.Fab")
			(hide yes)
			(effects
				(font
					(size 1 1)
					(thickness 0.15)
				)
				(justify mirror)
			)
		)
		(sheetname "/Power Supply/")
		(sheetfile "supply.kicad_sch")
		(attr smd)
		(fp_line
			(start -2.9 2.3)
			(end -2.3 2.3)
			(stroke
				(width 0.15)
				(type solid)
			)
			(layer "B.SilkS")
		)
		(fp_line
			(start -2.3 -2.6)
			(end -2.3 -2.3)
			(stroke
				(width 0.15)
				(type solid)
			)
			(layer "B.SilkS")
		)
		(fp_line
			(start -2.3 2.61)
			(end -2.3 2.3)
			(stroke
				(width 0.15)
				(type solid)
			)
			(layer "B.SilkS")
		)
		(fp_line
			(start -2.3 2.61)
			(end 2.3 2.605)
			(stroke
				(width 0.15)
				(type solid)
			)
			(layer "B.SilkS")
		)
		(fp_line
			(start 2.3 -2.6)
			(end -2.3 -2.6)
			(stroke
				(width 0.15)
				(type solid)
			)
			(layer "B.SilkS")
		)
		(fp_line
			(start 2.3 -2.3)
			(end 2.3 -2.6)
			(stroke
				(width 0.15)
				(type solid)
			)
			(layer "B.SilkS")
		)
		(fp_line
			(start 2.3 2.3)
			(end 2.3 2.605)
			(stroke
				(width 0.15)
				(type solid)
			)
			(layer "B.SilkS")
		)
		(fp_line
			(start -3.7 -2.6)
			(end 3.7 -2.6)
			(stroke
				(width 0.05)
				(type solid)
			)
			(layer "B.CrtYd")
		)
		(fp_line
			(start -3.7 2.6)
			(end -3.7 -2.6)
			(stroke
				(width 0.05)
				(type solid)
			)
			(layer "B.CrtYd")
		)
		(fp_line
			(start 3.7 -2.6)
			(end 3.7 2.6)
			(stroke
				(width 0.05)
				(type solid)
			)
			(layer "B.CrtYd")
		)
		(fp_line
			(start 3.7 2.6)
			(end -3.7 2.6)
			(stroke
				(width 0.05)
				(type solid)
			)
			(layer "B.CrtYd")
		)
		(fp_line
			(start -2.202 -2.499)
			(end -2.202 1.5)
			(stroke
				(width 0.15)
				(type solid)
			)
			(layer "B.Fab")
		)
		(fp_line
			(start -2.202 1.5)
			(end -1.2 2.5)
			(stroke
				(width 0.15)
				(type solid)
			)
			(layer "B.Fab")
		)
		(fp_line
			(start -1.2 2.5)
			(end 2.2 2.5)
			(stroke
				(width 0.15)
				(type solid)
			)
			(layer "B.Fab")
		)
		(fp_line
			(start 2.2 -2.499)
			(end -2.202 -2.499)
			(stroke
				(width 0.15)
				(type solid)
			)
			(layer "B.Fab")
		)
		(fp_line
			(start 2.2 2.5)
			(end 2.2 -2.499)
			(stroke
				(width 0.15)
				(type solid)
			)
			(layer "B.Fab")
		)
		(fp_text user "."
			(at -3.7 2.8 0)
			(layer "B.SilkS")
			(effects
				(font
					(size 1 1)
					(thickness 0.15)
				)
				(justify right mirror)
			)
		)
		(pad "1" smd roundrect
			(at -2.863 1.95)
			(size 1.475 0.4)
			(layers "B.Cu" "B.Mask" "B.Paste")
			(roundrect_rratio 0.25)
			(net 58 "Net-(D1-A)")
			(pintype "output")
		)
		(pad "2" smd roundrect
			(at -2.863 1.301)
			(size 1.475 0.4)
			(layers "B.Cu" "B.Mask" "B.Paste")
			(roundrect_rratio 0.25)
			(net 58 "Net-(D1-A)")
			(pintype "output")
		)
		(pad "3" smd roundrect
			(at -2.863 0.652)
			(size 1.475 0.4)
			(layers "B.Cu" "B.Mask" "B.Paste")
			(roundrect_rratio 0.25)
			(net 14 "+5V")
			(pinfunction "V+")
			(pintype "power_in")
		)
		(pad "4" smd roundrect
			(at -2.863 0)
			(size 1.475 0.4)
			(layers "B.Cu" "B.Mask" "B.Paste")
			(roundrect_rratio 0.25)
			(net 141 "/Power Supply/VREF_0V45")
			(pintype "input")
		)
		(pad "5" smd roundrect
			(at -2.863 -0.65)
			(size 1.475 0.4)
			(layers "B.Cu" "B.Mask" "B.Paste")
			(roundrect_rratio 0.25)
			(net 248 "+1V5")
			(pintype "input")
		)
		(pad "6" smd roundrect
			(at -2.863 -1.3)
			(size 1.475 0.4)
			(layers "B.Cu" "B.Mask" "B.Paste")
			(roundrect_rratio 0.25)
			(net 141 "/Power Supply/VREF_0V45")
			(pintype "input")
		)
		(pad "7" smd roundrect
			(at -2.863 -1.949)
			(size 1.475 0.4)
			(layers "B.Cu" "B.Mask" "B.Paste")
			(roundrect_rratio 0.25)
			(net 3 "+1V2")
			(pintype "input")
		)
		(pad "8" smd roundrect
			(at 2.862 -1.949)
			(size 1.475 0.4)
			(layers "B.Cu" "B.Mask" "B.Paste")
			(roundrect_rratio 0.25)
			(net 141 "/Power Supply/VREF_0V45")
			(pintype "input")
		)
		(pad "9" smd roundrect
			(at 2.862 -1.3)
			(size 1.475 0.4)
			(layers "B.Cu" "B.Mask" "B.Paste")
			(roundrect_rratio 0.25)
			(net 6 "Vtt")
			(pintype "input")
		)
		(pad "10" smd roundrect
			(at 2.862 -0.65)
			(size 1.475 0.4)
			(layers "B.Cu" "B.Mask" "B.Paste")
			(roundrect_rratio 0.25)
			(net 1 "GND")
			(pintype "input")
		)
		(pad "11" smd roundrect
			(at 2.862 0)
			(size 1.475 0.4)
			(layers "B.Cu" "B.Mask" "B.Paste")
			(roundrect_rratio 0.25)
			(net 14 "+5V")
			(pintype "input")
		)
		(pad "12" smd roundrect
			(at 2.862 0.652)
			(size 1.475 0.4)
			(layers "B.Cu" "B.Mask" "B.Paste")
			(roundrect_rratio 0.25)
			(net 1 "GND")
			(pinfunction "V-")
			(pintype "power_in")
		)
		(pad "13" smd roundrect
			(at 2.862 1.301)
			(size 1.475 0.4)
			(layers "B.Cu" "B.Mask" "B.Paste")
			(roundrect_rratio 0.25)
			(net 174 "unconnected-(U3-Pad13)")
			(pintype "output+no_connect")
		)
		(pad "14" smd roundrect
			(at 2.862 1.95)
			(size 1.475 0.4)
			(layers "B.Cu" "B.Mask" "B.Paste")
			(roundrect_rratio 0.25)
			(net 58 "Net-(D1-A)")
			(pintype "output")
		)
	)
	(footprint "antmicro-footprints:QFN-16-1EP_4x4mm_P0.65mm"
		(layer "B.Cu")
		(at 145.75 85.25)
		(property "Reference" "U20"
			(at -0.07 3.19 180)
			(layer "B.SilkS")
			(effects
				(font
					(size 0.7 0.7)
					(thickness 0.15)
				)
				(justify left bottom mirror)
			)
		)
		(property "Value" "FT230X_QFN"
			(at 0 -3.3 180)
			(layer "B.Fab")
			(effects
				(font
					(size 0.7 0.7)
					(thickness 0.15)
				)
				(justify left bottom mirror)
			)
		)
		(property "Datasheet" "https://ftdichip.com/wp-content/uploads/2021/10/DS_FT230X.pdf"
			(at 0 0 0)
			(layer "F.Fab")
			(hide yes)
			(effects
				(font
					(size 1.27 1.27)
					(thickness 0.15)
				)
			)
		)
		(property "Description" "USB Interface, USB-UART Converter, USB 2.0, 2.97 V, 5.5 V, QFN, 16 Pins"
			(at 0 0 0)
			(layer "F.Fab")
			(hide yes)
			(effects
				(font
					(size 1.27 1.27)
					(thickness 0.15)
				)
			)
		)
		(property "Author" "Antmicro"
			(at 0 0 0)
			(layer "B.Fab")
			(hide yes)
			(effects
				(font
					(size 1 1)
					(thickness 0.15)
				)
				(justify mirror)
			)
		)
		(property "License" "Apache-2.0"
			(at 0 0 0)
			(layer "B.Fab")
			(hide yes)
			(effects
				(font
					(size 1 1)
					(thickness 0.15)
				)
				(justify mirror)
			)
		)
		(property "MPN" "FT230XQ-R"
			(at 0 0 0)
			(layer "B.Fab")
			(hide yes)
			(effects
				(font
					(size 1 1)
					(thickness 0.15)
				)
				(justify mirror)
			)
		)
		(property "Manufacturer" "FTDI Chip"
			(at 0 0 0)
			(layer "B.Fab")
			(hide yes)
			(effects
				(font
					(size 1 1)
					(thickness 0.15)
				)
				(justify mirror)
			)
		)
		(sheetname "/Peripherals/")
		(sheetfile "peripherals.kicad_sch")
		(attr smd)
		(fp_line
			(start -2.101 -2.1)
			(end -1.5 -2.1)
			(stroke
				(width 0.15)
				(type solid)
			)
			(layer "B.SilkS")
		)
		(fp_line
			(start -2.101 -1.398)
			(end -2.101 -2.1)
			(stroke
				(width 0.15)
				(type solid)
			)
			(layer "B.SilkS")
		)
		(fp_line
			(start -2.1 2.1)
			(end -2.101 1.4)
			(stroke
				(width 0.15)
				(type solid)
			)
			(layer "B.SilkS")
		)
		(fp_line
			(start -1.4 2.1)
			(end -2.1 2.1)
			(stroke
				(width 0.15)
				(type solid)
			)
			(layer "B.SilkS")
		)
		(fp_line
			(start 1.499 -2.1)
			(end 2.1 -2.1)
			(stroke
				(width 0.15)
				(type solid)
			)
			(layer "B.SilkS")
		)
		(fp_line
			(start 1.499 2.101)
			(end 2.1 2.101)
			(stroke
				(width 0.15)
				(type solid)
			)
			(layer "B.SilkS")
		)
		(fp_line
			(start 2.1 -2.1)
			(end 2.1 -1.398)
			(stroke
				(width 0.15)
				(type solid)
			)
			(layer "B.SilkS")
		)
		(fp_line
			(start 2.1 2.101)
			(end 2.1 1.401)
			(stroke
				(width 0.15)
				(type solid)
			)
			(layer "B.SilkS")
		)
		(fp_circle
			(center -2.35 1.4)
			(end -2.3 1.4)
			(stroke
				(width 0.15)
				(type solid)
			)
			(fill yes)
			(layer "B.SilkS")
		)
		(fp_rect
			(start -2.35 2.35)
			(end 2.35 -2.35)
			(stroke
				(width 0.05)
				(type solid)
			)
			(fill no)
			(layer "B.CrtYd")
		)
		(fp_line
			(start -1.5 2)
			(end -2 1.5)
			(stroke
				(width 0.15)
				(type solid)
			)
			(layer "B.Fab")
		)
		(fp_rect
			(start 2 -2)
			(end -2 2)
			(stroke
				(width 0.15)
				(type solid)
			)
			(fill no)
			(layer "B.Fab")
		)
		(fp_text user "Author: Antmicro"
			(at -2.35 -6.799 180)
			(layer "B.Fab")
			(effects
				(font
					(size 0.7 0.7)
					(thickness 0.15)
				)
				(justify left bottom mirror)
			)
		)
		(fp_text user "${REFERENCE}"
			(at -2.35 -5.599 180)
			(layer "B.Fab")
			(effects
				(font
					(size 0.7 0.7)
					(thickness 0.15)
				)
				(justify left bottom mirror)
			)
		)
		(fp_text user "License: Apache-2.0"
			(at -2.35 -7.999 180)
			(layer "B.Fab")
			(effects
				(font
					(size 0.7 0.7)
					(thickness 0.15)
				)
				(justify left bottom mirror)
			)
		)
		(pad "1" smd rect
			(at -1.9 0.975)
			(size 0.8 0.4)
			(layers "B.Cu" "B.Mask" "B.Paste")
			(net 348 "/Peripherals/FTDI_VCCIO")
			(pinfunction "V_{CCIO}")
			(pintype "power_in")
		)
		(pad "2" smd rect
			(at -1.9 0.325)
			(size 0.8 0.4)
			(layers "B.Cu" "B.Mask" "B.Paste")
			(net 355 "RXD")
			(pinfunction "RXD")
			(pintype "input")
		)
		(pad "3" smd rect
			(at -1.9 -0.325)
			(size 0.8 0.4)
			(layers "B.Cu" "B.Mask" "B.Paste")
			(net 1 "GND")
			(pinfunction "GND")
			(pintype "passive")
		)
		(pad "4" smd rect
			(at -1.9 -0.975)
			(size 0.8 0.4)
			(layers "B.Cu" "B.Mask" "B.Paste")
			(net 396 "unconnected-(U20-~{CTS}-Pad4)")
			(pinfunction "~{CTS}")
			(pintype "input+no_connect")
		)
		(pad "5" smd rect
			(at -0.975 -1.9)
			(size 0.4 0.8)
			(layers "B.Cu" "B.Mask" "B.Paste")
			(net 296 "Net-(D13-C)")
			(pinfunction "CBUS2")
			(pintype "bidirectional")
		)
		(pad "6" smd rect
			(at -0.325 -1.9)
			(size 0.4 0.8)
			(layers "B.Cu" "B.Mask" "B.Paste")
			(net 362 "/Peripherals/USB_D2P")
			(pinfunction "D+")
			(pintype "input")
		)
		(pad "7" smd rect
			(at 0.325 -1.9)
			(size 0.4 0.8)
			(layers "B.Cu" "B.Mask" "B.Paste")
			(net 361 "/Peripherals/USB_D2N")
			(pinfunction "D-")
			(pintype "input")
		)
		(pad "8" smd rect
			(at 0.975 -1.9)
			(size 0.4 0.8)
			(layers "B.Cu" "B.Mask" "B.Paste")
			(net 348 "/Peripherals/FTDI_VCCIO")
			(pinfunction "3V3_{OUT}")
			(pintype "passive")
		)
		(pad "9" smd rect
			(at 1.9 -0.975)
			(size 0.8 0.4)
			(layers "B.Cu" "B.Mask" "B.Paste")
			(net 348 "/Peripherals/FTDI_VCCIO")
			(pinfunction "~{RESET}")
			(pintype "input")
		)
		(pad "10" smd rect
			(at 1.9 -0.325)
			(size 0.8 0.4)
			(layers "B.Cu" "B.Mask" "B.Paste")
			(net 325 "USB_POWER_IN")
			(pinfunction "V_{CC}")
			(pintype "power_in")
		)
		(pad "11" smd rect
			(at 1.9 0.325)
			(size 0.8 0.4)
			(layers "B.Cu" "B.Mask" "B.Paste")
			(net 258 "Net-(D12-C)")
			(pinfunction "CBUS1")
			(pintype "bidirectional")
		)
		(pad "12" smd rect
			(at 1.9 0.975)
			(size 0.8 0.4)
			(layers "B.Cu" "B.Mask" "B.Paste")
			(net 379 "Net-(U20-CBUS0)")
			(pinfunction "CBUS0")
			(pintype "bidirectional")
		)
		(pad "13" smd rect
			(at 0.975 1.9)
			(size 0.4 0.8)
			(layers "B.Cu" "B.Mask" "B.Paste")
			(net 1 "GND")
			(pinfunction "GND")
			(pintype "power_in")
		)
		(pad "14" smd rect
			(at 0.325 1.9)
			(size 0.4 0.8)
			(layers "B.Cu" "B.Mask" "B.Paste")
			(net 380 "Net-(U20-CBUS3)")
			(pinfunction "CBUS3")
			(pintype "bidirectional")
		)
		(pad "15" smd rect
			(at -0.325 1.9)
			(size 0.4 0.8)
			(layers "B.Cu" "B.Mask" "B.Paste")
			(net 357 "TXD")
			(pinfunction "TXD")
			(pintype "output")
		)
		(pad "16" smd rect
			(at -0.975 1.9)
			(size 0.4 0.8)
			(layers "B.Cu" "B.Mask" "B.Paste")
			(net 397 "unconnected-(U20-~{RTS}-Pad16)")
			(pinfunction "~{RTS}")
			(pintype "output+no_connect")
		)
		(pad "17" smd rect
			(at 0 0)
			(size 2.3 2.3)
			(layers "B.Cu" "B.Mask" "B.Paste")
			(net 1 "GND")
			(pinfunction "GND")
			(pintype "passive")
		)
	)
	(footprint "antmicro-footprints:C_0201"
		(layer "B.Cu")
		(at 130.7 95.59 180)
		(descr "Capacitor SMD 0201")
		(tags "capacitor SMD 0201")
		(property "Reference" "C101"
			(at 8.07 12.185736 180)
			(layer "B.SilkS")
			(effects
				(font
					(size 0.65 0.65)
					(thickness 0.15)
				)
				(justify left bottom mirror)
			)
		)
		(property "Value" "C_100n_0201"
			(at 0 -1.4 0)
			(layer "B.Fab")
			(hide yes)
			(effects
				(font
					(size 0.7 0.7)
					(thickness 0.15)
				)
				(justify left bottom mirror)
			)
		)
		(property "Datasheet" "https://www.yageo.com/en/Chart/Download/pdf/CC0201KRX6S5BB104"
			(at 0 0 180)
			(layer "F.Fab")
			(hide yes)
			(effects
				(font
					(size 1.27 1.27)
					(thickness 0.15)
				)
			)
		)
		(property "Description" "SMD Multilayer Ceramic Capacitor, 0.1 µF, 6.3 V, 0201 [0603 Metric], ± 10%, X6S, CC Series"
			(at 0 0 180)
			(layer "F.Fab")
			(hide yes)
			(effects
				(font
					(size 1.27 1.27)
					(thickness 0.15)
				)
			)
		)
		(property "Author" "Antmicro"
			(at 261.4 191.18 0)
			(layer "B.Fab")
			(hide yes)
			(effects
				(font
					(size 1 1)
					(thickness 0.15)
				)
				(justify mirror)
			)
		)
		(property "Dielectric" ""
			(at 261.4 191.18 0)
			(layer "B.Fab")
			(hide yes)
			(effects
				(font
					(size 1 1)
					(thickness 0.15)
				)
				(justify mirror)
			)
		)
		(property "License" "Apache-2.0"
			(at 261.4 191.18 0)
			(layer "B.Fab")
			(hide yes)
			(effects
				(font
					(size 1 1)
					(thickness 0.15)
				)
				(justify mirror)
			)
		)
		(property "MPN" "CC0201KRX6S5BB104"
			(at 261.4 191.18 0)
			(layer "B.Fab")
			(hide yes)
			(effects
				(font
					(size 1 1)
					(thickness 0.15)
				)
				(justify mirror)
			)
		)
		(property "Manufacturer" "YAGEO"
			(at 261.4 191.18 0)
			(layer "B.Fab")
			(hide yes)
			(effects
				(font
					(size 1 1)
					(thickness 0.15)
				)
				(justify mirror)
			)
		)
		(property "Val" "100n"
			(at 261.4 191.18 0)
			(layer "B.Fab")
			(hide yes)
			(effects
				(font
					(size 1 1)
					(thickness 0.15)
				)
				(justify mirror)
			)
		)
		(property "Voltage" ""
			(at 261.4 191.18 0)
			(layer "B.Fab")
			(hide yes)
			(effects
				(font
					(size 1 1)
					(thickness 0.15)
				)
				(justify mirror)
			)
		)
		(property "Public" "False"
			(at 0 0 180)
			(unlocked yes)
			(layer "B.Fab")
			(hide yes)
			(effects
				(font
					(size 1 1)
					(thickness 0.15)
				)
				(justify mirror)
			)
		)
		(sheetname "/FPGA Power/")
		(sheetfile "FPGA_Power.kicad_sch")
		(attr smd)
		(fp_rect
			(start -0.7 0.35)
			(end 0.7 -0.35)
			(stroke
				(width 0.05)
				(type default)
			)
			(fill no)
			(layer "B.CrtYd")
		)
		(fp_rect
			(start 0.3 -0.15)
			(end -0.301 0.149)
			(stroke
				(width 0.15)
				(type solid)
			)
			(fill no)
			(layer "B.Fab")
		)
		(fp_text user "Author: Antmicro"
			(at -0.72 -5.4 0)
			(layer "B.Fab")
			(effects
				(font
					(size 0.7 0.7)
					(thickness 0.15)
				)
				(justify left bottom mirror)
			)
		)
		(fp_text user "License: Apache-2.0"
			(at -0.72 -4.4 0)
			(layer "B.Fab")
			(effects
				(font
					(size 0.7 0.7)
					(thickness 0.15)
				)
				(justify left bottom mirror)
			)
		)
		(fp_text user "${REFERENCE}"
			(at -0.72 -3.4 0)
			(layer "B.Fab")
			(effects
				(font
					(size 0.7 0.7)
					(thickness 0.15)
				)
				(justify left bottom mirror)
			)
		)
		(pad "" smd roundrect
			(at -0.349 0.002 180)
			(size 0.318 0.36)
			(layers "B.Paste")
			(roundrect_rratio 0.25)
		)
		(pad "" smd roundrect
			(at 0.341 0.002 180)
			(size 0.318 0.36)
			(layers "B.Paste")
			(roundrect_rratio 0.25)
		)
		(pad "1" smd roundrect
			(at -0.321 0.002 180)
			(size 0.46 0.4)
			(layers "B.Cu" "B.Mask")
			(roundrect_rratio 0.25)
			(net 1 "GND")
			(pintype "passive")
		)
		(pad "2" smd roundrect
			(at 0.32 0.002 180)
			(size 0.46 0.4)
			(layers "B.Cu" "B.Mask")
			(roundrect_rratio 0.25)
			(net 11 "/FPGA Power/VCC_DPHY")
			(pintype "passive")
		)
	)
	(footprint "antmicro-footprints:R_Array_4x0402"
		(layer "B.Cu")
		(at 123.96 60.33 90)
		(property "Reference" "R46"
			(at -1.01 1.87 90)
			(layer "B.SilkS")
			(effects
				(font
					(size 0.65 0.65)
					(thickness 0.15)
				)
				(justify right bottom mirror)
			)
		)
		(property "Value" "R_4x51R_0402_array"
			(at -1.5 -2 90)
			(layer "B.Fab")
			(hide yes)
			(effects
				(font
					(size 0.7 0.7)
					(thickness 0.15)
				)
				(justify right bottom mirror)
			)
		)
		(property "Datasheet" "http://industrial.panasonic.com/cdbs/www-data/pdf/AOC0000/AOC0000C14.pdf"
			(at 0 0 90)
			(layer "F.Fab")
			(hide yes)
			(effects
				(font
					(size 1.27 1.27)
					(thickness 0.15)
				)
			)
		)
		(property "Description" "Fixed Network Resistor, 51 ohm, Isolated, 4 Resistors, 0804 [2010 Metric], Convex, ± 5%"
			(at 0 0 90)
			(layer "F.Fab")
			(hide yes)
			(effects
				(font
					(size 1.27 1.27)
					(thickness 0.15)
				)
			)
		)
		(property "Author" "Antmicro"
			(at 184.29 -63.63 0)
			(layer "B.Fab")
			(hide yes)
			(effects
				(font
					(size 1 1)
					(thickness 0.15)
				)
				(justify mirror)
			)
		)
		(property "License" "Apache-2.0"
			(at 184.29 -63.63 0)
			(layer "B.Fab")
			(hide yes)
			(effects
				(font
					(size 1 1)
					(thickness 0.15)
				)
				(justify mirror)
			)
		)
		(property "MPN" "EXB28V510JX"
			(at 184.29 -63.63 0)
			(layer "B.Fab")
			(hide yes)
			(effects
				(font
					(size 1 1)
					(thickness 0.15)
				)
				(justify mirror)
			)
		)
		(property "Manufacturer" "Panasonic"
			(at 184.29 -63.63 0)
			(layer "B.Fab")
			(hide yes)
			(effects
				(font
					(size 1 1)
					(thickness 0.15)
				)
				(justify mirror)
			)
		)
		(property "Val" "R_4x51R_0402"
			(at 184.29 -63.63 0)
			(layer "B.Fab")
			(hide yes)
			(effects
				(font
					(size 1 1)
					(thickness 0.15)
				)
				(justify mirror)
			)
		)
		(sheetname "/DDR3/")
		(sheetfile "ddr3.kicad_sch")
		(attr smd)
		(fp_line
			(start 1.167 -0.498)
			(end 1.167 0.5)
			(stroke
				(width 0.15)
				(type solid)
			)
			(layer "B.SilkS")
		)
		(fp_line
			(start -1.17 0.5)
			(end -1.17 -0.498)
			(stroke
				(width 0.15)
				(type solid)
			)
			(layer "B.SilkS")
		)
		(fp_rect
			(start -1.2 0.9)
			(end 1.2 -0.9)
			(stroke
				(width 0.05)
				(type solid)
			)
			(fill no)
			(layer "B.CrtYd")
		)
		(fp_line
			(start 0.998 -0.498)
			(end -1 -0.498)
			(stroke
				(width 0.15)
				(type solid)
			)
			(layer "B.Fab")
		)
		(fp_line
			(start -1 -0.498)
			(end -1 0.5)
			(stroke
				(width 0.15)
				(type solid)
			)
			(layer "B.Fab")
		)
		(fp_line
			(start 0.998 0.5)
			(end 0.998 -0.498)
			(stroke
				(width 0.15)
				(type solid)
			)
			(layer "B.Fab")
		)
		(fp_line
			(start -1 0.5)
			(end 0.998 0.5)
			(stroke
				(width 0.15)
				(type solid)
			)
			(layer "B.Fab")
		)
		(pad "1" smd roundrect
			(at -0.802 -0.45 90)
			(size 0.4 0.5)
			(layers "B.Cu" "B.Mask" "B.Paste")
			(roundrect_rratio 0.25)
			(net 152 "/DDR3/DDR3_A10")
			(pinfunction "R1.1")
			(pintype "passive")
		)
		(pad "2" smd roundrect
			(at -0.272 -0.45 90)
			(size 0.4 0.5)
			(layers "B.Cu" "B.Mask" "B.Paste")
			(roundrect_rratio 0.25)
			(net 160 "/DDR3/DDR3_A12")
			(pinfunction "R2.1")
			(pintype "passive")
		)
		(pad "3" smd roundrect
			(at 0.27 -0.45 90)
			(size 0.4 0.5)
			(layers "B.Cu" "B.Mask" "B.Paste")
			(roundrect_rratio 0.25)
			(net 159 "/DDR3/DDR3_BA1")
			(pinfunction "R3.1")
			(pintype "passive")
		)
		(pad "4" smd roundrect
			(at 0.8 -0.45 90)
			(size 0.4 0.5)
			(layers "B.Cu" "B.Mask" "B.Paste")
			(roundrect_rratio 0.25)
			(net 145 "/DDR3/DDR3_A1")
			(pinfunction "R4.1")
			(pintype "passive")
		)
		(pad "5" smd roundrect
			(at 0.8 0.452 90)
			(size 0.4 0.5)
			(layers "B.Cu" "B.Mask" "B.Paste")
			(roundrect_rratio 0.25)
			(net 6 "Vtt")
			(pinfunction "R4.2")
			(pintype "passive")
		)
		(pad "6" smd roundrect
			(at 0.27 0.452 90)
			(size 0.4 0.5)
			(layers "B.Cu" "B.Mask" "B.Paste")
			(roundrect_rratio 0.25)
			(net 6 "Vtt")
			(pinfunction "R3.2")
			(pintype "passive")
		)
		(pad "7" smd roundrect
			(at -0.272 0.452 90)
			(size 0.4 0.5)
			(layers "B.Cu" "B.Mask" "B.Paste")
			(roundrect_rratio 0.25)
			(net 6 "Vtt")
			(pinfunction "R2.2")
			(pintype "passive")
		)
		(pad "8" smd roundrect
			(at -0.802 0.452 90)
			(size 0.4 0.5)
			(layers "B.Cu" "B.Mask" "B.Paste")
			(roundrect_rratio 0.25)
			(net 6 "Vtt")
			(pinfunction "R1.2")
			(pintype "passive")
		)
	)
	(footprint "antmicro-footprints:TP_SMD_0.75mm"
		(layer "B.Cu")
		(at 92.3892 88.2 90)
		(property "Reference" "TP35"
			(at 0.76 0.39 90)
			(layer "B.SilkS")
			(effects
				(font
					(size 0.65 0.65)
					(thickness 0.15)
				)
				(justify right bottom mirror)
			)
		)
		(property "Value" "TP_0.75mm_SMD"
			(at 0 -1.2 90)
			(layer "B.Fab")
			(hide yes)
			(effects
				(font
					(size 0.7 0.7)
					(thickness 0.15)
				)
				(justify right bottom mirror)
			)
		)
		(property "Description" "SMT test point"
			(at 0 0 90)
			(layer "F.Fab")
			(hide yes)
			(effects
				(font
					(size 1.27 1.27)
					(thickness 0.15)
				)
			)
		)
		(property "Author" "Antmicro"
			(at 180.5892 -4.1892 0)
			(layer "B.Fab")
			(hide yes)
			(effects
				(font
					(size 1 1)
					(thickness 0.15)
				)
				(justify mirror)
			)
		)
		(property "License" "Apache-2.0"
			(at 180.5892 -4.1892 0)
			(layer "B.Fab")
			(hide yes)
			(effects
				(font
					(size 1 1)
					(thickness 0.15)
				)
				(justify mirror)
			)
		)
		(property "MPN" ""
			(at 180.5892 -4.1892 0)
			(layer "B.Fab")
			(hide yes)
			(effects
				(font
					(size 1 1)
					(thickness 0.15)
				)
				(justify mirror)
			)
		)
		(property "Manufacturer" ""
			(at 180.5892 -4.1892 0)
			(layer "B.Fab")
			(hide yes)
			(effects
				(font
					(size 1 1)
					(thickness 0.15)
				)
				(justify mirror)
			)
		)
		(sheetname "/SDI/")
		(sheetfile "sdi.kicad_sch")
		(attr exclude_from_pos_files)
		(fp_circle
			(center 0 0)
			(end 0.475 0)
			(stroke
				(width 0.05)
				(type default)
			)
			(fill no)
			(layer "B.CrtYd")
		)
		(fp_text user "License: Apache-2.0"
			(at -0.4 -5.101 270)
			(layer "B.Fab")
			(effects
				(font
					(size 0.7 0.7)
					(thickness 0.15)
				)
				(justify left bottom mirror)
			)
		)
		(fp_text user "${REFERENCE}"
			(at -0.4 -2.7 270)
			(layer "B.Fab")
			(effects
				(font
					(size 0.7 0.7)
					(thickness 0.15)
				)
				(justify left bottom mirror)
			)
		)
		(fp_text user "Author: Antmicro"
			(at -0.4 -3.901 270)
			(layer "B.Fab")
			(effects
				(font
					(size 0.7 0.7)
					(thickness 0.15)
				)
				(justify left bottom mirror)
			)
		)
		(pad "1" smd circle
			(at 0 0 90)
			(size 0.75 0.75)
			(layers "B.Cu" "B.Mask")
			(net 209 "/SDI/~{RC_BYP}")
			(pinfunction "1")
			(pintype "passive")
		)
	)
	(footprint "antmicro-footprints:C_0402_1005Metric"
		(layer "B.Cu")
		(at 127.97 70.95 -90)
		(descr "Capacitor SMD 0402")
		(tags "capacitor SMD 0402")
		(property "Reference" "C47"
			(at -1.01 0.64 90)
			(layer "B.SilkS")
			(effects
				(font
					(size 0.65 0.65)
					(thickness 0.15)
				)
				(justify left bottom mirror)
			)
		)
		(property "Value" "C_100n_0402"
			(at 0 -1.4 90)
			(layer "B.Fab")
			(hide yes)
			(effects
				(font
					(size 0.7 0.7)
					(thickness 0.15)
				)
				(justify left bottom mirror)
			)
		)
		(property "Datasheet" "https://www.murata.com/products/productdetail?partno=GRM155R61H104KE14%23"
			(at 0 0 270)
			(layer "F.Fab")
			(hide yes)
			(effects
				(font
					(size 1.27 1.27)
					(thickness 0.15)
				)
			)
		)
		(property "Description" "SMD Multilayer Ceramic Capacitor, 0.1 µF, 50 V, 0402 [1005 Metric], ± 10%, X5R, GRM Series"
			(at 0 0 270)
			(layer "F.Fab")
			(hide yes)
			(effects
				(font
					(size 1.27 1.27)
					(thickness 0.15)
				)
			)
		)
		(property "Author" "Antmicro"
			(at 57.02 198.92 0)
			(layer "B.Fab")
			(hide yes)
			(effects
				(font
					(size 1 1)
					(thickness 0.15)
				)
				(justify mirror)
			)
		)
		(property "Dielectric" "X5R"
			(at 57.02 198.92 0)
			(layer "B.Fab")
			(hide yes)
			(effects
				(font
					(size 1 1)
					(thickness 0.15)
				)
				(justify mirror)
			)
		)
		(property "License" "Apache-2.0"
			(at 57.02 198.92 0)
			(layer "B.Fab")
			(hide yes)
			(effects
				(font
					(size 1 1)
					(thickness 0.15)
				)
				(justify mirror)
			)
		)
		(property "MPN" "GRM155R61H104KE14D"
			(at 57.02 198.92 0)
			(layer "B.Fab")
			(hide yes)
			(effects
				(font
					(size 1 1)
					(thickness 0.15)
				)
				(justify mirror)
			)
		)
		(property "Manufacturer" "Murata"
			(at 57.02 198.92 0)
			(layer "B.Fab")
			(hide yes)
			(effects
				(font
					(size 1 1)
					(thickness 0.15)
				)
				(justify mirror)
			)
		)
		(property "Val" "100n"
			(at 57.02 198.92 0)
			(layer "B.Fab")
			(hide yes)
			(effects
				(font
					(size 1 1)
					(thickness 0.15)
				)
				(justify mirror)
			)
		)
		(property "Voltage" "50V"
			(at 57.02 198.92 0)
			(layer "B.Fab")
			(hide yes)
			(effects
				(font
					(size 1 1)
					(thickness 0.15)
				)
				(justify mirror)
			)
		)
		(sheetname "/DDR3/")
		(sheetfile "ddr3.kicad_sch")
		(attr smd)
		(fp_rect
			(start -0.925 0.47)
			(end 0.925 -0.47)
			(stroke
				(width 0.05)
				(type default)
			)
			(fill no)
			(layer "B.CrtYd")
		)
		(fp_line
			(start -0.494 0.25)
			(end 0.504 0.25)
			(stroke
				(width 0.15)
				(type solid)
			)
			(layer "B.Fab")
		)
		(fp_line
			(start 0.504 0.25)
			(end 0.504 -0.248)
			(stroke
				(width 0.15)
				(type solid)
			)
			(layer "B.Fab")
		)
		(fp_line
			(start -0.494 -0.248)
			(end -0.494 0.25)
			(stroke
				(width 0.15)
				(type solid)
			)
			(layer "B.Fab")
		)
		(fp_line
			(start 0.504 -0.248)
			(end -0.494 -0.248)
			(stroke
				(width 0.15)
				(type solid)
			)
			(layer "B.Fab")
		)
		(fp_text user "${REFERENCE}"
			(at -0.939 -4.599 90)
			(layer "B.Fab")
			(effects
				(font
					(size 0.7 0.7)
					(thickness 0.15)
				)
				(justify left bottom mirror)
			)
		)
		(fp_text user "License: Apache-2.0"
			(at -0.939 -5.799 90)
			(layer "B.Fab")
			(effects
				(font
					(size 0.7 0.7)
					(thickness 0.15)
				)
				(justify left bottom mirror)
			)
		)
		(fp_text user "Author: Antmicro"
			(at -0.939 -3.399 90)
			(layer "B.Fab")
			(effects
				(font
					(size 0.7 0.7)
					(thickness 0.15)
				)
				(justify left bottom mirror)
			)
		)
		(pad "1" smd roundrect
			(at -0.48 0 270)
			(size 0.59 0.64)
			(layers "B.Cu" "B.Mask" "B.Paste")
			(roundrect_rratio 0.25)
			(net 1 "GND")
			(pintype "passive")
		)
		(pad "2" smd roundrect
			(at 0.48 0 270)
			(size 0.59 0.64)
			(layers "B.Cu" "B.Mask" "B.Paste")
			(roundrect_rratio 0.25)
			(net 248 "+1V5")
			(pintype "passive")
		)
	)
	(footprint "antmicro-footprints:R_0402_1005Metric"
		(layer "B.Cu")
		(at 161.69 74.9)
		(descr "Resistor SMD 0402")
		(tags "resistor SMD 0402")
		(property "Reference" "R6"
			(at -0.96 0.84 180)
			(layer "B.SilkS")
			(effects
				(font
					(size 0.65 0.65)
					(thickness 0.15)
				)
				(justify left bottom mirror)
			)
		)
		(property "Value" "R_10k_0402"
			(at 0 -1.4 180)
			(layer "B.Fab")
			(hide yes)
			(effects
				(font
					(size 0.7 0.7)
					(thickness 0.15)
				)
				(justify left bottom mirror)
			)
		)
		(property "Datasheet" "https://www.bourns.com/docs/product-datasheets/cr.pdf"
			(at 0 0 0)
			(layer "F.Fab")
			(hide yes)
			(effects
				(font
					(size 1.27 1.27)
					(thickness 0.15)
				)
			)
		)
		(property "Description" "SMD Chip Resistor, 10 kohm, ± 1%, 62.5 mW, 0402 [1005 Metric], Thick Film, General Purpose"
			(at 0 0 0)
			(layer "F.Fab")
			(hide yes)
			(effects
				(font
					(size 1.27 1.27)
					(thickness 0.15)
				)
			)
		)
		(property "Author" "Antmicro"
			(at 0 0 0)
			(layer "B.Fab")
			(hide yes)
			(effects
				(font
					(size 1 1)
					(thickness 0.15)
				)
				(justify mirror)
			)
		)
		(property "License" "Apache-2.0"
			(at 0 0 0)
			(layer "B.Fab")
			(hide yes)
			(effects
				(font
					(size 1 1)
					(thickness 0.15)
				)
				(justify mirror)
			)
		)
		(property "MPN" "CR0402-FX-1002GLF"
			(at 0 0 0)
			(layer "B.Fab")
			(hide yes)
			(effects
				(font
					(size 1 1)
					(thickness 0.15)
				)
				(justify mirror)
			)
		)
		(property "Manufacturer" "Bourns"
			(at 0 0 0)
			(layer "B.Fab")
			(hide yes)
			(effects
				(font
					(size 1 1)
					(thickness 0.15)
				)
				(justify mirror)
			)
		)
		(property "Tolerance" "1%"
			(at 0 0 0)
			(layer "B.Fab")
			(hide yes)
			(effects
				(font
					(size 1 1)
					(thickness 0.15)
				)
				(justify mirror)
			)
		)
		(property "Val" "10k"
			(at 0 0 0)
			(layer "B.Fab")
			(hide yes)
			(effects
				(font
					(size 1 1)
					(thickness 0.15)
				)
				(justify mirror)
			)
		)
		(sheetname "/Power Supply/")
		(sheetfile "supply.kicad_sch")
		(attr smd)
		(fp_rect
			(start -0.925 0.47)
			(end 0.925 -0.47)
			(stroke
				(width 0.05)
				(type default)
			)
			(fill no)
			(layer "B.CrtYd")
		)
		(fp_rect
			(start -0.5 0.25)
			(end 0.5 -0.25)
			(stroke
				(width 0.15)
				(type solid)
			)
			(fill no)
			(layer "B.Fab")
		)
		(fp_text user "License: Apache-2.0"
			(at -0.95 -5.169 180)
			(layer "B.Fab")
			(effects
				(font
					(size 0.7 0.7)
					(thickness 0.15)
				)
				(justify left bottom mirror)
			)
		)
		(fp_text user "Author: Antmicro"
			(at -0.95 -4.169 180)
			(layer "B.Fab")
			(effects
				(font
					(size 0.7 0.7)
					(thickness 0.15)
				)
				(justify left bottom mirror)
			)
		)
		(fp_text user "${REFERENCE}"
			(at -0.95 -3.168 180)
			(layer "B.Fab")
			(effects
				(font
					(size 0.7 0.7)
					(thickness 0.15)
				)
				(justify left bottom mirror)
			)
		)
		(pad "1" smd roundrect
			(at -0.48 0)
			(size 0.59 0.64)
			(layers "B.Cu" "B.Mask" "B.Paste")
			(roundrect_rratio 0.25)
			(net 305 "/Power Supply/~{FAULT}")
			(pintype "passive")
		)
		(pad "2" smd roundrect
			(at 0.48 0)
			(size 0.59 0.64)
			(layers "B.Cu" "B.Mask" "B.Paste")
			(roundrect_rratio 0.25)
			(net 329 "/Power Supply/FFC2_5V_1")
			(pintype "passive")
		)
	)
	(footprint "antmicro-footprints:C_0201"
		(layer "B.Cu")
		(at 123.5 92.3 -135)
		(descr "Capacitor SMD 0201")
		(tags "capacitor SMD 0201")
		(property "Reference" "C84"
			(at -3.174909 15.153298 45)
			(layer "B.SilkS")
			(effects
				(font
					(size 0.65 0.65)
					(thickness 0.15)
				)
				(justify left bottom mirror)
			)
		)
		(property "Value" "C_100n_0201"
			(at 0 -1.399999 45)
			(layer "B.Fab")
			(hide yes)
			(effects
				(font
					(size 0.7 0.7)
					(thickness 0.15)
				)
				(justify left bottom mirror)
			)
		)
		(property "Datasheet" "https://www.yageo.com/en/Chart/Download/pdf/CC0201KRX6S5BB104"
			(at 0 0 225)
			(layer "F.Fab")
			(hide yes)
			(effects
				(font
					(size 1.27 1.27)
					(thickness 0.15)
				)
			)
		)
		(property "Description" "SMD Multilayer Ceramic Capacitor, 0.1 µF, 6.3 V, 0201 [0603 Metric], ± 10%, X6S, CC Series"
			(at 0 0 225)
			(layer "F.Fab")
			(hide yes)
			(effects
				(font
					(size 1.27 1.27)
					(thickness 0.15)
				)
			)
		)
		(property "Author" "Antmicro"
			(at 145.561732 244.893643 0)
			(layer "B.Fab")
			(hide yes)
			(effects
				(font
					(size 1 1)
					(thickness 0.15)
				)
				(justify mirror)
			)
		)
		(property "Dielectric" ""
			(at 145.561732 244.893643 0)
			(layer "B.Fab")
			(hide yes)
			(effects
				(font
					(size 1 1)
					(thickness 0.15)
				)
				(justify mirror)
			)
		)
		(property "License" "Apache-2.0"
			(at 145.561732 244.893643 0)
			(layer "B.Fab")
			(hide yes)
			(effects
				(font
					(size 1 1)
					(thickness 0.15)
				)
				(justify mirror)
			)
		)
		(property "MPN" "CC0201KRX6S5BB104"
			(at 145.561732 244.893643 0)
			(layer "B.Fab")
			(hide yes)
			(effects
				(font
					(size 1 1)
					(thickness 0.15)
				)
				(justify mirror)
			)
		)
		(property "Manufacturer" "YAGEO"
			(at 145.561732 244.893643 0)
			(layer "B.Fab")
			(hide yes)
			(effects
				(font
					(size 1 1)
					(thickness 0.15)
				)
				(justify mirror)
			)
		)
		(property "Val" "100n"
			(at 145.561732 244.893643 0)
			(layer "B.Fab")
			(hide yes)
			(effects
				(font
					(size 1 1)
					(thickness 0.15)
				)
				(justify mirror)
			)
		)
		(property "Voltage" ""
			(at 145.561732 244.893643 0)
			(layer "B.Fab")
			(hide yes)
			(effects
				(font
					(size 1 1)
					(thickness 0.15)
				)
				(justify mirror)
			)
		)
		(property "Public" "False"
			(at 0 0 225)
			(unlocked yes)
			(layer "B.Fab")
			(hide yes)
			(effects
				(font
					(size 1 1)
					(thickness 0.15)
				)
				(justify mirror)
			)
		)
		(sheetname "/Peripherals/")
		(sheetfile "peripherals.kicad_sch")
		(attr smd)
		(fp_poly
			(pts
				(xy -0.7 0.35) (xy 0.7 0.35) (xy 0.7 -0.35) (xy -0.7 -0.35)
			)
			(stroke
				(width 0.05)
				(type default)
			)
			(fill no)
			(layer "B.CrtYd")
		)
		(fp_poly
			(pts
				(xy 0.3 -0.15) (xy -0.301 -0.15) (xy -0.301 0.149) (xy 0.3 0.149)
			)
			(stroke
				(width 0.15)
				(type solid)
			)
			(fill no)
			(layer "B.Fab")
		)
		(fp_text user "${REFERENCE}"
			(at -0.72 -3.4 45)
			(layer "B.Fab")
			(effects
				(font
					(size 0.7 0.7)
					(thickness 0.15)
				)
				(justify left bottom mirror)
			)
		)
		(fp_text user "License: Apache-2.0"
			(at -0.72 -4.4 45)
			(layer "B.Fab")
			(effects
				(font
					(size 0.7 0.7)
					(thickness 0.15)
				)
				(justify left bottom mirror)
			)
		)
		(fp_text user "Author: Antmicro"
			(at -0.72 -5.400001 45)
			(layer "B.Fab")
			(effects
				(font
					(size 0.7 0.7)
					(thickness 0.15)
				)
				(justify left bottom mirror)
			)
		)
		(pad "" smd roundrect
			(at -0.349 0.002 225)
			(size 0.318 0.36)
			(layers "B.Paste")
			(roundrect_rratio 0.25)
		)
		(pad "" smd roundrect
			(at 0.341 0.002 225)
			(size 0.318 0.36)
			(layers "B.Paste")
			(roundrect_rratio 0.25)
		)
		(pad "1" smd roundrect
			(at -0.321 0.002 225)
			(size 0.46 0.4)
			(layers "B.Cu" "B.Mask")
			(roundrect_rratio 0.25)
			(net 1 "GND")
			(pintype "passive")
		)
		(pad "2" smd roundrect
			(at 0.32 0.002 225)
			(size 0.46 0.4)
			(layers "B.Cu" "B.Mask")
			(roundrect_rratio 0.25)
			(net 2 "+3V3")
			(pintype "passive")
		)
	)
	(footprint "antmicro-footprints:R_0402_1005Metric"
		(layer "B.Cu")
		(at 105.19 96.8 -90)
		(descr "Resistor SMD 0402")
		(tags "resistor SMD 0402")
		(property "Reference" "R75"
			(at 0.94 -0.34 90)
			(layer "B.SilkS")
			(effects
				(font
					(size 0.65 0.65)
					(thickness 0.15)
				)
				(justify left bottom mirror)
			)
		)
		(property "Value" "R_0R_0402"
			(at 0 -1.4 90)
			(layer "B.Fab")
			(hide yes)
			(effects
				(font
					(size 0.7 0.7)
					(thickness 0.15)
				)
				(justify left bottom mirror)
			)
		)
		(property "Datasheet" "https://industrial.panasonic.com/cdbs/www-data/pdf/RDA0000/AOA0000C301.pdf"
			(at 0 0 270)
			(layer "F.Fab")
			(hide yes)
			(effects
				(font
					(size 1.27 1.27)
					(thickness 0.15)
				)
			)
		)
		(property "Description" "SMD Chip Resistor, Jumper, 0 ohm, 100 mW, 0402 [1005 Metric], Thick Film, General Purpose"
			(at 0 0 270)
			(layer "F.Fab")
			(hide yes)
			(effects
				(font
					(size 1.27 1.27)
					(thickness 0.15)
				)
			)
		)
		(property "Author" "Antmicro"
			(at 8.39 201.99 0)
			(layer "B.Fab")
			(hide yes)
			(effects
				(font
					(size 1 1)
					(thickness 0.15)
				)
				(justify mirror)
			)
		)
		(property "Current" "1A"
			(at 8.39 201.99 0)
			(layer "B.Fab")
			(hide yes)
			(effects
				(font
					(size 1 1)
					(thickness 0.15)
				)
				(justify mirror)
			)
		)
		(property "License" "Apache-2.0"
			(at 8.39 201.99 0)
			(layer "B.Fab")
			(hide yes)
			(effects
				(font
					(size 1 1)
					(thickness 0.15)
				)
				(justify mirror)
			)
		)
		(property "MPN" "ERJ2GE0R00X"
			(at 8.39 201.99 0)
			(layer "B.Fab")
			(hide yes)
			(effects
				(font
					(size 1 1)
					(thickness 0.15)
				)
				(justify mirror)
			)
		)
		(property "Manufacturer" "Panasonic"
			(at 8.39 201.99 0)
			(layer "B.Fab")
			(hide yes)
			(effects
				(font
					(size 1 1)
					(thickness 0.15)
				)
				(justify mirror)
			)
		)
		(property "Tolerance" "~"
			(at 8.39 201.99 0)
			(layer "B.Fab")
			(hide yes)
			(effects
				(font
					(size 1 1)
					(thickness 0.15)
				)
				(justify mirror)
			)
		)
		(property "Val" "0R"
			(at 8.39 201.99 0)
			(layer "B.Fab")
			(hide yes)
			(effects
				(font
					(size 1 1)
					(thickness 0.15)
				)
				(justify mirror)
			)
		)
		(sheetname "/FPGA/")
		(sheetfile "fpga.kicad_sch")
		(attr smd)
		(fp_rect
			(start -0.925 0.47)
			(end 0.925 -0.47)
			(stroke
				(width 0.05)
				(type default)
			)
			(fill no)
			(layer "B.CrtYd")
		)
		(fp_rect
			(start -0.5 0.25)
			(end 0.5 -0.25)
			(stroke
				(width 0.15)
				(type solid)
			)
			(fill no)
			(layer "B.Fab")
		)
		(fp_text user "License: Apache-2.0"
			(at -0.95 -5.169 90)
			(layer "B.Fab")
			(effects
				(font
					(size 0.7 0.7)
					(thickness 0.15)
				)
				(justify left bottom mirror)
			)
		)
		(fp_text user "Author: Antmicro"
			(at -0.95 -4.169 90)
			(layer "B.Fab")
			(effects
				(font
					(size 0.7 0.7)
					(thickness 0.15)
				)
				(justify left bottom mirror)
			)
		)
		(fp_text user "${REFERENCE}"
			(at -0.95 -3.168 90)
			(layer "B.Fab")
			(effects
				(font
					(size 0.7 0.7)
					(thickness 0.15)
				)
				(justify left bottom mirror)
			)
		)
		(pad "1" smd roundrect
			(at -0.48 0 270)
			(size 0.59 0.64)
			(layers "B.Cu" "B.Mask" "B.Paste")
			(roundrect_rratio 0.25)
			(net 303 "Net-(U18-SCLK)")
			(pintype "passive")
		)
		(pad "2" smd roundrect
			(at 0.48 0 270)
			(size 0.59 0.64)
			(layers "B.Cu" "B.Mask" "B.Paste")
			(roundrect_rratio 0.25)
			(net 39 "/FPGA/SPI_CLK")
			(pintype "passive")
		)
	)
	(footprint "antmicro-footprints:C_0402_1005Metric"
		(layer "B.Cu")
		(at 128.37 59.62 -45)
		(descr "Capacitor SMD 0402")
		(tags "capacitor SMD 0402")
		(property "Reference" "C43"
			(at 0.374767 1.378858 135)
			(layer "B.SilkS")
			(effects
				(font
					(size 0.65 0.65)
					(thickness 0.15)
				)
				(justify left bottom mirror)
			)
		)
		(property "Value" "C_100n_0402"
			(at 0 -1.399999 135)
			(layer "B.Fab")
			(hide yes)
			(effects
				(font
					(size 0.7 0.7)
					(thickness 0.15)
				)
				(justify left bottom mirror)
			)
		)
		(property "Datasheet" "https://www.murata.com/products/productdetail?partno=GRM155R61H104KE14%23"
			(at 0 0 315)
			(layer "F.Fab")
			(hide yes)
			(effects
				(font
					(size 1.27 1.27)
					(thickness 0.15)
				)
			)
		)
		(property "Description" "SMD Multilayer Ceramic Capacitor, 0.1 µF, 50 V, 0402 [1005 Metric], ± 10%, X5R, GRM Series"
			(at 0 0 315)
			(layer "F.Fab")
			(hide yes)
			(effects
				(font
					(size 1.27 1.27)
					(thickness 0.15)
				)
			)
		)
		(property "Author" "Antmicro"
			(at -4.559004 108.233591 0)
			(layer "B.Fab")
			(hide yes)
			(effects
				(font
					(size 1 1)
					(thickness 0.15)
				)
				(justify mirror)
			)
		)
		(property "Dielectric" "X5R"
			(at -4.559004 108.233591 0)
			(layer "B.Fab")
			(hide yes)
			(effects
				(font
					(size 1 1)
					(thickness 0.15)
				)
				(justify mirror)
			)
		)
		(property "License" "Apache-2.0"
			(at -4.559004 108.233591 0)
			(layer "B.Fab")
			(hide yes)
			(effects
				(font
					(size 1 1)
					(thickness 0.15)
				)
				(justify mirror)
			)
		)
		(property "MPN" "GRM155R61H104KE14D"
			(at -4.559004 108.233591 0)
			(layer "B.Fab")
			(hide yes)
			(effects
				(font
					(size 1 1)
					(thickness 0.15)
				)
				(justify mirror)
			)
		)
		(property "Manufacturer" "Murata"
			(at -4.559004 108.233591 0)
			(layer "B.Fab")
			(hide yes)
			(effects
				(font
					(size 1 1)
					(thickness 0.15)
				)
				(justify mirror)
			)
		)
		(property "Val" "100n"
			(at -4.559004 108.233591 0)
			(layer "B.Fab")
			(hide yes)
			(effects
				(font
					(size 1 1)
					(thickness 0.15)
				)
				(justify mirror)
			)
		)
		(property "Voltage" "50V"
			(at -4.559004 108.233591 0)
			(layer "B.Fab")
			(hide yes)
			(effects
				(font
					(size 1 1)
					(thickness 0.15)
				)
				(justify mirror)
			)
		)
		(sheetname "/DDR3/")
		(sheetfile "ddr3.kicad_sch")
		(attr smd)
		(fp_poly
			(pts
				(xy -0.925 0.47) (xy 0.925 0.47) (xy 0.925 -0.47) (xy -0.925 -0.47)
			)
			(stroke
				(width 0.05)
				(type default)
			)
			(fill no)
			(layer "B.CrtYd")
		)
		(fp_line
			(start -0.494 0.25)
			(end 0.504 0.25)
			(stroke
				(width 0.15)
				(type solid)
			)
			(layer "B.Fab")
		)
		(fp_line
			(start -0.494 -0.248)
			(end -0.494 0.25)
			(stroke
				(width 0.15)
				(type solid)
			)
			(layer "B.Fab")
		)
		(fp_line
			(start 0.504 0.25)
			(end 0.504 -0.248)
			(stroke
				(width 0.15)
				(type solid)
			)
			(layer "B.Fab")
		)
		(fp_line
			(start 0.504 -0.248)
			(end -0.494 -0.248)
			(stroke
				(width 0.15)
				(type solid)
			)
			(layer "B.Fab")
		)
		(fp_text user "${REFERENCE}"
			(at -0.939 -4.599 135)
			(layer "B.Fab")
			(effects
				(font
					(size 0.7 0.7)
					(thickness 0.15)
				)
				(justify left bottom mirror)
			)
		)
		(fp_text user "Author: Antmicro"
			(at -0.939 -3.399 135)
			(layer "B.Fab")
			(effects
				(font
					(size 0.7 0.7)
					(thickness 0.15)
				)
				(justify left bottom mirror)
			)
		)
		(fp_text user "License: Apache-2.0"
			(at -0.939 -5.799 135)
			(layer "B.Fab")
			(effects
				(font
					(size 0.7 0.7)
					(thickness 0.15)
				)
				(justify left bottom mirror)
			)
		)
		(pad "1" smd roundrect
			(at -0.48 0 315)
			(size 0.59 0.64)
			(layers "B.Cu" "B.Mask" "B.Paste")
			(roundrect_rratio 0.25)
			(net 1 "GND")
			(pintype "passive")
		)
		(pad "2" smd roundrect
			(at 0.48 0 315)
			(size 0.59 0.64)
			(layers "B.Cu" "B.Mask" "B.Paste")
			(roundrect_rratio 0.25)
			(net 248 "+1V5")
			(pintype "passive")
		)
	)
	(footprint "antmicro-footprints:C_0402_1005Metric"
		(layer "B.Cu")
		(at 162.43 100.95 -90)
		(descr "Capacitor SMD 0402")
		(tags "capacitor SMD 0402")
		(property "Reference" "C2"
			(at -0.61 -1.3 90)
			(layer "B.SilkS")
			(effects
				(font
					(size 0.65 0.65)
					(thickness 0.15)
				)
				(justify left bottom mirror)
			)
		)
		(property "Value" "C_100n_0402"
			(at 0 -1.4 90)
			(layer "B.Fab")
			(hide yes)
			(effects
				(font
					(size 0.7 0.7)
					(thickness 0.15)
				)
				(justify left bottom mirror)
			)
		)
		(property "Datasheet" "https://www.murata.com/products/productdetail?partno=GRM155R61H104KE14%23"
			(at 0 0 270)
			(layer "F.Fab")
			(hide yes)
			(effects
				(font
					(size 1.27 1.27)
					(thickness 0.15)
				)
			)
		)
		(property "Description" "SMD Multilayer Ceramic Capacitor, 0.1 µF, 50 V, 0402 [1005 Metric], ± 10%, X5R, GRM Series"
			(at 0 0 270)
			(layer "F.Fab")
			(hide yes)
			(effects
				(font
					(size 1.27 1.27)
					(thickness 0.15)
				)
			)
		)
		(property "Author" "Antmicro"
			(at 61.48 263.38 0)
			(layer "B.Fab")
			(hide yes)
			(effects
				(font
					(size 1 1)
					(thickness 0.15)
				)
				(justify mirror)
			)
		)
		(property "Dielectric" "X5R"
			(at 61.48 263.38 0)
			(layer "B.Fab")
			(hide yes)
			(effects
				(font
					(size 1 1)
					(thickness 0.15)
				)
				(justify mirror)
			)
		)
		(property "License" "Apache-2.0"
			(at 61.48 263.38 0)
			(layer "B.Fab")
			(hide yes)
			(effects
				(font
					(size 1 1)
					(thickness 0.15)
				)
				(justify mirror)
			)
		)
		(property "MPN" "GRM155R61H104KE14D"
			(at 61.48 263.38 0)
			(layer "B.Fab")
			(hide yes)
			(effects
				(font
					(size 1 1)
					(thickness 0.15)
				)
				(justify mirror)
			)
		)
		(property "Manufacturer" "Murata"
			(at 61.48 263.38 0)
			(layer "B.Fab")
			(hide yes)
			(effects
				(font
					(size 1 1)
					(thickness 0.15)
				)
				(justify mirror)
			)
		)
		(property "Val" "100n"
			(at 61.48 263.38 0)
			(layer "B.Fab")
			(hide yes)
			(effects
				(font
					(size 1 1)
					(thickness 0.15)
				)
				(justify mirror)
			)
		)
		(property "Voltage" "50V"
			(at 61.48 263.38 0)
			(layer "B.Fab")
			(hide yes)
			(effects
				(font
					(size 1 1)
					(thickness 0.15)
				)
				(justify mirror)
			)
		)
		(sheetname "/Power Supply/")
		(sheetfile "supply.kicad_sch")
		(attr smd)
		(fp_rect
			(start -0.925 0.47)
			(end 0.925 -0.47)
			(stroke
				(width 0.05)
				(type default)
			)
			(fill no)
			(layer "B.CrtYd")
		)
		(fp_line
			(start -0.494 0.25)
			(end 0.504 0.25)
			(stroke
				(width 0.15)
				(type solid)
			)
			(layer "B.Fab")
		)
		(fp_line
			(start 0.504 0.25)
			(end 0.504 -0.248)
			(stroke
				(width 0.15)
				(type solid)
			)
			(layer "B.Fab")
		)
		(fp_line
			(start -0.494 -0.248)
			(end -0.494 0.25)
			(stroke
				(width 0.15)
				(type solid)
			)
			(layer "B.Fab")
		)
		(fp_line
			(start 0.504 -0.248)
			(end -0.494 -0.248)
			(stroke
				(width 0.15)
				(type solid)
			)
			(layer "B.Fab")
		)
		(fp_text user "${REFERENCE}"
			(at -0.939 -4.599 90)
			(layer "B.Fab")
			(effects
				(font
					(size 0.7 0.7)
					(thickness 0.15)
				)
				(justify left bottom mirror)
			)
		)
		(fp_text user "Author: Antmicro"
			(at -0.939 -3.399 90)
			(layer "B.Fab")
			(effects
				(font
					(size 0.7 0.7)
					(thickness 0.15)
				)
				(justify left bottom mirror)
			)
		)
		(fp_text user "License: Apache-2.0"
			(at -0.939 -5.799 90)
			(layer "B.Fab")
			(effects
				(font
					(size 0.7 0.7)
					(thickness 0.15)
				)
				(justify left bottom mirror)
			)
		)
		(pad "1" smd roundrect
			(at -0.48 0 270)
			(size 0.59 0.64)
			(layers "B.Cu" "B.Mask" "B.Paste")
			(roundrect_rratio 0.25)
			(net 1 "GND")
			(pintype "passive")
		)
		(pad "2" smd roundrect
			(at 0.48 0 270)
			(size 0.59 0.64)
			(layers "B.Cu" "B.Mask" "B.Paste")
			(roundrect_rratio 0.25)
			(net 14 "+5V")
			(pintype "passive")
		)
	)
	(footprint "antmicro-footprints:R_0402_1005Metric"
		(layer "B.Cu")
		(at 162.43 104.865 90)
		(descr "Resistor SMD 0402")
		(tags "resistor SMD 0402")
		(property "Reference" "R3"
			(at 0.725 1.3 270)
			(layer "B.SilkS")
			(effects
				(font
					(size 0.65 0.65)
					(thickness 0.15)
				)
				(justify left bottom mirror)
			)
		)
		(property "Value" "R_1k_0402"
			(at 0 -1.4 270)
			(layer "B.Fab")
			(hide yes)
			(effects
				(font
					(size 0.7 0.7)
					(thickness 0.15)
				)
				(justify left bottom mirror)
			)
		)
		(property "Datasheet" "https://www.bourns.com/docs/product-datasheets/cr.pdf"
			(at 0 0 90)
			(layer "F.Fab")
			(hide yes)
			(effects
				(font
					(size 1.27 1.27)
					(thickness 0.15)
				)
			)
		)
		(property "Description" "SMD Chip Resistor, 1 kohm, ± 1%, 63 mW, 0402 [1005 Metric], Thick Film, General Purpose"
			(at 0 0 90)
			(layer "F.Fab")
			(hide yes)
			(effects
				(font
					(size 1.27 1.27)
					(thickness 0.15)
				)
			)
		)
		(property "Author" "Antmicro"
			(at 267.295 -57.565 0)
			(layer "B.Fab")
			(hide yes)
			(effects
				(font
					(size 1 1)
					(thickness 0.15)
				)
				(justify mirror)
			)
		)
		(property "License" "Apache-2.0"
			(at 267.295 -57.565 0)
			(layer "B.Fab")
			(hide yes)
			(effects
				(font
					(size 1 1)
					(thickness 0.15)
				)
				(justify mirror)
			)
		)
		(property "MPN" "CR0402-FX-1001GLF"
			(at 267.295 -57.565 0)
			(layer "B.Fab")
			(hide yes)
			(effects
				(font
					(size 1 1)
					(thickness 0.15)
				)
				(justify mirror)
			)
		)
		(property "Manufacturer" "Bourns"
			(at 267.295 -57.565 0)
			(layer "B.Fab")
			(hide yes)
			(effects
				(font
					(size 1 1)
					(thickness 0.15)
				)
				(justify mirror)
			)
		)
		(property "Tolerance" "1%"
			(at 267.295 -57.565 0)
			(layer "B.Fab")
			(hide yes)
			(effects
				(font
					(size 1 1)
					(thickness 0.15)
				)
				(justify mirror)
			)
		)
		(property "Val" "1k"
			(at 267.295 -57.565 0)
			(layer "B.Fab")
			(hide yes)
			(effects
				(font
					(size 1 1)
					(thickness 0.15)
				)
				(justify mirror)
			)
		)
		(sheetname "/Power Supply/")
		(sheetfile "supply.kicad_sch")
		(attr smd)
		(fp_rect
			(start -0.925 0.47)
			(end 0.925 -0.47)
			(stroke
				(width 0.05)
				(type default)
			)
			(fill no)
			(layer "B.CrtYd")
		)
		(fp_rect
			(start -0.5 0.25)
			(end 0.5 -0.25)
			(stroke
				(width 0.15)
				(type solid)
			)
			(fill no)
			(layer "B.Fab")
		)
		(fp_text user "License: Apache-2.0"
			(at -0.95 -5.169 270)
			(layer "B.Fab")
			(effects
				(font
					(size 0.7 0.7)
					(thickness 0.15)
				)
				(justify left bottom mirror)
			)
		)
		(fp_text user "${REFERENCE}"
			(at -0.95 -3.168 270)
			(layer "B.Fab")
			(effects
				(font
					(size 0.7 0.7)
					(thickness 0.15)
				)
				(justify left bottom mirror)
			)
		)
		(fp_text user "Author: Antmicro"
			(at -0.95 -4.169 270)
			(layer "B.Fab")
			(effects
				(font
					(size 0.7 0.7)
					(thickness 0.15)
				)
				(justify left bottom mirror)
			)
		)
		(pad "1" smd roundrect
			(at -0.48 0 90)
			(size 0.59 0.64)
			(layers "B.Cu" "B.Mask" "B.Paste")
			(roundrect_rratio 0.25)
			(net 1 "GND")
			(pintype "passive")
		)
		(pad "2" smd roundrect
			(at 0.48 0 90)
			(size 0.59 0.64)
			(layers "B.Cu" "B.Mask" "B.Paste")
			(roundrect_rratio 0.25)
			(net 141 "/Power Supply/VREF_0V45")
			(pintype "passive")
		)
	)
	(footprint "antmicro-footprints:C_0201"
		(layer "B.Cu")
		(at 124.35 86.75 45)
		(descr "Capacitor SMD 0201")
		(tags "capacitor SMD 0201")
		(property "Reference" "C35"
			(at 1.149569 -15.178567 45)
			(layer "B.SilkS")
			(effects
				(font
					(size 0.65 0.65)
					(thickness 0.15)
				)
				(justify right bottom mirror)
			)
		)
		(property "Value" "C_100n_0201"
			(at 0 -1.399999 45)
			(layer "B.Fab")
			(hide yes)
			(effects
				(font
					(size 0.7 0.7)
					(thickness 0.15)
				)
				(justify right bottom mirror)
			)
		)
		(property "Datasheet" "https://www.yageo.com/en/Chart/Download/pdf/CC0201KRX6S5BB104"
			(at 0 0 45)
			(layer "F.Fab")
			(hide yes)
			(effects
				(font
					(size 1.27 1.27)
					(thickness 0.15)
				)
			)
		)
		(property "Description" "SMD Multilayer Ceramic Capacitor, 0.1 µF, 6.3 V, 0201 [0603 Metric], ± 10%, X6S, CC Series"
			(at 0 0 45)
			(layer "F.Fab")
			(hide yes)
			(effects
				(font
					(size 1.27 1.27)
					(thickness 0.15)
				)
			)
		)
		(property "Author" "Antmicro"
			(at 97.762785 -62.520241 0)
			(layer "B.Fab")
			(hide yes)
			(effects
				(font
					(size 1 1)
					(thickness 0.15)
				)
				(justify mirror)
			)
		)
		(property "Dielectric" ""
			(at 97.762785 -62.520241 0)
			(layer "B.Fab")
			(hide yes)
			(effects
				(font
					(size 1 1)
					(thickness 0.15)
				)
				(justify mirror)
			)
		)
		(property "License" "Apache-2.0"
			(at 97.762785 -62.520241 0)
			(layer "B.Fab")
			(hide yes)
			(effects
				(font
					(size 1 1)
					(thickness 0.15)
				)
				(justify mirror)
			)
		)
		(property "MPN" "CC0201KRX6S5BB104"
			(at 97.762785 -62.520241 0)
			(layer "B.Fab")
			(hide yes)
			(effects
				(font
					(size 1 1)
					(thickness 0.15)
				)
				(justify mirror)
			)
		)
		(property "Manufacturer" "YAGEO"
			(at 97.762785 -62.520241 0)
			(layer "B.Fab")
			(hide yes)
			(effects
				(font
					(size 1 1)
					(thickness 0.15)
				)
				(justify mirror)
			)
		)
		(property "Val" "100n"
			(at 97.762785 -62.520241 0)
			(layer "B.Fab")
			(hide yes)
			(effects
				(font
					(size 1 1)
					(thickness 0.15)
				)
				(justify mirror)
			)
		)
		(property "Voltage" ""
			(at 97.762785 -62.520241 0)
			(layer "B.Fab")
			(hide yes)
			(effects
				(font
					(size 1 1)
					(thickness 0.15)
				)
				(justify mirror)
			)
		)
		(property "Public" "False"
			(at 0 0 45)
			(unlocked yes)
			(layer "B.Fab")
			(hide yes)
			(effects
				(font
					(size 1 1)
					(thickness 0.15)
				)
				(justify mirror)
			)
		)
		(sheetname "/DDR3/")
		(sheetfile "ddr3.kicad_sch")
		(attr smd)
		(fp_poly
			(pts
				(xy -0.7 0.35) (xy 0.7 0.35) (xy 0.7 -0.35) (xy -0.7 -0.35)
			)
			(stroke
				(width 0.05)
				(type default)
			)
			(fill no)
			(layer "B.CrtYd")
		)
		(fp_poly
			(pts
				(xy 0.3 -0.15) (xy -0.301 -0.15) (xy -0.301 0.149) (xy 0.3 0.149)
			)
			(stroke
				(width 0.15)
				(type solid)
			)
			(fill no)
			(layer "B.Fab")
		)
		(fp_text user "Author: Antmicro"
			(at -0.72 -5.400001 225)
			(layer "B.Fab")
			(effects
				(font
					(size 0.7 0.7)
					(thickness 0.15)
				)
				(justify left bottom mirror)
			)
		)
		(fp_text user "${REFERENCE}"
			(at -0.72 -3.4 225)
			(layer "B.Fab")
			(effects
				(font
					(size 0.7 0.7)
					(thickness 0.15)
				)
				(justify left bottom mirror)
			)
		)
		(fp_text user "License: Apache-2.0"
			(at -0.72 -4.4 225)
			(layer "B.Fab")
			(effects
				(font
					(size 0.7 0.7)
					(thickness 0.15)
				)
				(justify left bottom mirror)
			)
		)
		(pad "" smd roundrect
			(at -0.349 0.002 45)
			(size 0.318 0.36)
			(layers "B.Paste")
			(roundrect_rratio 0.25)
		)
		(pad "" smd roundrect
			(at 0.341 0.002 45)
			(size 0.318 0.36)
			(layers "B.Paste")
			(roundrect_rratio 0.25)
		)
		(pad "1" smd roundrect
			(at -0.321 0.002 45)
			(size 0.46 0.4)
			(layers "B.Cu" "B.Mask")
			(roundrect_rratio 0.25)
			(net 1 "GND")
			(pintype "passive")
		)
		(pad "2" smd roundrect
			(at 0.32 0.002 45)
			(size 0.46 0.4)
			(layers "B.Cu" "B.Mask")
			(roundrect_rratio 0.25)
			(net 248 "+1V5")
			(pintype "passive")
		)
	)
	(footprint "antmicro-footprints:C_0402_1005Metric"
		(layer "B.Cu")
		(at 101.8 76.38 180)
		(descr "Capacitor SMD 0402")
		(tags "capacitor SMD 0402")
		(property "Reference" "C74"
			(at -1.03 0.64 0)
			(layer "B.SilkS")
			(effects
				(font
					(size 0.65 0.65)
					(thickness 0.15)
				)
				(justify left bottom mirror)
			)
		)
		(property "Value" "C_100n_0402"
			(at 0 -1.4 0)
			(layer "B.Fab")
			(hide yes)
			(effects
				(font
					(size 0.7 0.7)
					(thickness 0.15)
				)
				(justify left bottom mirror)
			)
		)
		(property "Datasheet" "https://www.murata.com/products/productdetail?partno=GRM155R61H104KE14%23"
			(at 0 0 180)
			(layer "F.Fab")
			(hide yes)
			(effects
				(font
					(size 1.27 1.27)
					(thickness 0.15)
				)
			)
		)
		(property "Description" "SMD Multilayer Ceramic Capacitor, 0.1 µF, 50 V, 0402 [1005 Metric], ± 10%, X5R, GRM Series"
			(at 0 0 180)
			(layer "F.Fab")
			(hide yes)
			(effects
				(font
					(size 1.27 1.27)
					(thickness 0.15)
				)
			)
		)
		(property "Author" "Antmicro"
			(at 203.6 152.76 0)
			(layer "B.Fab")
			(hide yes)
			(effects
				(font
					(size 1 1)
					(thickness 0.15)
				)
				(justify mirror)
			)
		)
		(property "Dielectric" "X5R"
			(at 203.6 152.76 0)
			(layer "B.Fab")
			(hide yes)
			(effects
				(font
					(size 1 1)
					(thickness 0.15)
				)
				(justify mirror)
			)
		)
		(property "License" "Apache-2.0"
			(at 203.6 152.76 0)
			(layer "B.Fab")
			(hide yes)
			(effects
				(font
					(size 1 1)
					(thickness 0.15)
				)
				(justify mirror)
			)
		)
		(property "MPN" "GRM155R61H104KE14D"
			(at 203.6 152.76 0)
			(layer "B.Fab")
			(hide yes)
			(effects
				(font
					(size 1 1)
					(thickness 0.15)
				)
				(justify mirror)
			)
		)
		(property "Manufacturer" "Murata"
			(at 203.6 152.76 0)
			(layer "B.Fab")
			(hide yes)
			(effects
				(font
					(size 1 1)
					(thickness 0.15)
				)
				(justify mirror)
			)
		)
		(property "Val" "100n"
			(at 203.6 152.76 0)
			(layer "B.Fab")
			(hide yes)
			(effects
				(font
					(size 1 1)
					(thickness 0.15)
				)
				(justify mirror)
			)
		)
		(property "Voltage" "50V"
			(at 203.6 152.76 0)
			(layer "B.Fab")
			(hide yes)
			(effects
				(font
					(size 1 1)
					(thickness 0.15)
				)
				(justify mirror)
			)
		)
		(sheetname "/SDI/")
		(sheetfile "sdi.kicad_sch")
		(attr smd)
		(fp_rect
			(start -0.925 0.47)
			(end 0.925 -0.47)
			(stroke
				(width 0.05)
				(type default)
			)
			(fill no)
			(layer "B.CrtYd")
		)
		(fp_line
			(start 0.504 0.25)
			(end 0.504 -0.248)
			(stroke
				(width 0.15)
				(type solid)
			)
			(layer "B.Fab")
		)
		(fp_line
			(start 0.504 -0.248)
			(end -0.494 -0.248)
			(stroke
				(width 0.15)
				(type solid)
			)
			(layer "B.Fab")
		)
		(fp_line
			(start -0.494 0.25)
			(end 0.504 0.25)
			(stroke
				(width 0.15)
				(type solid)
			)
			(layer "B.Fab")
		)
		(fp_line
			(start -0.494 -0.248)
			(end -0.494 0.25)
			(stroke
				(width 0.15)
				(type solid)
			)
			(layer "B.Fab")
		)
		(fp_text user "License: Apache-2.0"
			(at -0.939 -5.799 0)
			(layer "B.Fab")
			(effects
				(font
					(size 0.7 0.7)
					(thickness 0.15)
				)
				(justify left bottom mirror)
			)
		)
		(fp_text user "Author: Antmicro"
			(at -0.939 -3.399 0)
			(layer "B.Fab")
			(effects
				(font
					(size 0.7 0.7)
					(thickness 0.15)
				)
				(justify left bottom mirror)
			)
		)
		(fp_text user "${REFERENCE}"
			(at -0.939 -4.599 0)
			(layer "B.Fab")
			(effects
				(font
					(size 0.7 0.7)
					(thickness 0.15)
				)
				(justify left bottom mirror)
			)
		)
		(pad "1" smd roundrect
			(at -0.48 0 180)
			(size 0.59 0.64)
			(layers "B.Cu" "B.Mask" "B.Paste")
			(roundrect_rratio 0.25)
			(net 1 "GND")
			(pintype "passive")
		)
		(pad "2" smd roundrect
			(at 0.48 0 180)
			(size 0.59 0.64)
			(layers "B.Cu" "B.Mask" "B.Paste")
			(roundrect_rratio 0.25)
			(net 2 "+3V3")
			(pintype "passive")
		)
	)
	(footprint "antmicro-footprints:C_0201"
		(layer "B.Cu")
		(at 126.3 89.9 90)
		(descr "Capacitor SMD 0201")
		(tags "capacitor SMD 0201")
		(property "Reference" "C118"
			(at 11.895736 -9.17 90)
			(layer "B.SilkS")
			(effects
				(font
					(size 0.65 0.65)
					(thickness 0.15)
				)
				(justify right bottom mirror)
			)
		)
		(property "Value" "C_100n_0201"
			(at 0 -1.4 90)
			(layer "B.Fab")
			(hide yes)
			(effects
				(font
					(size 0.7 0.7)
					(thickness 0.15)
				)
				(justify right bottom mirror)
			)
		)
		(property "Datasheet" "https://www.yageo.com/en/Chart/Download/pdf/CC0201KRX6S5BB104"
			(at 0 0 90)
			(layer "F.Fab")
			(hide yes)
			(effects
				(font
					(size 1.27 1.27)
					(thickness 0.15)
				)
			)
		)
		(property "Description" "SMD Multilayer Ceramic Capacitor, 0.1 µF, 6.3 V, 0201 [0603 Metric], ± 10%, X6S, CC Series"
			(at 0 0 90)
			(layer "F.Fab")
			(hide yes)
			(effects
				(font
					(size 1.27 1.27)
					(thickness 0.15)
				)
			)
		)
		(property "Author" "Antmicro"
			(at 216.2 -36.4 0)
			(layer "B.Fab")
			(hide yes)
			(effects
				(font
					(size 1 1)
					(thickness 0.15)
				)
				(justify mirror)
			)
		)
		(property "Dielectric" ""
			(at 216.2 -36.4 0)
			(layer "B.Fab")
			(hide yes)
			(effects
				(font
					(size 1 1)
					(thickness 0.15)
				)
				(justify mirror)
			)
		)
		(property "License" "Apache-2.0"
			(at 216.2 -36.4 0)
			(layer "B.Fab")
			(hide yes)
			(effects
				(font
					(size 1 1)
					(thickness 0.15)
				)
				(justify mirror)
			)
		)
		(property "MPN" "CC0201KRX6S5BB104"
			(at 216.2 -36.4 0)
			(layer "B.Fab")
			(hide yes)
			(effects
				(font
					(size 1 1)
					(thickness 0.15)
				)
				(justify mirror)
			)
		)
		(property "Manufacturer" "YAGEO"
			(at 216.2 -36.4 0)
			(layer "B.Fab")
			(hide yes)
			(effects
				(font
					(size 1 1)
					(thickness 0.15)
				)
				(justify mirror)
			)
		)
		(property "Val" "100n"
			(at 216.2 -36.4 0)
			(layer "B.Fab")
			(hide yes)
			(effects
				(font
					(size 1 1)
					(thickness 0.15)
				)
				(justify mirror)
			)
		)
		(property "Voltage" ""
			(at 216.2 -36.4 0)
			(layer "B.Fab")
			(hide yes)
			(effects
				(font
					(size 1 1)
					(thickness 0.15)
				)
				(justify mirror)
			)
		)
		(property "Public" "False"
			(at 0 0 90)
			(unlocked yes)
			(layer "B.Fab")
			(hide yes)
			(effects
				(font
					(size 1 1)
					(thickness 0.15)
				)
				(justify mirror)
			)
		)
		(sheetname "/FPGA Power/")
		(sheetfile "FPGA_Power.kicad_sch")
		(attr smd)
		(fp_rect
			(start -0.7 0.35)
			(end 0.7 -0.35)
			(stroke
				(width 0.05)
				(type default)
			)
			(fill no)
			(layer "B.CrtYd")
		)
		(fp_rect
			(start 0.3 -0.15)
			(end -0.301 0.149)
			(stroke
				(width 0.15)
				(type solid)
			)
			(fill no)
			(layer "B.Fab")
		)
		(fp_text user "License: Apache-2.0"
			(at -0.72 -4.4 270)
			(layer "B.Fab")
			(effects
				(font
					(size 0.7 0.7)
					(thickness 0.15)
				)
				(justify left bottom mirror)
			)
		)
		(fp_text user "Author: Antmicro"
			(at -0.72 -5.4 270)
			(layer "B.Fab")
			(effects
				(font
					(size 0.7 0.7)
					(thickness 0.15)
				)
				(justify left bottom mirror)
			)
		)
		(fp_text user "${REFERENCE}"
			(at -0.72 -3.4 270)
			(layer "B.Fab")
			(effects
				(font
					(size 0.7 0.7)
					(thickness 0.15)
				)
				(justify left bottom mirror)
			)
		)
		(pad "" smd roundrect
			(at -0.349 0.002 90)
			(size 0.318 0.36)
			(layers "B.Paste")
			(roundrect_rratio 0.25)
		)
		(pad "" smd roundrect
			(at 0.341 0.002 90)
			(size 0.318 0.36)
			(layers "B.Paste")
			(roundrect_rratio 0.25)
		)
		(pad "1" smd roundrect
			(at -0.321 0.002 90)
			(size 0.46 0.4)
			(layers "B.Cu" "B.Mask")
			(roundrect_rratio 0.25)
			(net 1 "GND")
			(pintype "passive")
		)
		(pad "2" smd roundrect
			(at 0.32 0.002 90)
			(size 0.46 0.4)
			(layers "B.Cu" "B.Mask")
			(roundrect_rratio 0.25)
			(net 9 "/FPGA Power/VCC_AUX")
			(pintype "passive")
		)
	)
	(footprint "antmicro-footprints:R_0402_1005Metric"
		(layer "B.Cu")
		(at 94.255 93.25)
		(descr "Resistor SMD 0402")
		(tags "resistor SMD 0402")
		(property "Reference" "R140"
			(at -1.025 0.29 180)
			(layer "B.SilkS")
			(effects
				(font
					(size 0.65 0.65)
					(thickness 0.15)
				)
				(justify left bottom mirror)
			)
		)
		(property "Value" "R_1k_0402"
			(at 0 -1.4 180)
			(layer "B.Fab")
			(hide yes)
			(effects
				(font
					(size 0.7 0.7)
					(thickness 0.15)
				)
				(justify left bottom mirror)
			)
		)
		(property "Datasheet" "https://www.bourns.com/docs/product-datasheets/cr.pdf"
			(at 0 0 0)
			(layer "F.Fab")
			(hide yes)
			(effects
				(font
					(size 1.27 1.27)
					(thickness 0.15)
				)
			)
		)
		(property "Description" "SMD Chip Resistor, 1 kohm, ± 1%, 63 mW, 0402 [1005 Metric], Thick Film, General Purpose"
			(at 0 0 0)
			(layer "F.Fab")
			(hide yes)
			(effects
				(font
					(size 1.27 1.27)
					(thickness 0.15)
				)
			)
		)
		(property "Author" "Antmicro"
			(at 0 0 0)
			(layer "B.Fab")
			(hide yes)
			(effects
				(font
					(size 1 1)
					(thickness 0.15)
				)
				(justify mirror)
			)
		)
		(property "License" "Apache-2.0"
			(at 0 0 0)
			(layer "B.Fab")
			(hide yes)
			(effects
				(font
					(size 1 1)
					(thickness 0.15)
				)
				(justify mirror)
			)
		)
		(property "MPN" "CR0402-FX-1001GLF"
			(at 0 0 0)
			(layer "B.Fab")
			(hide yes)
			(effects
				(font
					(size 1 1)
					(thickness 0.15)
				)
				(justify mirror)
			)
		)
		(property "Manufacturer" "Bourns"
			(at 0 0 0)
			(layer "B.Fab")
			(hide yes)
			(effects
				(font
					(size 1 1)
					(thickness 0.15)
				)
				(justify mirror)
			)
		)
		(property "Tolerance" "1%"
			(at 0 0 0)
			(layer "B.Fab")
			(hide yes)
			(effects
				(font
					(size 1 1)
					(thickness 0.15)
				)
				(justify mirror)
			)
		)
		(property "Val" "1k"
			(at 0 0 0)
			(layer "B.Fab")
			(hide yes)
			(effects
				(font
					(size 1 1)
					(thickness 0.15)
				)
				(justify mirror)
			)
		)
		(sheetname "/SDI/")
		(sheetfile "sdi.kicad_sch")
		(attr smd exclude_from_pos_files exclude_from_bom dnp)
		(fp_rect
			(start -0.925 0.47)
			(end 0.925 -0.47)
			(stroke
				(width 0.05)
				(type default)
			)
			(fill no)
			(layer "B.CrtYd")
		)
		(fp_rect
			(start -0.5 0.25)
			(end 0.5 -0.25)
			(stroke
				(width 0.15)
				(type solid)
			)
			(fill no)
			(layer "B.Fab")
		)
		(fp_text user "License: Apache-2.0"
			(at -0.95 -5.169 180)
			(layer "B.Fab")
			(effects
				(font
					(size 0.7 0.7)
					(thickness 0.15)
				)
				(justify left bottom mirror)
			)
		)
		(fp_text user "${REFERENCE}"
			(at -0.95 -3.168 180)
			(layer "B.Fab")
			(effects
				(font
					(size 0.7 0.7)
					(thickness 0.15)
				)
				(justify left bottom mirror)
			)
		)
		(fp_text user "Author: Antmicro"
			(at -0.95 -4.169 180)
			(layer "B.Fab")
			(effects
				(font
					(size 0.7 0.7)
					(thickness 0.15)
				)
				(justify left bottom mirror)
			)
		)
		(pad "1" smd roundrect
			(at -0.48 0)
			(size 0.59 0.64)
			(layers "B.Cu" "B.Mask" "B.Paste")
			(roundrect_rratio 0.25)
			(net 1 "GND")
			(pintype "passive")
		)
		(pad "2" smd roundrect
			(at 0.48 0)
			(size 0.59 0.64)
			(layers "B.Cu" "B.Mask" "B.Paste")
			(roundrect_rratio 0.25)
			(net 198 "/SDI/AUDIO_EN{slash}~{DIS}")
			(pintype "passive")
		)
	)
	(footprint "antmicro-footprints:C_0402_1005Metric"
		(layer "B.Cu")
		(at 91.58 75.36 90)
		(descr "Capacitor SMD 0402")
		(tags "capacitor SMD 0402")
		(property "Reference" "C73"
			(at -1.28 -0.65 90)
			(layer "B.SilkS")
			(effects
				(font
					(size 0.65 0.65)
					(thickness 0.15)
				)
				(justify right bottom mirror)
			)
		)
		(property "Value" "C_100n_0402"
			(at 0 -1.4 90)
			(layer "B.Fab")
			(hide yes)
			(effects
				(font
					(size 0.7 0.7)
					(thickness 0.15)
				)
				(justify right bottom mirror)
			)
		)
		(property "Datasheet" "https://www.murata.com/products/productdetail?partno=GRM155R61H104KE14%23"
			(at 0 0 90)
			(layer "F.Fab")
			(hide yes)
			(effects
				(font
					(size 1.27 1.27)
					(thickness 0.15)
				)
			)
		)
		(property "Description" "SMD Multilayer Ceramic Capacitor, 0.1 µF, 50 V, 0402 [1005 Metric], ± 10%, X5R, GRM Series"
			(at 0 0 90)
			(layer "F.Fab")
			(hide yes)
			(effects
				(font
					(size 1.27 1.27)
					(thickness 0.15)
				)
			)
		)
		(property "Author" "Antmicro"
			(at 166.94 -16.22 0)
			(layer "B.Fab")
			(hide yes)
			(effects
				(font
					(size 1 1)
					(thickness 0.15)
				)
				(justify mirror)
			)
		)
		(property "Dielectric" "X5R"
			(at 166.94 -16.22 0)
			(layer "B.Fab")
			(hide yes)
			(effects
				(font
					(size 1 1)
					(thickness 0.15)
				)
				(justify mirror)
			)
		)
		(property "License" "Apache-2.0"
			(at 166.94 -16.22 0)
			(layer "B.Fab")
			(hide yes)
			(effects
				(font
					(size 1 1)
					(thickness 0.15)
				)
				(justify mirror)
			)
		)
		(property "MPN" "GRM155R61H104KE14D"
			(at 166.94 -16.22 0)
			(layer "B.Fab")
			(hide yes)
			(effects
				(font
					(size 1 1)
					(thickness 0.15)
				)
				(justify mirror)
			)
		)
		(property "Manufacturer" "Murata"
			(at 166.94 -16.22 0)
			(layer "B.Fab")
			(hide yes)
			(effects
				(font
					(size 1 1)
					(thickness 0.15)
				)
				(justify mirror)
			)
		)
		(property "Val" "100n"
			(at 166.94 -16.22 0)
			(layer "B.Fab")
			(hide yes)
			(effects
				(font
					(size 1 1)
					(thickness 0.15)
				)
				(justify mirror)
			)
		)
		(property "Voltage" "50V"
			(at 166.94 -16.22 0)
			(layer "B.Fab")
			(hide yes)
			(effects
				(font
					(size 1 1)
					(thickness 0.15)
				)
				(justify mirror)
			)
		)
		(sheetname "/SDI/")
		(sheetfile "sdi.kicad_sch")
		(attr smd)
		(fp_rect
			(start -0.925 0.47)
			(end 0.925 -0.47)
			(stroke
				(width 0.05)
				(type default)
			)
			(fill no)
			(layer "B.CrtYd")
		)
		(fp_line
			(start 0.504 -0.248)
			(end -0.494 -0.248)
			(stroke
				(width 0.15)
				(type solid)
			)
			(layer "B.Fab")
		)
		(fp_line
			(start -0.494 -0.248)
			(end -0.494 0.25)
			(stroke
				(width 0.15)
				(type solid)
			)
			(layer "B.Fab")
		)
		(fp_line
			(start 0.504 0.25)
			(end 0.504 -0.248)
			(stroke
				(width 0.15)
				(type solid)
			)
			(layer "B.Fab")
		)
		(fp_line
			(start -0.494 0.25)
			(end 0.504 0.25)
			(stroke
				(width 0.15)
				(type solid)
			)
			(layer "B.Fab")
		)
		(fp_text user "${REFERENCE}"
			(at -0.939 -4.599 270)
			(layer "B.Fab")
			(effects
				(font
					(size 0.7 0.7)
					(thickness 0.15)
				)
				(justify left bottom mirror)
			)
		)
		(fp_text user "License: Apache-2.0"
			(at -0.939 -5.799 270)
			(layer "B.Fab")
			(effects
				(font
					(size 0.7 0.7)
					(thickness 0.15)
				)
				(justify left bottom mirror)
			)
		)
		(fp_text user "Author: Antmicro"
			(at -0.939 -3.399 270)
			(layer "B.Fab")
			(effects
				(font
					(size 0.7 0.7)
					(thickness 0.15)
				)
				(justify left bottom mirror)
			)
		)
		(pad "1" smd roundrect
			(at -0.48 0 90)
			(size 0.59 0.64)
			(layers "B.Cu" "B.Mask" "B.Paste")
			(roundrect_rratio 0.25)
			(net 1 "GND")
			(pintype "passive")
		)
		(pad "2" smd roundrect
			(at 0.48 0 90)
			(size 0.59 0.64)
			(layers "B.Cu" "B.Mask" "B.Paste")
			(roundrect_rratio 0.25)
			(net 3 "+1V2")
			(pintype "passive")
		)
	)
	(footprint "antmicro-footprints:FB_0603_1608Metric"
		(layer "B.Cu")
		(at 136.99 96.48)
		(property "Reference" "FB4"
			(at 3.54 0.41 180)
			(layer "B.SilkS")
			(effects
				(font
					(size 0.65 0.65)
					(thickness 0.15)
				)
				(justify left bottom mirror)
			)
		)
		(property "Value" "FB_120Z_2A_0603"
			(at 0 -1.5 180)
			(layer "B.Fab")
			(hide yes)
			(effects
				(font
					(size 0.7 0.7)
					(thickness 0.15)
				)
				(justify left bottom mirror)
			)
		)
		(property "Datasheet" "https://www.murata.com/en-us/products/productdata/8796738650142/ENFA0003.pdf"
			(at 0 0 0)
			(layer "F.Fab")
			(hide yes)
			(effects
				(font
					(size 1.27 1.27)
					(thickness 0.15)
				)
			)
		)
		(property "Description" "Ferrite Bead, 0603 [1608 Metric], 120 ohm, 2 A, BLM18P, 0.05 ohm, ± 25%, DC power line"
			(at 0 0 0)
			(layer "F.Fab")
			(hide yes)
			(effects
				(font
					(size 1.27 1.27)
					(thickness 0.15)
				)
			)
		)
		(property "Author" "Antmicro"
			(at 0 0 0)
			(layer "B.Fab")
			(hide yes)
			(effects
				(font
					(size 1 1)
					(thickness 0.15)
				)
				(justify mirror)
			)
		)
		(property "License" "Apache-2.0"
			(at 0 0 0)
			(layer "B.Fab")
			(hide yes)
			(effects
				(font
					(size 1 1)
					(thickness 0.15)
				)
				(justify mirror)
			)
		)
		(property "MPN" "BLM18PG121SN1D"
			(at 0 0 0)
			(layer "B.Fab")
			(hide yes)
			(effects
				(font
					(size 1 1)
					(thickness 0.15)
				)
				(justify mirror)
			)
		)
		(property "Manufacturer" "Murata"
			(at 0 0 0)
			(layer "B.Fab")
			(hide yes)
			(effects
				(font
					(size 1 1)
					(thickness 0.15)
				)
				(justify mirror)
			)
		)
		(property "Val" "120Z/2A"
			(at 0 0 0)
			(unlocked yes)
			(layer "B.Fab")
			(hide yes)
			(effects
				(font
					(size 1 1)
					(thickness 0.15)
				)
				(justify mirror)
			)
		)
		(property "Current" ""
			(at 0 0 0)
			(unlocked yes)
			(layer "B.Fab")
			(hide yes)
			(effects
				(font
					(size 1 1)
					(thickness 0.15)
				)
				(justify mirror)
			)
		)
		(sheetname "/FPGA Power/")
		(sheetfile "FPGA_Power.kicad_sch")
		(attr smd)
		(fp_line
			(start -0.15 -0.4)
			(end 0.15 -0.4)
			(stroke
				(width 0.15)
				(type solid)
			)
			(layer "B.SilkS")
		)
		(fp_line
			(start -0.15 0.4)
			(end 0.15 0.4)
			(stroke
				(width 0.15)
				(type solid)
			)
			(layer "B.SilkS")
		)
		(fp_rect
			(start -1.25 0.65)
			(end 1.25 -0.65)
			(stroke
				(width 0.05)
				(type solid)
			)
			(fill no)
			(layer "B.CrtYd")
		)
		(fp_line
			(start -0.803 -0.406)
			(end -0.803 0.408)
			(stroke
				(width 0.15)
				(type solid)
			)
			(layer "B.Fab")
		)
		(fp_line
			(start 0.8 -0.406)
			(end -0.803 -0.406)
			(stroke
				(width 0.15)
				(type solid)
			)
			(layer "B.Fab")
		)
		(fp_line
			(start 0.8 0.408)
			(end -0.803 0.408)
			(stroke
				(width 0.15)
				(type solid)
			)
			(layer "B.Fab")
		)
		(fp_line
			(start 0.8 0.408)
			(end 0.8 -0.406)
			(stroke
				(width 0.15)
				(type solid)
			)
			(layer "B.Fab")
		)
		(fp_text user "License: Apache-2.0"
			(at -1.653 -5.9 180)
			(layer "B.Fab")
			(effects
				(font
					(size 0.7 0.7)
					(thickness 0.15)
				)
				(justify left bottom mirror)
			)
		)
		(fp_text user "Author: Antmicro"
			(at -1.653 -3.162 180)
			(layer "B.Fab")
			(effects
				(font
					(size 0.7 0.7)
					(thickness 0.15)
				)
				(justify left bottom mirror)
			)
		)
		(fp_text user "${REFERENCE}"
			(at -1.653 -4.6 180)
			(layer "B.Fab")
			(effects
				(font
					(size 0.7 0.7)
					(thickness 0.15)
				)
				(justify left bottom mirror)
			)
		)
		(pad "1" smd roundrect
			(at -0.7 0)
			(size 0.8 1)
			(layers "B.Cu" "B.Mask" "B.Paste")
			(roundrect_rratio 0.2)
			(net 12 "/FPGA Power/VCC_ADPHY")
			(pintype "passive")
		)
		(pad "2" smd roundrect
			(at 0.7 0)
			(size 0.8 1)
			(layers "B.Cu" "B.Mask" "B.Paste")
			(roundrect_rratio 0.2)
			(net 50 "+1V8")
			(pintype "passive")
		)
	)
	(footprint "antmicro-footprints:C_0603_1608Metric"
		(layer "B.Cu")
		(at 118.82 56.14)
		(descr "Capacitor SMD 0603")
		(tags "capacitor 0603")
		(property "Reference" "C8"
			(at -2.59 0.4 0)
			(layer "B.SilkS")
			(effects
				(font
					(size 0.65 0.65)
					(thickness 0.15)
				)
				(justify right bottom mirror)
			)
		)
		(property "Value" "C_22u_0603"
			(at 0 -1.6 0)
			(layer "B.Fab")
			(hide yes)
			(effects
				(font
					(size 0.7 0.7)
					(thickness 0.15)
				)
				(justify right bottom mirror)
			)
		)
		(property "Datasheet" "https://www.murata.com/products/productdetail?partno=GRM188R60J226MEA0%23"
			(at 0 0 0)
			(layer "F.Fab")
			(hide yes)
			(effects
				(font
					(size 1.27 1.27)
					(thickness 0.15)
				)
			)
		)
		(property "Description" "SMD Multilayer Ceramic Capacitor, 22 µF, 6.3 V, 0603 [1608 Metric], ± 20%, X5R, GRM Series"
			(at 0 0 0)
			(layer "F.Fab")
			(hide yes)
			(effects
				(font
					(size 1.27 1.27)
					(thickness 0.15)
				)
			)
		)
		(property "Author" "Antmicro"
			(at 0 0 0)
			(layer "B.Fab")
			(hide yes)
			(effects
				(font
					(size 1 1)
					(thickness 0.15)
				)
				(justify mirror)
			)
		)
		(property "Dielectric" ""
			(at 0 0 0)
			(layer "B.Fab")
			(hide yes)
			(effects
				(font
					(size 1 1)
					(thickness 0.15)
				)
				(justify mirror)
			)
		)
		(property "License" "Apache-2.0"
			(at 0 0 0)
			(layer "B.Fab")
			(hide yes)
			(effects
				(font
					(size 1 1)
					(thickness 0.15)
				)
				(justify mirror)
			)
		)
		(property "MPN" "GRM188R60J226MEA0D"
			(at 0 0 0)
			(layer "B.Fab")
			(hide yes)
			(effects
				(font
					(size 1 1)
					(thickness 0.15)
				)
				(justify mirror)
			)
		)
		(property "Manufacturer" "Murata"
			(at 0 0 0)
			(layer "B.Fab")
			(hide yes)
			(effects
				(font
					(size 1 1)
					(thickness 0.15)
				)
				(justify mirror)
			)
		)
		(property "Val" "22u"
			(at 0 0 0)
			(layer "B.Fab")
			(hide yes)
			(effects
				(font
					(size 1 1)
					(thickness 0.15)
				)
				(justify mirror)
			)
		)
		(property "Voltage" ""
			(at 0 0 0)
			(layer "B.Fab")
			(hide yes)
			(effects
				(font
					(size 1 1)
					(thickness 0.15)
				)
				(justify mirror)
			)
		)
		(sheetname "/Power Supply/")
		(sheetfile "supply.kicad_sch")
		(attr smd)
		(fp_line
			(start -0.15 -0.4)
			(end 0.15 -0.4)
			(stroke
				(width 0.15)
				(type solid)
			)
			(layer "B.SilkS")
		)
		(fp_line
			(start -0.15 0.4)
			(end 0.15 0.4)
			(stroke
				(width 0.15)
				(type solid)
			)
			(layer "B.SilkS")
		)
		(fp_rect
			(start -1.25 0.65)
			(end 1.25 -0.65)
			(stroke
				(width 0.05)
				(type solid)
			)
			(fill no)
			(layer "B.CrtYd")
		)
		(fp_rect
			(start -0.8 0.4)
			(end 0.8 -0.4)
			(stroke
				(width 0.15)
				(type solid)
			)
			(fill no)
			(layer "B.Fab")
		)
		(fp_text user "License: Apache-2.0"
			(at -1.682 -5.895 180)
			(layer "B.Fab")
			(effects
				(font
					(size 0.7 0.7)
					(thickness 0.15)
				)
				(justify left bottom mirror)
			)
		)
		(fp_text user "${REFERENCE}"
			(at -1.682 -3.895 180)
			(layer "B.Fab")
			(effects
				(font
					(size 0.7 0.7)
					(thickness 0.15)
				)
				(justify left bottom mirror)
			)
		)
		(fp_text user "Author: Antmicro"
			(at -1.682 -4.894 180)
			(layer "B.Fab")
			(effects
				(font
					(size 0.7 0.7)
					(thickness 0.15)
				)
				(justify left bottom mirror)
			)
		)
		(pad "1" smd roundrect
			(at -0.7 0)
			(size 0.8 1)
			(layers "B.Cu" "B.Mask" "B.Paste")
			(roundrect_rratio 0.2)
			(net 1 "GND")
			(pintype "passive")
		)
		(pad "2" smd roundrect
			(at 0.7 0)
			(size 0.8 1)
			(layers "B.Cu" "B.Mask" "B.Paste")
			(roundrect_rratio 0.2)
			(net 6 "Vtt")
			(pintype "passive")
		)
	)
	(footprint "antmicro-footprints:C_0201"
		(layer "B.Cu")
		(at 125.1 90.3 180)
		(descr "Capacitor SMD 0201")
		(tags "capacitor SMD 0201")
		(property "Reference" "C85"
			(at 8.67 12.295736 0)
			(layer "B.SilkS")
			(effects
				(font
					(size 0.65 0.65)
					(thickness 0.15)
				)
				(justify left bottom mirror)
			)
		)
		(property "Value" "C_100n_0201"
			(at 0 -1.4 0)
			(layer "B.Fab")
			(hide yes)
			(effects
				(font
					(size 0.7 0.7)
					(thickness 0.15)
				)
				(justify left bottom mirror)
			)
		)
		(property "Datasheet" "https://www.yageo.com/en/Chart/Download/pdf/CC0201KRX6S5BB104"
			(at 0 0 180)
			(layer "F.Fab")
			(hide yes)
			(effects
				(font
					(size 1.27 1.27)
					(thickness 0.15)
				)
			)
		)
		(property "Description" "SMD Multilayer Ceramic Capacitor, 0.1 µF, 6.3 V, 0201 [0603 Metric], ± 10%, X6S, CC Series"
			(at 0 0 180)
			(layer "F.Fab")
			(hide yes)
			(effects
				(font
					(size 1.27 1.27)
					(thickness 0.15)
				)
			)
		)
		(property "Author" "Antmicro"
			(at 250.2 180.6 0)
			(layer "B.Fab")
			(hide yes)
			(effects
				(font
					(size 1 1)
					(thickness 0.15)
				)
				(justify mirror)
			)
		)
		(property "Dielectric" ""
			(at 250.2 180.6 0)
			(layer "B.Fab")
			(hide yes)
			(effects
				(font
					(size 1 1)
					(thickness 0.15)
				)
				(justify mirror)
			)
		)
		(property "License" "Apache-2.0"
			(at 250.2 180.6 0)
			(layer "B.Fab")
			(hide yes)
			(effects
				(font
					(size 1 1)
					(thickness 0.15)
				)
				(justify mirror)
			)
		)
		(property "MPN" "CC0201KRX6S5BB104"
			(at 250.2 180.6 0)
			(layer "B.Fab")
			(hide yes)
			(effects
				(font
					(size 1 1)
					(thickness 0.15)
				)
				(justify mirror)
			)
		)
		(property "Manufacturer" "YAGEO"
			(at 250.2 180.6 0)
			(layer "B.Fab")
			(hide yes)
			(effects
				(font
					(size 1 1)
					(thickness 0.15)
				)
				(justify mirror)
			)
		)
		(property "Val" "100n"
			(at 250.2 180.6 0)
			(layer "B.Fab")
			(hide yes)
			(effects
				(font
					(size 1 1)
					(thickness 0.15)
				)
				(justify mirror)
			)
		)
		(property "Voltage" ""
			(at 250.2 180.6 0)
			(layer "B.Fab")
			(hide yes)
			(effects
				(font
					(size 1 1)
					(thickness 0.15)
				)
				(justify mirror)
			)
		)
		(property "Public" "False"
			(at 0 0 180)
			(unlocked yes)
			(layer "B.Fab")
			(hide yes)
			(effects
				(font
					(size 1 1)
					(thickness 0.15)
				)
				(justify mirror)
			)
		)
		(sheetname "/FPGA Power/")
		(sheetfile "FPGA_Power.kicad_sch")
		(attr smd)
		(fp_rect
			(start -0.7 0.35)
			(end 0.7 -0.35)
			(stroke
				(width 0.05)
				(type default)
			)
			(fill no)
			(layer "B.CrtYd")
		)
		(fp_rect
			(start 0.3 -0.15)
			(end -0.301 0.149)
			(stroke
				(width 0.15)
				(type solid)
			)
			(fill no)
			(layer "B.Fab")
		)
		(fp_text user "Author: Antmicro"
			(at -0.72 -5.4 0)
			(layer "B.Fab")
			(effects
				(font
					(size 0.7 0.7)
					(thickness 0.15)
				)
				(justify left bottom mirror)
			)
		)
		(fp_text user "License: Apache-2.0"
			(at -0.72 -4.4 0)
			(layer "B.Fab")
			(effects
				(font
					(size 0.7 0.7)
					(thickness 0.15)
				)
				(justify left bottom mirror)
			)
		)
		(fp_text user "${REFERENCE}"
			(at -0.72 -3.4 0)
			(layer "B.Fab")
			(effects
				(font
					(size 0.7 0.7)
					(thickness 0.15)
				)
				(justify left bottom mirror)
			)
		)
		(pad "" smd roundrect
			(at -0.349 0.002 180)
			(size 0.318 0.36)
			(layers "B.Paste")
			(roundrect_rratio 0.25)
		)
		(pad "" smd roundrect
			(at 0.341 0.002 180)
			(size 0.318 0.36)
			(layers "B.Paste")
			(roundrect_rratio 0.25)
		)
		(pad "1" smd roundrect
			(at -0.321 0.002 180)
			(size 0.46 0.4)
			(layers "B.Cu" "B.Mask")
			(roundrect_rratio 0.25)
			(net 1 "GND")
			(pintype "passive")
		)
		(pad "2" smd roundrect
			(at 0.32 0.002 180)
			(size 0.46 0.4)
			(layers "B.Cu" "B.Mask")
			(roundrect_rratio 0.25)
			(net 4 "1V0_Power")
			(pintype "passive")
		)
	)
	(footprint "antmicro-footprints:C_0201"
		(layer "B.Cu")
		(at 125.1 85.5 180)
		(descr "Capacitor SMD 0201")
		(tags "capacitor SMD 0201")
		(property "Reference" "C39"
			(at 8.27 12.295736 0)
			(layer "B.SilkS")
			(effects
				(font
					(size 0.65 0.65)
					(thickness 0.15)
				)
				(justify left bottom mirror)
			)
		)
		(property "Value" "C_100n_0201"
			(at 0 -1.4 0)
			(layer "B.Fab")
			(hide yes)
			(effects
				(font
					(size 0.7 0.7)
					(thickness 0.15)
				)
				(justify left bottom mirror)
			)
		)
		(property "Datasheet" "https://www.yageo.com/en/Chart/Download/pdf/CC0201KRX6S5BB104"
			(at 0 0 180)
			(layer "F.Fab")
			(hide yes)
			(effects
				(font
					(size 1.27 1.27)
					(thickness 0.15)
				)
			)
		)
		(property "Description" "SMD Multilayer Ceramic Capacitor, 0.1 µF, 6.3 V, 0201 [0603 Metric], ± 10%, X6S, CC Series"
			(at 0 0 180)
			(layer "F.Fab")
			(hide yes)
			(effects
				(font
					(size 1.27 1.27)
					(thickness 0.15)
				)
			)
		)
		(property "Author" "Antmicro"
			(at 250.2 171 0)
			(layer "B.Fab")
			(hide yes)
			(effects
				(font
					(size 1 1)
					(thickness 0.15)
				)
				(justify mirror)
			)
		)
		(property "Dielectric" ""
			(at 250.2 171 0)
			(layer "B.Fab")
			(hide yes)
			(effects
				(font
					(size 1 1)
					(thickness 0.15)
				)
				(justify mirror)
			)
		)
		(property "License" "Apache-2.0"
			(at 250.2 171 0)
			(layer "B.Fab")
			(hide yes)
			(effects
				(font
					(size 1 1)
					(thickness 0.15)
				)
				(justify mirror)
			)
		)
		(property "MPN" "CC0201KRX6S5BB104"
			(at 250.2 171 0)
			(layer "B.Fab")
			(hide yes)
			(effects
				(font
					(size 1 1)
					(thickness 0.15)
				)
				(justify mirror)
			)
		)
		(property "Manufacturer" "YAGEO"
			(at 250.2 171 0)
			(layer "B.Fab")
			(hide yes)
			(effects
				(font
					(size 1 1)
					(thickness 0.15)
				)
				(justify mirror)
			)
		)
		(property "Val" "100n"
			(at 250.2 171 0)
			(layer "B.Fab")
			(hide yes)
			(effects
				(font
					(size 1 1)
					(thickness 0.15)
				)
				(justify mirror)
			)
		)
		(property "Voltage" ""
			(at 250.2 171 0)
			(layer "B.Fab")
			(hide yes)
			(effects
				(font
					(size 1 1)
					(thickness 0.15)
				)
				(justify mirror)
			)
		)
		(property "Public" "False"
			(at 0 0 180)
			(unlocked yes)
			(layer "B.Fab")
			(hide yes)
			(effects
				(font
					(size 1 1)
					(thickness 0.15)
				)
				(justify mirror)
			)
		)
		(sheetname "/DDR3/")
		(sheetfile "ddr3.kicad_sch")
		(attr smd)
		(fp_rect
			(start -0.7 0.35)
			(end 0.7 -0.35)
			(stroke
				(width 0.05)
				(type default)
			)
			(fill no)
			(layer "B.CrtYd")
		)
		(fp_rect
			(start 0.3 -0.15)
			(end -0.301 0.149)
			(stroke
				(width 0.15)
				(type solid)
			)
			(fill no)
			(layer "B.Fab")
		)
		(fp_text user "${REFERENCE}"
			(at -0.72 -3.4 0)
			(layer "B.Fab")
			(effects
				(font
					(size 0.7 0.7)
					(thickness 0.15)
				)
				(justify left bottom mirror)
			)
		)
		(fp_text user "Author: Antmicro"
			(at -0.72 -5.4 0)
			(layer "B.Fab")
			(effects
				(font
					(size 0.7 0.7)
					(thickness 0.15)
				)
				(justify left bottom mirror)
			)
		)
		(fp_text user "License: Apache-2.0"
			(at -0.72 -4.4 0)
			(layer "B.Fab")
			(effects
				(font
					(size 0.7 0.7)
					(thickness 0.15)
				)
				(justify left bottom mirror)
			)
		)
		(pad "" smd roundrect
			(at -0.349 0.002 180)
			(size 0.318 0.36)
			(layers "B.Paste")
			(roundrect_rratio 0.25)
		)
		(pad "" smd roundrect
			(at 0.341 0.002 180)
			(size 0.318 0.36)
			(layers "B.Paste")
			(roundrect_rratio 0.25)
		)
		(pad "1" smd roundrect
			(at -0.321 0.002 180)
			(size 0.46 0.4)
			(layers "B.Cu" "B.Mask")
			(roundrect_rratio 0.25)
			(net 1 "GND")
			(pintype "passive")
		)
		(pad "2" smd roundrect
			(at 0.32 0.002 180)
			(size 0.46 0.4)
			(layers "B.Cu" "B.Mask")
			(roundrect_rratio 0.25)
			(net 5 "Vref")
			(pintype "passive")
		)
	)
	(footprint "antmicro-footprints:C_0201"
		(layer "B.Cu")
		(at 126.83 92.11 90)
		(descr "Capacitor SMD 0201")
		(tags "capacitor SMD 0201")
		(property "Reference" "C93"
			(at 11.305736 -9 90)
			(layer "B.SilkS")
			(effects
				(font
					(size 0.65 0.65)
					(thickness 0.15)
				)
				(justify right bottom mirror)
			)
		)
		(property "Value" "C_100n_0201"
			(at 0 -1.4 90)
			(layer "B.Fab")
			(hide yes)
			(effects
				(font
					(size 0.7 0.7)
					(thickness 0.15)
				)
				(justify right bottom mirror)
			)
		)
		(property "Datasheet" "https://www.yageo.com/en/Chart/Download/pdf/CC0201KRX6S5BB104"
			(at 0 0 90)
			(layer "F.Fab")
			(hide yes)
			(effects
				(font
					(size 1.27 1.27)
					(thickness 0.15)
				)
			)
		)
		(property "Description" "SMD Multilayer Ceramic Capacitor, 0.1 µF, 6.3 V, 0201 [0603 Metric], ± 10%, X6S, CC Series"
			(at 0 0 90)
			(layer "F.Fab")
			(hide yes)
			(effects
				(font
					(size 1.27 1.27)
					(thickness 0.15)
				)
			)
		)
		(property "Author" "Antmicro"
			(at 218.94 -34.72 0)
			(layer "B.Fab")
			(hide yes)
			(effects
				(font
					(size 1 1)
					(thickness 0.15)
				)
				(justify mirror)
			)
		)
		(property "Dielectric" ""
			(at 218.94 -34.72 0)
			(layer "B.Fab")
			(hide yes)
			(effects
				(font
					(size 1 1)
					(thickness 0.15)
				)
				(justify mirror)
			)
		)
		(property "License" "Apache-2.0"
			(at 218.94 -34.72 0)
			(layer "B.Fab")
			(hide yes)
			(effects
				(font
					(size 1 1)
					(thickness 0.15)
				)
				(justify mirror)
			)
		)
		(property "MPN" "CC0201KRX6S5BB104"
			(at 218.94 -34.72 0)
			(layer "B.Fab")
			(hide yes)
			(effects
				(font
					(size 1 1)
					(thickness 0.15)
				)
				(justify mirror)
			)
		)
		(property "Manufacturer" "YAGEO"
			(at 218.94 -34.72 0)
			(layer "B.Fab")
			(hide yes)
			(effects
				(font
					(size 1 1)
					(thickness 0.15)
				)
				(justify mirror)
			)
		)
		(property "Val" "100n"
			(at 218.94 -34.72 0)
			(layer "B.Fab")
			(hide yes)
			(effects
				(font
					(size 1 1)
					(thickness 0.15)
				)
				(justify mirror)
			)
		)
		(property "Voltage" ""
			(at 218.94 -34.72 0)
			(layer "B.Fab")
			(hide yes)
			(effects
				(font
					(size 1 1)
					(thickness 0.15)
				)
				(justify mirror)
			)
		)
		(property "Public" "False"
			(at 0 0 90)
			(unlocked yes)
			(layer "B.Fab")
			(hide yes)
			(effects
				(font
					(size 1 1)
					(thickness 0.15)
				)
				(justify mirror)
			)
		)
		(sheetname "/FPGA Power/")
		(sheetfile "FPGA_Power.kicad_sch")
		(attr smd)
		(fp_rect
			(start -0.7 0.35)
			(end 0.7 -0.35)
			(stroke
				(width 0.05)
				(type default)
			)
			(fill no)
			(layer "B.CrtYd")
		)
		(fp_rect
			(start 0.3 -0.15)
			(end -0.301 0.149)
			(stroke
				(width 0.15)
				(type solid)
			)
			(fill no)
			(layer "B.Fab")
		)
		(fp_text user "Author: Antmicro"
			(at -0.72 -5.4 270)
			(layer "B.Fab")
			(effects
				(font
					(size 0.7 0.7)
					(thickness 0.15)
				)
				(justify left bottom mirror)
			)
		)
		(fp_text user "${REFERENCE}"
			(at -0.72 -3.4 270)
			(layer "B.Fab")
			(effects
				(font
					(size 0.7 0.7)
					(thickness 0.15)
				)
				(justify left bottom mirror)
			)
		)
		(fp_text user "License: Apache-2.0"
			(at -0.72 -4.4 270)
			(layer "B.Fab")
			(effects
				(font
					(size 0.7 0.7)
					(thickness 0.15)
				)
				(justify left bottom mirror)
			)
		)
		(pad "" smd roundrect
			(at -0.349 0.002 90)
			(size 0.318 0.36)
			(layers "B.Paste")
			(roundrect_rratio 0.25)
		)
		(pad "" smd roundrect
			(at 0.341 0.002 90)
			(size 0.318 0.36)
			(layers "B.Paste")
			(roundrect_rratio 0.25)
		)
		(pad "1" smd roundrect
			(at -0.321 0.002 90)
			(size 0.46 0.4)
			(layers "B.Cu" "B.Mask")
			(roundrect_rratio 0.25)
			(net 1 "GND")
			(pintype "passive")
		)
		(pad "2" smd roundrect
			(at 0.32 0.002 90)
			(size 0.46 0.4)
			(layers "B.Cu" "B.Mask")
			(roundrect_rratio 0.25)
			(net 9 "/FPGA Power/VCC_AUX")
			(pintype "passive")
		)
	)
	(footprint "antmicro-footprints:C_0402_1005Metric"
		(layer "B.Cu")
		(at 89.3 77.4)
		(descr "Capacitor SMD 0402")
		(tags "capacitor SMD 0402")
		(property "Reference" "C60"
			(at -1.27 -0.66 0)
			(layer "B.SilkS")
			(effects
				(font
					(size 0.65 0.65)
					(thickness 0.15)
				)
				(justify right bottom mirror)
			)
		)
		(property "Value" "C_100n_0402"
			(at 0 -1.4 0)
			(layer "B.Fab")
			(hide yes)
			(effects
				(font
					(size 0.7 0.7)
					(thickness 0.15)
				)
				(justify right bottom mirror)
			)
		)
		(property "Datasheet" "https://www.murata.com/products/productdetail?partno=GRM155R61H104KE14%23"
			(at 0 0 0)
			(layer "F.Fab")
			(hide yes)
			(effects
				(font
					(size 1.27 1.27)
					(thickness 0.15)
				)
			)
		)
		(property "Description" "SMD Multilayer Ceramic Capacitor, 0.1 µF, 50 V, 0402 [1005 Metric], ± 10%, X5R, GRM Series"
			(at 0 0 0)
			(layer "F.Fab")
			(hide yes)
			(effects
				(font
					(size 1.27 1.27)
					(thickness 0.15)
				)
			)
		)
		(property "Author" "Antmicro"
			(at 0 0 0)
			(layer "B.Fab")
			(hide yes)
			(effects
				(font
					(size 1 1)
					(thickness 0.15)
				)
				(justify mirror)
			)
		)
		(property "Dielectric" "X5R"
			(at 0 0 0)
			(layer "B.Fab")
			(hide yes)
			(effects
				(font
					(size 1 1)
					(thickness 0.15)
				)
				(justify mirror)
			)
		)
		(property "License" "Apache-2.0"
			(at 0 0 0)
			(layer "B.Fab")
			(hide yes)
			(effects
				(font
					(size 1 1)
					(thickness 0.15)
				)
				(justify mirror)
			)
		)
		(property "MPN" "GRM155R61H104KE14D"
			(at 0 0 0)
			(layer "B.Fab")
			(hide yes)
			(effects
				(font
					(size 1 1)
					(thickness 0.15)
				)
				(justify mirror)
			)
		)
		(property "Manufacturer" "Murata"
			(at 0 0 0)
			(layer "B.Fab")
			(hide yes)
			(effects
				(font
					(size 1 1)
					(thickness 0.15)
				)
				(justify mirror)
			)
		)
		(property "Val" "100n"
			(at 0 0 0)
			(layer "B.Fab")
			(hide yes)
			(effects
				(font
					(size 1 1)
					(thickness 0.15)
				)
				(justify mirror)
			)
		)
		(property "Voltage" "50V"
			(at 0 0 0)
			(layer "B.Fab")
			(hide yes)
			(effects
				(font
					(size 1 1)
					(thickness 0.15)
				)
				(justify mirror)
			)
		)
		(sheetname "/SDI/")
		(sheetfile "sdi.kicad_sch")
		(attr smd)
		(fp_rect
			(start -0.925 0.47)
			(end 0.925 -0.47)
			(stroke
				(width 0.05)
				(type default)
			)
			(fill no)
			(layer "B.CrtYd")
		)
		(fp_line
			(start -0.494 -0.248)
			(end -0.494 0.25)
			(stroke
				(width 0.15)
				(type solid)
			)
			(layer "B.Fab")
		)
		(fp_line
			(start -0.494 0.25)
			(end 0.504 0.25)
			(stroke
				(width 0.15)
				(type solid)
			)
			(layer "B.Fab")
		)
		(fp_line
			(start 0.504 -0.248)
			(end -0.494 -0.248)
			(stroke
				(width 0.15)
				(type solid)
			)
			(layer "B.Fab")
		)
		(fp_line
			(start 0.504 0.25)
			(end 0.504 -0.248)
			(stroke
				(width 0.15)
				(type solid)
			)
			(layer "B.Fab")
		)
		(fp_text user "${REFERENCE}"
			(at -0.939 -4.599 180)
			(layer "B.Fab")
			(effects
				(font
					(size 0.7 0.7)
					(thickness 0.15)
				)
				(justify left bottom mirror)
			)
		)
		(fp_text user "License: Apache-2.0"
			(at -0.939 -5.799 180)
			(layer "B.Fab")
			(effects
				(font
					(size 0.7 0.7)
					(thickness 0.15)
				)
				(justify left bottom mirror)
			)
		)
		(fp_text user "Author: Antmicro"
			(at -0.939 -3.399 180)
			(layer "B.Fab")
			(effects
				(font
					(size 0.7 0.7)
					(thickness 0.15)
				)
				(justify left bottom mirror)
			)
		)
		(pad "1" smd roundrect
			(at -0.48 0)
			(size 0.59 0.64)
			(layers "B.Cu" "B.Mask" "B.Paste")
			(roundrect_rratio 0.25)
			(net 1 "GND")
			(pintype "passive")
		)
		(pad "2" smd roundrect
			(at 0.48 0)
			(size 0.59 0.64)
			(layers "B.Cu" "B.Mask" "B.Paste")
			(roundrect_rratio 0.25)
			(net 2 "+3V3")
			(pintype "passive")
		)
	)
	(footprint "antmicro-footprints:C_0402_1005Metric"
		(layer "B.Cu")
		(at 93.08 74.06 180)
		(descr "Capacitor SMD 0402")
		(tags "capacitor SMD 0402")
		(property "Reference" "C66"
			(at -1.05 0.62 0)
			(layer "B.SilkS")
			(effects
				(font
					(size 0.65 0.65)
					(thickness 0.15)
				)
				(justify left bottom mirror)
			)
		)
		(property "Value" "C_100n_0402"
			(at 0 -1.4 0)
			(layer "B.Fab")
			(hide yes)
			(effects
				(font
					(size 0.7 0.7)
					(thickness 0.15)
				)
				(justify left bottom mirror)
			)
		)
		(property "Datasheet" "https://www.murata.com/products/productdetail?partno=GRM155R61H104KE14%23"
			(at 0 0 180)
			(layer "F.Fab")
			(hide yes)
			(effects
				(font
					(size 1.27 1.27)
					(thickness 0.15)
				)
			)
		)
		(property "Description" "SMD Multilayer Ceramic Capacitor, 0.1 µF, 50 V, 0402 [1005 Metric], ± 10%, X5R, GRM Series"
			(at 0 0 180)
			(layer "F.Fab")
			(hide yes)
			(effects
				(font
					(size 1.27 1.27)
					(thickness 0.15)
				)
			)
		)
		(property "Author" "Antmicro"
			(at 186.16 148.12 0)
			(layer "B.Fab")
			(hide yes)
			(effects
				(font
					(size 1 1)
					(thickness 0.15)
				)
				(justify mirror)
			)
		)
		(property "Dielectric" "X5R"
			(at 186.16 148.12 0)
			(layer "B.Fab")
			(hide yes)
			(effects
				(font
					(size 1 1)
					(thickness 0.15)
				)
				(justify mirror)
			)
		)
		(property "License" "Apache-2.0"
			(at 186.16 148.12 0)
			(layer "B.Fab")
			(hide yes)
			(effects
				(font
					(size 1 1)
					(thickness 0.15)
				)
				(justify mirror)
			)
		)
		(property "MPN" "GRM155R61H104KE14D"
			(at 186.16 148.12 0)
			(layer "B.Fab")
			(hide yes)
			(effects
				(font
					(size 1 1)
					(thickness 0.15)
				)
				(justify mirror)
			)
		)
		(property "Manufacturer" "Murata"
			(at 186.16 148.12 0)
			(layer "B.Fab")
			(hide yes)
			(effects
				(font
					(size 1 1)
					(thickness 0.15)
				)
				(justify mirror)
			)
		)
		(property "Val" "100n"
			(at 186.16 148.12 0)
			(layer "B.Fab")
			(hide yes)
			(effects
				(font
					(size 1 1)
					(thickness 0.15)
				)
				(justify mirror)
			)
		)
		(property "Voltage" "50V"
			(at 186.16 148.12 0)
			(layer "B.Fab")
			(hide yes)
			(effects
				(font
					(size 1 1)
					(thickness 0.15)
				)
				(justify mirror)
			)
		)
		(sheetname "/SDI/")
		(sheetfile "sdi.kicad_sch")
		(attr smd)
		(fp_rect
			(start -0.925 0.47)
			(end 0.925 -0.47)
			(stroke
				(width 0.05)
				(type default)
			)
			(fill no)
			(layer "B.CrtYd")
		)
		(fp_line
			(start 0.504 0.25)
			(end 0.504 -0.248)
			(stroke
				(width 0.15)
				(type solid)
			)
			(layer "B.Fab")
		)
		(fp_line
			(start 0.504 -0.248)
			(end -0.494 -0.248)
			(stroke
				(width 0.15)
				(type solid)
			)
			(layer "B.Fab")
		)
		(fp_line
			(start -0.494 0.25)
			(end 0.504 0.25)
			(stroke
				(width 0.15)
				(type solid)
			)
			(layer "B.Fab")
		)
		(fp_line
			(start -0.494 -0.248)
			(end -0.494 0.25)
			(stroke
				(width 0.15)
				(type solid)
			)
			(layer "B.Fab")
		)
		(fp_text user "License: Apache-2.0"
			(at -0.939 -5.799 0)
			(layer "B.Fab")
			(effects
				(font
					(size 0.7 0.7)
					(thickness 0.15)
				)
				(justify left bottom mirror)
			)
		)
		(fp_text user "${REFERENCE}"
			(at -0.939 -4.599 0)
			(layer "B.Fab")
			(effects
				(font
					(size 0.7 0.7)
					(thickness 0.15)
				)
				(justify left bottom mirror)
			)
		)
		(fp_text user "Author: Antmicro"
			(at -0.939 -3.399 0)
			(layer "B.Fab")
			(effects
				(font
					(size 0.7 0.7)
					(thickness 0.15)
				)
				(justify left bottom mirror)
			)
		)
		(pad "1" smd roundrect
			(at -0.48 0 180)
			(size 0.59 0.64)
			(layers "B.Cu" "B.Mask" "B.Paste")
			(roundrect_rratio 0.25)
			(net 1 "GND")
			(pintype "passive")
		)
		(pad "2" smd roundrect
			(at 0.48 0 180)
			(size 0.59 0.64)
			(layers "B.Cu" "B.Mask" "B.Paste")
			(roundrect_rratio 0.25)
			(net 3 "+1V2")
			(pintype "passive")
		)
	)
	(footprint "antmicro-footprints:C_0201"
		(layer "B.Cu")
		(at 127.57 93.94 45)
		(descr "Capacitor SMD 0201")
		(tags "capacitor SMD 0201")
		(property "Reference" "C104"
			(at 1.835463 -14.761374 45)
			(layer "B.SilkS")
			(effects
				(font
					(size 0.65 0.65)
					(thickness 0.15)
				)
				(justify right bottom mirror)
			)
		)
		(property "Value" "C_100n_0201"
			(at 0 -1.399999 45)
			(layer "B.Fab")
			(hide yes)
			(effects
				(font
					(size 0.7 0.7)
					(thickness 0.15)
				)
				(justify right bottom mirror)
			)
		)
		(property "Datasheet" "https://www.yageo.com/en/Chart/Download/pdf/CC0201KRX6S5BB104"
			(at 0 0 45)
			(layer "F.Fab")
			(hide yes)
			(effects
				(font
					(size 1.27 1.27)
					(thickness 0.15)
				)
			)
		)
		(property "Description" "SMD Multilayer Ceramic Capacitor, 0.1 µF, 6.3 V, 0201 [0603 Metric], ± 10%, X6S, CC Series"
			(at 0 0 45)
			(layer "F.Fab")
			(hide yes)
			(effects
				(font
					(size 1.27 1.27)
					(thickness 0.15)
				)
			)
		)
		(property "Author" "Antmicro"
			(at 103.789999 -62.691223 0)
			(layer "B.Fab")
			(hide yes)
			(effects
				(font
					(size 1 1)
					(thickness 0.15)
				)
				(justify mirror)
			)
		)
		(property "Dielectric" ""
			(at 103.789999 -62.691223 0)
			(layer "B.Fab")
			(hide yes)
			(effects
				(font
					(size 1 1)
					(thickness 0.15)
				)
				(justify mirror)
			)
		)
		(property "License" "Apache-2.0"
			(at 103.789999 -62.691223 0)
			(layer "B.Fab")
			(hide yes)
			(effects
				(font
					(size 1 1)
					(thickness 0.15)
				)
				(justify mirror)
			)
		)
		(property "MPN" "CC0201KRX6S5BB104"
			(at 103.789999 -62.691223 0)
			(layer "B.Fab")
			(hide yes)
			(effects
				(font
					(size 1 1)
					(thickness 0.15)
				)
				(justify mirror)
			)
		)
		(property "Manufacturer" "YAGEO"
			(at 103.789999 -62.691223 0)
			(layer "B.Fab")
			(hide yes)
			(effects
				(font
					(size 1 1)
					(thickness 0.15)
				)
				(justify mirror)
			)
		)
		(property "Val" "100n"
			(at 103.789999 -62.691223 0)
			(layer "B.Fab")
			(hide yes)
			(effects
				(font
					(size 1 1)
					(thickness 0.15)
				)
				(justify mirror)
			)
		)
		(property "Voltage" ""
			(at 103.789999 -62.691223 0)
			(layer "B.Fab")
			(hide yes)
			(effects
				(font
					(size 1 1)
					(thickness 0.15)
				)
				(justify mirror)
			)
		)
		(property "Public" "False"
			(at 0 0 45)
			(unlocked yes)
			(layer "B.Fab")
			(hide yes)
			(effects
				(font
					(size 1 1)
					(thickness 0.15)
				)
				(justify mirror)
			)
		)
		(sheetname "/FPGA Power/")
		(sheetfile "FPGA_Power.kicad_sch")
		(attr smd)
		(fp_poly
			(pts
				(xy -0.7 0.35) (xy 0.7 0.35) (xy 0.7 -0.35) (xy -0.7 -0.35)
			)
			(stroke
				(width 0.05)
				(type default)
			)
			(fill no)
			(layer "B.CrtYd")
		)
		(fp_poly
			(pts
				(xy 0.3 -0.15) (xy -0.301 -0.15) (xy -0.301 0.149) (xy 0.3 0.149)
			)
			(stroke
				(width 0.15)
				(type solid)
			)
			(fill no)
			(layer "B.Fab")
		)
		(fp_text user "License: Apache-2.0"
			(at -0.72 -4.4 225)
			(layer "B.Fab")
			(effects
				(font
					(size 0.7 0.7)
					(thickness 0.15)
				)
				(justify left bottom mirror)
			)
		)
		(fp_text user "Author: Antmicro"
			(at -0.72 -5.400001 225)
			(layer "B.Fab")
			(effects
				(font
					(size 0.7 0.7)
					(thickness 0.15)
				)
				(justify left bottom mirror)
			)
		)
		(fp_text user "${REFERENCE}"
			(at -0.72 -3.4 225)
			(layer "B.Fab")
			(effects
				(font
					(size 0.7 0.7)
					(thickness 0.15)
				)
				(justify left bottom mirror)
			)
		)
		(pad "" smd roundrect
			(at -0.349 0.002 45)
			(size 0.318 0.36)
			(layers "B.Paste")
			(roundrect_rratio 0.25)
		)
		(pad "" smd roundrect
			(at 0.341 0.002 45)
			(size 0.318 0.36)
			(layers "B.Paste")
			(roundrect_rratio 0.25)
		)
		(pad "1" smd roundrect
			(at -0.321 0.002 45)
			(size 0.46 0.4)
			(layers "B.Cu" "B.Mask")
			(roundrect_rratio 0.25)
			(net 1 "GND")
			(pintype "passive")
		)
		(pad "2" smd roundrect
			(at 0.32 0.002 45)
			(size 0.46 0.4)
			(layers "B.Cu" "B.Mask")
			(roundrect_rratio 0.25)
			(net 4 "1V0_Power")
			(pintype "passive")
		)
	)
	(footprint "antmicro-footprints:FB_0603_1608Metric"
		(layer "B.Cu")
		(at 130.75 81.06)
		(property "Reference" "FB1"
			(at 1.03 1.58 180)
			(layer "B.SilkS")
			(effects
				(font
					(size 0.65 0.65)
					(thickness 0.15)
				)
				(justify left bottom mirror)
			)
		)
		(property "Value" "FB_120Z_2A_0603"
			(at 0 -1.5 180)
			(layer "B.Fab")
			(hide yes)
			(effects
				(font
					(size 0.7 0.7)
					(thickness 0.15)
				)
				(justify left bottom mirror)
			)
		)
		(property "Datasheet" "https://www.murata.com/en-us/products/productdata/8796738650142/ENFA0003.pdf"
			(at 0 0 0)
			(layer "F.Fab")
			(hide yes)
			(effects
				(font
					(size 1.27 1.27)
					(thickness 0.15)
				)
			)
		)
		(property "Description" "Ferrite Bead, 0603 [1608 Metric], 120 ohm, 2 A, BLM18P, 0.05 ohm, ± 25%, DC power line"
			(at 0 0 0)
			(layer "F.Fab")
			(hide yes)
			(effects
				(font
					(size 1.27 1.27)
					(thickness 0.15)
				)
			)
		)
		(property "Author" "Antmicro"
			(at 0 0 0)
			(layer "B.Fab")
			(hide yes)
			(effects
				(font
					(size 1 1)
					(thickness 0.15)
				)
				(justify mirror)
			)
		)
		(property "License" "Apache-2.0"
			(at 0 0 0)
			(layer "B.Fab")
			(hide yes)
			(effects
				(font
					(size 1 1)
					(thickness 0.15)
				)
				(justify mirror)
			)
		)
		(property "MPN" "BLM18PG121SN1D"
			(at 0 0 0)
			(layer "B.Fab")
			(hide yes)
			(effects
				(font
					(size 1 1)
					(thickness 0.15)
				)
				(justify mirror)
			)
		)
		(property "Manufacturer" "Murata"
			(at 0 0 0)
			(layer "B.Fab")
			(hide yes)
			(effects
				(font
					(size 1 1)
					(thickness 0.15)
				)
				(justify mirror)
			)
		)
		(property "Val" "120Z/2A"
			(at 0 0 0)
			(unlocked yes)
			(layer "B.Fab")
			(hide yes)
			(effects
				(font
					(size 1 1)
					(thickness 0.15)
				)
				(justify mirror)
			)
		)
		(property "Current" ""
			(at 0 0 0)
			(unlocked yes)
			(layer "B.Fab")
			(hide yes)
			(effects
				(font
					(size 1 1)
					(thickness 0.15)
				)
				(justify mirror)
			)
		)
		(sheetname "/FPGA Power/")
		(sheetfile "FPGA_Power.kicad_sch")
		(attr smd)
		(fp_line
			(start -0.15 -0.4)
			(end 0.15 -0.4)
			(stroke
				(width 0.15)
				(type solid)
			)
			(layer "B.SilkS")
		)
		(fp_line
			(start -0.15 0.4)
			(end 0.15 0.4)
			(stroke
				(width 0.15)
				(type solid)
			)
			(layer "B.SilkS")
		)
		(fp_rect
			(start -1.25 0.65)
			(end 1.25 -0.65)
			(stroke
				(width 0.05)
				(type solid)
			)
			(fill no)
			(layer "B.CrtYd")
		)
		(fp_line
			(start -0.803 -0.406)
			(end -0.803 0.408)
			(stroke
				(width 0.15)
				(type solid)
			)
			(layer "B.Fab")
		)
		(fp_line
			(start 0.8 -0.406)
			(end -0.803 -0.406)
			(stroke
				(width 0.15)
				(type solid)
			)
			(layer "B.Fab")
		)
		(fp_line
			(start 0.8 0.408)
			(end -0.803 0.408)
			(stroke
				(width 0.15)
				(type solid)
			)
			(layer "B.Fab")
		)
		(fp_line
			(start 0.8 0.408)
			(end 0.8 -0.406)
			(stroke
				(width 0.15)
				(type solid)
			)
			(layer "B.Fab")
		)
		(fp_text user "License: Apache-2.0"
			(at -1.653 -5.9 180)
			(layer "B.Fab")
			(effects
				(font
					(size 0.7 0.7)
					(thickness 0.15)
				)
				(justify left bottom mirror)
			)
		)
		(fp_text user "${REFERENCE}"
			(at -1.653 -4.6 180)
			(layer "B.Fab")
			(effects
				(font
					(size 0.7 0.7)
					(thickness 0.15)
				)
				(justify left bottom mirror)
			)
		)
		(fp_text user "Author: Antmicro"
			(at -1.653 -3.162 180)
			(layer "B.Fab")
			(effects
				(font
					(size 0.7 0.7)
					(thickness 0.15)
				)
				(justify left bottom mirror)
			)
		)
		(pad "1" smd roundrect
			(at -0.7 0)
			(size 0.8 1)
			(layers "B.Cu" "B.Mask" "B.Paste")
			(roundrect_rratio 0.2)
			(net 9 "/FPGA Power/VCC_AUX")
			(pintype "passive")
		)
		(pad "2" smd roundrect
			(at 0.7 0)
			(size 0.8 1)
			(layers "B.Cu" "B.Mask" "B.Paste")
			(roundrect_rratio 0.2)
			(net 50 "+1V8")
			(pintype "passive")
		)
	)
	(footprint "antmicro-footprints:C_0402_1005Metric"
		(layer "B.Cu")
		(at 89.3 74.4)
		(descr "Capacitor SMD 0402")
		(tags "capacitor SMD 0402")
		(property "Reference" "C64"
			(at -1.27 1.34 0)
			(layer "B.SilkS")
			(effects
				(font
					(size 0.65 0.65)
					(thickness 0.15)
				)
				(justify right bottom mirror)
			)
		)
		(property "Value" "C_100n_0402"
			(at 0 -1.4 0)
			(layer "B.Fab")
			(hide yes)
			(effects
				(font
					(size 0.7 0.7)
					(thickness 0.15)
				)
				(justify right bottom mirror)
			)
		)
		(property "Datasheet" "https://www.murata.com/products/productdetail?partno=GRM155R61H104KE14%23"
			(at 0 0 0)
			(layer "F.Fab")
			(hide yes)
			(effects
				(font
					(size 1.27 1.27)
					(thickness 0.15)
				)
			)
		)
		(property "Description" "SMD Multilayer Ceramic Capacitor, 0.1 µF, 50 V, 0402 [1005 Metric], ± 10%, X5R, GRM Series"
			(at 0 0 0)
			(layer "F.Fab")
			(hide yes)
			(effects
				(font
					(size 1.27 1.27)
					(thickness 0.15)
				)
			)
		)
		(property "Author" "Antmicro"
			(at 0 0 0)
			(layer "B.Fab")
			(hide yes)
			(effects
				(font
					(size 1 1)
					(thickness 0.15)
				)
				(justify mirror)
			)
		)
		(property "Dielectric" "X5R"
			(at 0 0 0)
			(layer "B.Fab")
			(hide yes)
			(effects
				(font
					(size 1 1)
					(thickness 0.15)
				)
				(justify mirror)
			)
		)
		(property "License" "Apache-2.0"
			(at 0 0 0)
			(layer "B.Fab")
			(hide yes)
			(effects
				(font
					(size 1 1)
					(thickness 0.15)
				)
				(justify mirror)
			)
		)
		(property "MPN" "GRM155R61H104KE14D"
			(at 0 0 0)
			(layer "B.Fab")
			(hide yes)
			(effects
				(font
					(size 1 1)
					(thickness 0.15)
				)
				(justify mirror)
			)
		)
		(property "Manufacturer" "Murata"
			(at 0 0 0)
			(layer "B.Fab")
			(hide yes)
			(effects
				(font
					(size 1 1)
					(thickness 0.15)
				)
				(justify mirror)
			)
		)
		(property "Val" "100n"
			(at 0 0 0)
			(layer "B.Fab")
			(hide yes)
			(effects
				(font
					(size 1 1)
					(thickness 0.15)
				)
				(justify mirror)
			)
		)
		(property "Voltage" "50V"
			(at 0 0 0)
			(layer "B.Fab")
			(hide yes)
			(effects
				(font
					(size 1 1)
					(thickness 0.15)
				)
				(justify mirror)
			)
		)
		(sheetname "/SDI/")
		(sheetfile "sdi.kicad_sch")
		(attr smd)
		(fp_rect
			(start -0.925 0.47)
			(end 0.925 -0.47)
			(stroke
				(width 0.05)
				(type default)
			)
			(fill no)
			(layer "B.CrtYd")
		)
		(fp_line
			(start -0.494 -0.248)
			(end -0.494 0.25)
			(stroke
				(width 0.15)
				(type solid)
			)
			(layer "B.Fab")
		)
		(fp_line
			(start -0.494 0.25)
			(end 0.504 0.25)
			(stroke
				(width 0.15)
				(type solid)
			)
			(layer "B.Fab")
		)
		(fp_line
			(start 0.504 -0.248)
			(end -0.494 -0.248)
			(stroke
				(width 0.15)
				(type solid)
			)
			(layer "B.Fab")
		)
		(fp_line
			(start 0.504 0.25)
			(end 0.504 -0.248)
			(stroke
				(width 0.15)
				(type solid)
			)
			(layer "B.Fab")
		)
		(fp_text user "License: Apache-2.0"
			(at -0.939 -5.799 180)
			(layer "B.Fab")
			(effects
				(font
					(size 0.7 0.7)
					(thickness 0.15)
				)
				(justify left bottom mirror)
			)
		)
		(fp_text user "${REFERENCE}"
			(at -0.939 -4.599 180)
			(layer "B.Fab")
			(effects
				(font
					(size 0.7 0.7)
					(thickness 0.15)
				)
				(justify left bottom mirror)
			)
		)
		(fp_text user "Author: Antmicro"
			(at -0.939 -3.399 180)
			(layer "B.Fab")
			(effects
				(font
					(size 0.7 0.7)
					(thickness 0.15)
				)
				(justify left bottom mirror)
			)
		)
		(pad "1" smd roundrect
			(at -0.48 0)
			(size 0.59 0.64)
			(layers "B.Cu" "B.Mask" "B.Paste")
			(roundrect_rratio 0.25)
			(net 1 "GND")
			(pintype "passive")
		)
		(pad "2" smd roundrect
			(at 0.48 0)
			(size 0.59 0.64)
			(layers "B.Cu" "B.Mask" "B.Paste")
			(roundrect_rratio 0.25)
			(net 2 "+3V3")
			(pintype "passive")
		)
	)
	(footprint "antmicro-footprints:C_0201"
		(layer "B.Cu")
		(at 128.3 95.1 180)
		(descr "Capacitor SMD 0201")
		(tags "capacitor SMD 0201")
		(property "Reference" "C95"
			(at 8.47 12.095736 0)
			(layer "B.SilkS")
			(effects
				(font
					(size 0.65 0.65)
					(thickness 0.15)
				)
				(justify left bottom mirror)
			)
		)
		(property "Value" "C_100n_0201"
			(at 0 -1.4 0)
			(layer "B.Fab")
			(hide yes)
			(effects
				(font
					(size 0.7 0.7)
					(thickness 0.15)
				)
				(justify left bottom mirror)
			)
		)
		(property "Datasheet" "https://www.yageo.com/en/Chart/Download/pdf/CC0201KRX6S5BB104"
			(at 0 0 180)
			(layer "F.Fab")
			(hide yes)
			(effects
				(font
					(size 1.27 1.27)
					(thickness 0.15)
				)
			)
		)
		(property "Description" "SMD Multilayer Ceramic Capacitor, 0.1 µF, 6.3 V, 0201 [0603 Metric], ± 10%, X6S, CC Series"
			(at 0 0 180)
			(layer "F.Fab")
			(hide yes)
			(effects
				(font
					(size 1.27 1.27)
					(thickness 0.15)
				)
			)
		)
		(property "Author" "Antmicro"
			(at 256.6 190.2 0)
			(layer "B.Fab")
			(hide yes)
			(effects
				(font
					(size 1 1)
					(thickness 0.15)
				)
				(justify mirror)
			)
		)
		(property "Dielectric" ""
			(at 256.6 190.2 0)
			(layer "B.Fab")
			(hide yes)
			(effects
				(font
					(size 1 1)
					(thickness 0.15)
				)
				(justify mirror)
			)
		)
		(property "License" "Apache-2.0"
			(at 256.6 190.2 0)
			(layer "B.Fab")
			(hide yes)
			(effects
				(font
					(size 1 1)
					(thickness 0.15)
				)
				(justify mirror)
			)
		)
		(property "MPN" "CC0201KRX6S5BB104"
			(at 256.6 190.2 0)
			(layer "B.Fab")
			(hide yes)
			(effects
				(font
					(size 1 1)
					(thickness 0.15)
				)
				(justify mirror)
			)
		)
		(property "Manufacturer" "YAGEO"
			(at 256.6 190.2 0)
			(layer "B.Fab")
			(hide yes)
			(effects
				(font
					(size 1 1)
					(thickness 0.15)
				)
				(justify mirror)
			)
		)
		(property "Val" "100n"
			(at 256.6 190.2 0)
			(layer "B.Fab")
			(hide yes)
			(effects
				(font
					(size 1 1)
					(thickness 0.15)
				)
				(justify mirror)
			)
		)
		(property "Voltage" ""
			(at 256.6 190.2 0)
			(layer "B.Fab")
			(hide yes)
			(effects
				(font
					(size 1 1)
					(thickness 0.15)
				)
				(justify mirror)
			)
		)
		(property "Public" "False"
			(at 0 0 180)
			(unlocked yes)
			(layer "B.Fab")
			(hide yes)
			(effects
				(font
					(size 1 1)
					(thickness 0.15)
				)
				(justify mirror)
			)
		)
		(sheetname "/FPGA Power/")
		(sheetfile "FPGA_Power.kicad_sch")
		(attr smd)
		(fp_rect
			(start -0.7 0.35)
			(end 0.7 -0.35)
			(stroke
				(width 0.05)
				(type default)
			)
			(fill no)
			(layer "B.CrtYd")
		)
		(fp_rect
			(start 0.3 -0.15)
			(end -0.301 0.149)
			(stroke
				(width 0.15)
				(type solid)
			)
			(fill no)
			(layer "B.Fab")
		)
		(fp_text user "${REFERENCE}"
			(at -0.72 -3.4 0)
			(layer "B.Fab")
			(effects
				(font
					(size 0.7 0.7)
					(thickness 0.15)
				)
				(justify left bottom mirror)
			)
		)
		(fp_text user "Author: Antmicro"
			(at -0.72 -5.4 0)
			(layer "B.Fab")
			(effects
				(font
					(size 0.7 0.7)
					(thickness 0.15)
				)
				(justify left bottom mirror)
			)
		)
		(fp_text user "License: Apache-2.0"
			(at -0.72 -4.4 0)
			(layer "B.Fab")
			(effects
				(font
					(size 0.7 0.7)
					(thickness 0.15)
				)
				(justify left bottom mirror)
			)
		)
		(pad "" smd roundrect
			(at -0.349 0.002 180)
			(size 0.318 0.36)
			(layers "B.Paste")
			(roundrect_rratio 0.25)
		)
		(pad "" smd roundrect
			(at 0.341 0.002 180)
			(size 0.318 0.36)
			(layers "B.Paste")
			(roundrect_rratio 0.25)
		)
		(pad "1" smd roundrect
			(at -0.321 0.002 180)
			(size 0.46 0.4)
			(layers "B.Cu" "B.Mask")
			(roundrect_rratio 0.25)
			(net 1 "GND")
			(pintype "passive")
		)
		(pad "2" smd roundrect
			(at 0.32 0.002 180)
			(size 0.46 0.4)
			(layers "B.Cu" "B.Mask")
			(roundrect_rratio 0.25)
			(net 11 "/FPGA Power/VCC_DPHY")
			(pintype "passive")
		)
	)
	(footprint "antmicro-footprints:C_0402_1005Metric"
		(layer "B.Cu")
		(at 127.95 67.72 90)
		(descr "Capacitor SMD 0402")
		(tags "capacitor SMD 0402")
		(property "Reference" "C41"
			(at -1.02 1.38 90)
			(layer "B.SilkS")
			(effects
				(font
					(size 0.65 0.65)
					(thickness 0.15)
				)
				(justify right bottom mirror)
			)
		)
		(property "Value" "C_100n_0402"
			(at 0 -1.4 90)
			(layer "B.Fab")
			(hide yes)
			(effects
				(font
					(size 0.7 0.7)
					(thickness 0.15)
				)
				(justify right bottom mirror)
			)
		)
		(property "Datasheet" "https://www.murata.com/products/productdetail?partno=GRM155R61H104KE14%23"
			(at 0 0 90)
			(layer "F.Fab")
			(hide yes)
			(effects
				(font
					(size 1.27 1.27)
					(thickness 0.15)
				)
			)
		)
		(property "Description" "SMD Multilayer Ceramic Capacitor, 0.1 µF, 50 V, 0402 [1005 Metric], ± 10%, X5R, GRM Series"
			(at 0 0 90)
			(layer "F.Fab")
			(hide yes)
			(effects
				(font
					(size 1.27 1.27)
					(thickness 0.15)
				)
			)
		)
		(property "Author" "Antmicro"
			(at 195.67 -60.23 0)
			(layer "B.Fab")
			(hide yes)
			(effects
				(font
					(size 1 1)
					(thickness 0.15)
				)
				(justify mirror)
			)
		)
		(property "Dielectric" "X5R"
			(at 195.67 -60.23 0)
			(layer "B.Fab")
			(hide yes)
			(effects
				(font
					(size 1 1)
					(thickness 0.15)
				)
				(justify mirror)
			)
		)
		(property "License" "Apache-2.0"
			(at 195.67 -60.23 0)
			(layer "B.Fab")
			(hide yes)
			(effects
				(font
					(size 1 1)
					(thickness 0.15)
				)
				(justify mirror)
			)
		)
		(property "MPN" "GRM155R61H104KE14D"
			(at 195.67 -60.23 0)
			(layer "B.Fab")
			(hide yes)
			(effects
				(font
					(size 1 1)
					(thickness 0.15)
				)
				(justify mirror)
			)
		)
		(property "Manufacturer" "Murata"
			(at 195.67 -60.23 0)
			(layer "B.Fab")
			(hide yes)
			(effects
				(font
					(size 1 1)
					(thickness 0.15)
				)
				(justify mirror)
			)
		)
		(property "Val" "100n"
			(at 195.67 -60.23 0)
			(layer "B.Fab")
			(hide yes)
			(effects
				(font
					(size 1 1)
					(thickness 0.15)
				)
				(justify mirror)
			)
		)
		(property "Voltage" "50V"
			(at 195.67 -60.23 0)
			(layer "B.Fab")
			(hide yes)
			(effects
				(font
					(size 1 1)
					(thickness 0.15)
				)
				(justify mirror)
			)
		)
		(sheetname "/DDR3/")
		(sheetfile "ddr3.kicad_sch")
		(attr smd)
		(fp_rect
			(start -0.925 0.47)
			(end 0.925 -0.47)
			(stroke
				(width 0.05)
				(type default)
			)
			(fill no)
			(layer "B.CrtYd")
		)
		(fp_line
			(start 0.504 -0.248)
			(end -0.494 -0.248)
			(stroke
				(width 0.15)
				(type solid)
			)
			(layer "B.Fab")
		)
		(fp_line
			(start -0.494 -0.248)
			(end -0.494 0.25)
			(stroke
				(width 0.15)
				(type solid)
			)
			(layer "B.Fab")
		)
		(fp_line
			(start 0.504 0.25)
			(end 0.504 -0.248)
			(stroke
				(width 0.15)
				(type solid)
			)
			(layer "B.Fab")
		)
		(fp_line
			(start -0.494 0.25)
			(end 0.504 0.25)
			(stroke
				(width 0.15)
				(type solid)
			)
			(layer "B.Fab")
		)
		(fp_text user "License: Apache-2.0"
			(at -0.939 -5.799 270)
			(layer "B.Fab")
			(effects
				(font
					(size 0.7 0.7)
					(thickness 0.15)
				)
				(justify left bottom mirror)
			)
		)
		(fp_text user "Author: Antmicro"
			(at -0.939 -3.399 270)
			(layer "B.Fab")
			(effects
				(font
					(size 0.7 0.7)
					(thickness 0.15)
				)
				(justify left bottom mirror)
			)
		)
		(fp_text user "${REFERENCE}"
			(at -0.939 -4.599 270)
			(layer "B.Fab")
			(effects
				(font
					(size 0.7 0.7)
					(thickness 0.15)
				)
				(justify left bottom mirror)
			)
		)
		(pad "1" smd roundrect
			(at -0.48 0 90)
			(size 0.59 0.64)
			(layers "B.Cu" "B.Mask" "B.Paste")
			(roundrect_rratio 0.25)
			(net 1 "GND")
			(pintype "passive")
		)
		(pad "2" smd roundrect
			(at 0.48 0 90)
			(size 0.59 0.64)
			(layers "B.Cu" "B.Mask" "B.Paste")
			(roundrect_rratio 0.25)
			(net 248 "+1V5")
			(pintype "passive")
		)
	)
	(footprint "antmicro-footprints:R_0402_1005Metric"
		(layer "B.Cu")
		(at 145.2 81.5 -90)
		(descr "Resistor SMD 0402")
		(tags "resistor SMD 0402")
		(property "Reference" "R134"
			(at -3.66 -0.33 90)
			(layer "B.SilkS")
			(effects
				(font
					(size 0.65 0.65)
					(thickness 0.15)
				)
				(justify left bottom mirror)
			)
		)
		(property "Value" "R_27R_0402"
			(at 0 -1.4 90)
			(layer "B.Fab")
			(hide yes)
			(effects
				(font
					(size 0.7 0.7)
					(thickness 0.15)
				)
				(justify left bottom mirror)
			)
		)
		(property "Datasheet" "https://www.bourns.com/docs/product-datasheets/cr.pdf"
			(at 0 0 270)
			(layer "F.Fab")
			(hide yes)
			(effects
				(font
					(size 1.27 1.27)
					(thickness 0.15)
				)
			)
		)
		(property "Description" "SMD Chip Resistor, 27 ohm, ± 1%, 63 mW, 0402 [1005 Metric], Thick Film, General Purpose"
			(at 0 0 270)
			(layer "F.Fab")
			(hide yes)
			(effects
				(font
					(size 1.27 1.27)
					(thickness 0.15)
				)
			)
		)
		(property "Author" "Antmicro"
			(at 63.7 226.7 0)
			(layer "B.Fab")
			(hide yes)
			(effects
				(font
					(size 1 1)
					(thickness 0.15)
				)
				(justify mirror)
			)
		)
		(property "License" "Apache-2.0"
			(at 63.7 226.7 0)
			(layer "B.Fab")
			(hide yes)
			(effects
				(font
					(size 1 1)
					(thickness 0.15)
				)
				(justify mirror)
			)
		)
		(property "MPN" "CR0402-FX-27R0GLF"
			(at 63.7 226.7 0)
			(layer "B.Fab")
			(hide yes)
			(effects
				(font
					(size 1 1)
					(thickness 0.15)
				)
				(justify mirror)
			)
		)
		(property "Manufacturer" "Bourns"
			(at 63.7 226.7 0)
			(layer "B.Fab")
			(hide yes)
			(effects
				(font
					(size 1 1)
					(thickness 0.15)
				)
				(justify mirror)
			)
		)
		(property "Tolerance" "1%"
			(at 63.7 226.7 0)
			(layer "B.Fab")
			(hide yes)
			(effects
				(font
					(size 1 1)
					(thickness 0.15)
				)
				(justify mirror)
			)
		)
		(property "Val" "27R"
			(at 63.7 226.7 0)
			(layer "B.Fab")
			(hide yes)
			(effects
				(font
					(size 1 1)
					(thickness 0.15)
				)
				(justify mirror)
			)
		)
		(sheetname "/Peripherals/")
		(sheetfile "peripherals.kicad_sch")
		(attr smd)
		(fp_rect
			(start -0.925 0.47)
			(end 0.925 -0.47)
			(stroke
				(width 0.05)
				(type default)
			)
			(fill no)
			(layer "B.CrtYd")
		)
		(fp_rect
			(start -0.5 0.25)
			(end 0.5 -0.25)
			(stroke
				(width 0.15)
				(type solid)
			)
			(fill no)
			(layer "B.Fab")
		)
		(fp_text user "${REFERENCE}"
			(at -0.95 -3.168 90)
			(layer "B.Fab")
			(effects
				(font
					(size 0.7 0.7)
					(thickness 0.15)
				)
				(justify left bottom mirror)
			)
		)
		(fp_text user "License: Apache-2.0"
			(at -0.95 -5.169 90)
			(layer "B.Fab")
			(effects
				(font
					(size 0.7 0.7)
					(thickness 0.15)
				)
				(justify left bottom mirror)
			)
		)
		(fp_text user "Author: Antmicro"
			(at -0.95 -4.169 90)
			(layer "B.Fab")
			(effects
				(font
					(size 0.7 0.7)
					(thickness 0.15)
				)
				(justify left bottom mirror)
			)
		)
		(pad "1" smd roundrect
			(at -0.48 0 270)
			(size 0.59 0.64)
			(layers "B.Cu" "B.Mask" "B.Paste")
			(roundrect_rratio 0.25)
			(net 359 "/Peripherals/USB_DP")
			(pintype "passive")
		)
		(pad "2" smd roundrect
			(at 0.48 0 270)
			(size 0.59 0.64)
			(layers "B.Cu" "B.Mask" "B.Paste")
			(roundrect_rratio 0.25)
			(net 362 "/Peripherals/USB_D2P")
			(pintype "passive")
		)
	)
	(footprint "antmicro-footprints:C_0201"
		(layer "B.Cu")
		(at 122.3 89.9 -90)
		(descr "Capacitor SMD 0201")
		(tags "capacitor SMD 0201")
		(property "Reference" "C115"
			(at -13.895736 9.07 90)
			(layer "B.SilkS")
			(effects
				(font
					(size 0.65 0.65)
					(thickness 0.15)
				)
				(justify left bottom mirror)
			)
		)
		(property "Value" "C_100n_0201"
			(at 0 -1.4 90)
			(layer "B.Fab")
			(hide yes)
			(effects
				(font
					(size 0.7 0.7)
					(thickness 0.15)
				)
				(justify left bottom mirror)
			)
		)
		(property "Datasheet" "https://www.yageo.com/en/Chart/Download/pdf/CC0201KRX6S5BB104"
			(at 0 0 270)
			(layer "F.Fab")
			(hide yes)
			(effects
				(font
					(size 1.27 1.27)
					(thickness 0.15)
				)
			)
		)
		(property "Description" "SMD Multilayer Ceramic Capacitor, 0.1 µF, 6.3 V, 0201 [0603 Metric], ± 10%, X6S, CC Series"
			(at 0 0 270)
			(layer "F.Fab")
			(hide yes)
			(effects
				(font
					(size 1.27 1.27)
					(thickness 0.15)
				)
			)
		)
		(property "Author" "Antmicro"
			(at 32.4 212.2 0)
			(layer "B.Fab")
			(hide yes)
			(effects
				(font
					(size 1 1)
					(thickness 0.15)
				)
				(justify mirror)
			)
		)
		(property "Dielectric" ""
			(at 32.4 212.2 0)
			(layer "B.Fab")
			(hide yes)
			(effects
				(font
					(size 1 1)
					(thickness 0.15)
				)
				(justify mirror)
			)
		)
		(property "License" "Apache-2.0"
			(at 32.4 212.2 0)
			(layer "B.Fab")
			(hide yes)
			(effects
				(font
					(size 1 1)
					(thickness 0.15)
				)
				(justify mirror)
			)
		)
		(property "MPN" "CC0201KRX6S5BB104"
			(at 32.4 212.2 0)
			(layer "B.Fab")
			(hide yes)
			(effects
				(font
					(size 1 1)
					(thickness 0.15)
				)
				(justify mirror)
			)
		)
		(property "Manufacturer" "YAGEO"
			(at 32.4 212.2 0)
			(layer "B.Fab")
			(hide yes)
			(effects
				(font
					(size 1 1)
					(thickness 0.15)
				)
				(justify mirror)
			)
		)
		(property "Val" "100n"
			(at 32.4 212.2 0)
			(layer "B.Fab")
			(hide yes)
			(effects
				(font
					(size 1 1)
					(thickness 0.15)
				)
				(justify mirror)
			)
		)
		(property "Voltage" ""
			(at 32.4 212.2 0)
			(layer "B.Fab")
			(hide yes)
			(effects
				(font
					(size 1 1)
					(thickness 0.15)
				)
				(justify mirror)
			)
		)
		(property "Public" "False"
			(at 0 0 270)
			(unlocked yes)
			(layer "B.Fab")
			(hide yes)
			(effects
				(font
					(size 1 1)
					(thickness 0.15)
				)
				(justify mirror)
			)
		)
		(sheetname "/SDI/")
		(sheetfile "sdi.kicad_sch")
		(attr smd)
		(fp_rect
			(start -0.7 0.35)
			(end 0.7 -0.35)
			(stroke
				(width 0.05)
				(type default)
			)
			(fill no)
			(layer "B.CrtYd")
		)
		(fp_rect
			(start 0.3 -0.15)
			(end -0.301 0.149)
			(stroke
				(width 0.15)
				(type solid)
			)
			(fill no)
			(layer "B.Fab")
		)
		(fp_text user "Author: Antmicro"
			(at -0.72 -5.4 90)
			(layer "B.Fab")
			(effects
				(font
					(size 0.7 0.7)
					(thickness 0.15)
				)
				(justify left bottom mirror)
			)
		)
		(fp_text user "${REFERENCE}"
			(at -0.72 -3.4 90)
			(layer "B.Fab")
			(effects
				(font
					(size 0.7 0.7)
					(thickness 0.15)
				)
				(justify left bottom mirror)
			)
		)
		(fp_text user "License: Apache-2.0"
			(at -0.72 -4.4 90)
			(layer "B.Fab")
			(effects
				(font
					(size 0.7 0.7)
					(thickness 0.15)
				)
				(justify left bottom mirror)
			)
		)
		(pad "" smd roundrect
			(at -0.349 0.002 270)
			(size 0.318 0.36)
			(layers "B.Paste")
			(roundrect_rratio 0.25)
		)
		(pad "" smd roundrect
			(at 0.341 0.002 270)
			(size 0.318 0.36)
			(layers "B.Paste")
			(roundrect_rratio 0.25)
		)
		(pad "1" smd roundrect
			(at -0.321 0.002 270)
			(size 0.46 0.4)
			(layers "B.Cu" "B.Mask")
			(roundrect_rratio 0.25)
			(net 1 "GND")
			(pintype "passive")
		)
		(pad "2" smd roundrect
			(at 0.32 0.002 270)
			(size 0.46 0.4)
			(layers "B.Cu" "B.Mask")
			(roundrect_rratio 0.25)
			(net 2 "+3V3")
			(pintype "passive")
		)
	)
	(footprint "antmicro-footprints:R_0402_1005Metric"
		(layer "B.Cu")
		(at 146.2 81.5 -90)
		(descr "Resistor SMD 0402")
		(tags "resistor SMD 0402")
		(property "Reference" "R133"
			(at -3.66 -0.33 90)
			(layer "B.SilkS")
			(effects
				(font
					(size 0.65 0.65)
					(thickness 0.15)
				)
				(justify left bottom mirror)
			)
		)
		(property "Value" "R_27R_0402"
			(at 0 -1.4 90)
			(layer "B.Fab")
			(hide yes)
			(effects
				(font
					(size 0.7 0.7)
					(thickness 0.15)
				)
				(justify left bottom mirror)
			)
		)
		(property "Datasheet" "https://www.bourns.com/docs/product-datasheets/cr.pdf"
			(at 0 0 270)
			(layer "F.Fab")
			(hide yes)
			(effects
				(font
					(size 1.27 1.27)
					(thickness 0.15)
				)
			)
		)
		(property "Description" "SMD Chip Resistor, 27 ohm, ± 1%, 63 mW, 0402 [1005 Metric], Thick Film, General Purpose"
			(at 0 0 270)
			(layer "F.Fab")
			(hide yes)
			(effects
				(font
					(size 1.27 1.27)
					(thickness 0.15)
				)
			)
		)
		(property "Author" "Antmicro"
			(at 64.7 227.7 0)
			(layer "B.Fab")
			(hide yes)
			(effects
				(font
					(size 1 1)
					(thickness 0.15)
				)
				(justify mirror)
			)
		)
		(property "License" "Apache-2.0"
			(at 64.7 227.7 0)
			(layer "B.Fab")
			(hide yes)
			(effects
				(font
					(size 1 1)
					(thickness 0.15)
				)
				(justify mirror)
			)
		)
		(property "MPN" "CR0402-FX-27R0GLF"
			(at 64.7 227.7 0)
			(layer "B.Fab")
			(hide yes)
			(effects
				(font
					(size 1 1)
					(thickness 0.15)
				)
				(justify mirror)
			)
		)
		(property "Manufacturer" "Bourns"
			(at 64.7 227.7 0)
			(layer "B.Fab")
			(hide yes)
			(effects
				(font
					(size 1 1)
					(thickness 0.15)
				)
				(justify mirror)
			)
		)
		(property "Tolerance" "1%"
			(at 64.7 227.7 0)
			(layer "B.Fab")
			(hide yes)
			(effects
				(font
					(size 1 1)
					(thickness 0.15)
				)
				(justify mirror)
			)
		)
		(property "Val" "27R"
			(at 64.7 227.7 0)
			(layer "B.Fab")
			(hide yes)
			(effects
				(font
					(size 1 1)
					(thickness 0.15)
				)
				(justify mirror)
			)
		)
		(sheetname "/Peripherals/")
		(sheetfile "peripherals.kicad_sch")
		(attr smd)
		(fp_rect
			(start -0.925 0.47)
			(end 0.925 -0.47)
			(stroke
				(width 0.05)
				(type default)
			)
			(fill no)
			(layer "B.CrtYd")
		)
		(fp_rect
			(start -0.5 0.25)
			(end 0.5 -0.25)
			(stroke
				(width 0.15)
				(type solid)
			)
			(fill no)
			(layer "B.Fab")
		)
		(fp_text user "License: Apache-2.0"
			(at -0.95 -5.169 90)
			(layer "B.Fab")
			(effects
				(font
					(size 0.7 0.7)
					(thickness 0.15)
				)
				(justify left bottom mirror)
			)
		)
		(fp_text user "${REFERENCE}"
			(at -0.95 -3.168 90)
			(layer "B.Fab")
			(effects
				(font
					(size 0.7 0.7)
					(thickness 0.15)
				)
				(justify left bottom mirror)
			)
		)
		(fp_text user "Author: Antmicro"
			(at -0.95 -4.169 90)
			(layer "B.Fab")
			(effects
				(font
					(size 0.7 0.7)
					(thickness 0.15)
				)
				(justify left bottom mirror)
			)
		)
		(pad "1" smd roundrect
			(at -0.48 0 270)
			(size 0.59 0.64)
			(layers "B.Cu" "B.Mask" "B.Paste")
			(roundrect_rratio 0.25)
			(net 360 "/Peripherals/USB_DN")
			(pintype "passive")
		)
		(pad "2" smd roundrect
			(at 0.48 0 270)
			(size 0.59 0.64)
			(layers "B.Cu" "B.Mask" "B.Paste")
			(roundrect_rratio 0.25)
			(net 361 "/Peripherals/USB_D2N")
			(pintype "passive")
		)
	)
	(footprint "antmicro-footprints:C_0603_1608Metric"
		(layer "B.Cu")
		(at 136.55 61.86 90)
		(descr "Capacitor SMD 0603")
		(tags "capacitor 0603")
		(property "Reference" "C108"
			(at -1.19 1.58 90)
			(layer "B.SilkS")
			(effects
				(font
					(size 0.65 0.65)
					(thickness 0.15)
				)
				(justify right bottom mirror)
			)
		)
		(property "Value" "C_10u_0603"
			(at 0 -1.6 90)
			(layer "B.Fab")
			(hide yes)
			(effects
				(font
					(size 0.7 0.7)
					(thickness 0.15)
				)
				(justify right bottom mirror)
			)
		)
		(property "Datasheet" "https://www.murata.com/products/productdetail?partno=GRM188R61A106KE69%23"
			(at 0 0 90)
			(layer "F.Fab")
			(hide yes)
			(effects
				(font
					(size 1.27 1.27)
					(thickness 0.15)
				)
			)
		)
		(property "Description" "SMD Multilayer Ceramic Capacitor, 10 µF, 10 V, 0603 [1608 Metric], ± 10%, X5R, GRM Series"
			(at 0 0 90)
			(layer "F.Fab")
			(hide yes)
			(effects
				(font
					(size 1.27 1.27)
					(thickness 0.15)
				)
			)
		)
		(property "Author" "Antmicro"
			(at 198.5 -74.8 0)
			(layer "B.Fab")
			(hide yes)
			(effects
				(font
					(size 1 1)
					(thickness 0.15)
				)
				(justify mirror)
			)
		)
		(property "License" "Apache-2.0"
			(at 198.5 -74.8 0)
			(layer "B.Fab")
			(hide yes)
			(effects
				(font
					(size 1 1)
					(thickness 0.15)
				)
				(justify mirror)
			)
		)
		(property "MPN" "GRM188R61A106KE69D"
			(at 198.5 -74.8 0)
			(layer "B.Fab")
			(hide yes)
			(effects
				(font
					(size 1 1)
					(thickness 0.15)
				)
				(justify mirror)
			)
		)
		(property "Manufacturer" "Murata"
			(at 198.5 -74.8 0)
			(layer "B.Fab")
			(hide yes)
			(effects
				(font
					(size 1 1)
					(thickness 0.15)
				)
				(justify mirror)
			)
		)
		(property "Val" "10u"
			(at 198.5 -74.8 0)
			(layer "B.Fab")
			(hide yes)
			(effects
				(font
					(size 1 1)
					(thickness 0.15)
				)
				(justify mirror)
			)
		)
		(property "Voltage" ""
			(at 198.5 -74.8 0)
			(layer "B.Fab")
			(hide yes)
			(effects
				(font
					(size 1 1)
					(thickness 0.15)
				)
				(justify mirror)
			)
		)
		(property "Dielectric" "template_dielectric"
			(at 0 0 90)
			(unlocked yes)
			(layer "B.Fab")
			(hide yes)
			(effects
				(font
					(size 1 1)
					(thickness 0.15)
				)
				(justify mirror)
			)
		)
		(sheetname "/Power Supply/")
		(sheetfile "supply.kicad_sch")
		(attr smd)
		(fp_line
			(start -0.15 -0.4)
			(end 0.15 -0.4)
			(stroke
				(width 0.15)
				(type solid)
			)
			(layer "B.SilkS")
		)
		(fp_line
			(start -0.15 0.4)
			(end 0.15 0.4)
			(stroke
				(width 0.15)
				(type solid)
			)
			(layer "B.SilkS")
		)
		(fp_rect
			(start -1.25 0.65)
			(end 1.25 -0.65)
			(stroke
				(width 0.05)
				(type solid)
			)
			(fill no)
			(layer "B.CrtYd")
		)
		(fp_rect
			(start -0.8 0.4)
			(end 0.8 -0.4)
			(stroke
				(width 0.15)
				(type solid)
			)
			(fill no)
			(layer "B.Fab")
		)
		(fp_text user "License: Apache-2.0"
			(at -1.682 -5.895 270)
			(layer "B.Fab")
			(effects
				(font
					(size 0.7 0.7)
					(thickness 0.15)
				)
				(justify left bottom mirror)
			)
		)
		(fp_text user "Author: Antmicro"
			(at -1.682 -4.894 270)
			(layer "B.Fab")
			(effects
				(font
					(size 0.7 0.7)
					(thickness 0.15)
				)
				(justify left bottom mirror)
			)
		)
		(fp_text user "${REFERENCE}"
			(at -1.682 -3.895 270)
			(layer "B.Fab")
			(effects
				(font
					(size 0.7 0.7)
					(thickness 0.15)
				)
				(justify left bottom mirror)
			)
		)
		(pad "1" smd roundrect
			(at -0.7 0 90)
			(size 0.8 1)
			(layers "B.Cu" "B.Mask" "B.Paste")
			(roundrect_rratio 0.2)
			(net 1 "GND")
			(pintype "passive")
		)
		(pad "2" smd roundrect
			(at 0.7 0 90)
			(size 0.8 1)
			(layers "B.Cu" "B.Mask" "B.Paste")
			(roundrect_rratio 0.2)
			(net 2 "+3V3")
			(pintype "passive")
		)
	)
	(footprint "antmicro-footprints:TP_SMD_0.75mm"
		(layer "B.Cu")
		(at 97.69 88.95 90)
		(property "Reference" "TP30"
			(at -0.49 0.44 90)
			(layer "B.SilkS")
			(effects
				(font
					(size 0.65 0.65)
					(thickness 0.15)
				)
				(justify left bottom mirror)
			)
		)
		(property "Value" "TP_0.75mm_SMD"
			(at 0 -1.2 90)
			(layer "B.Fab")
			(hide yes)
			(effects
				(font
					(size 0.7 0.7)
					(thickness 0.15)
				)
				(justify right bottom mirror)
			)
		)
		(property "Description" "SMT test point"
			(at 0 0 90)
			(layer "F.Fab")
			(hide yes)
			(effects
				(font
					(size 1.27 1.27)
					(thickness 0.15)
				)
			)
		)
		(property "Author" "Antmicro"
			(at 186.64 -8.74 0)
			(layer "B.Fab")
			(hide yes)
			(effects
				(font
					(size 1 1)
					(thickness 0.15)
				)
				(justify mirror)
			)
		)
		(property "License" "Apache-2.0"
			(at 186.64 -8.74 0)
			(layer "B.Fab")
			(hide yes)
			(effects
				(font
					(size 1 1)
					(thickness 0.15)
				)
				(justify mirror)
			)
		)
		(property "MPN" ""
			(at 186.64 -8.74 0)
			(layer "B.Fab")
			(hide yes)
			(effects
				(font
					(size 1 1)
					(thickness 0.15)
				)
				(justify mirror)
			)
		)
		(property "Manufacturer" ""
			(at 186.64 -8.74 0)
			(layer "B.Fab")
			(hide yes)
			(effects
				(font
					(size 1 1)
					(thickness 0.15)
				)
				(justify mirror)
			)
		)
		(sheetname "/SDI/")
		(sheetfile "sdi.kicad_sch")
		(attr exclude_from_pos_files)
		(fp_circle
			(center 0 0)
			(end 0.475 0)
			(stroke
				(width 0.05)
				(type default)
			)
			(fill no)
			(layer "B.CrtYd")
		)
		(fp_text user "Author: Antmicro"
			(at -0.4 -3.901 270)
			(layer "B.Fab")
			(effects
				(font
					(size 0.7 0.7)
					(thickness 0.15)
				)
				(justify left bottom mirror)
			)
		)
		(fp_text user "License: Apache-2.0"
			(at -0.4 -5.101 270)
			(layer "B.Fab")
			(effects
				(font
					(size 0.7 0.7)
					(thickness 0.15)
				)
				(justify left bottom mirror)
			)
		)
		(fp_text user "${REFERENCE}"
			(at -0.4 -2.7 270)
			(layer "B.Fab")
			(effects
				(font
					(size 0.7 0.7)
					(thickness 0.15)
				)
				(justify left bottom mirror)
			)
		)
		(pad "1" smd circle
			(at 0 0 90)
			(size 0.75 0.75)
			(layers "B.Cu" "B.Mask")
			(net 200 "/SDI/20bit{slash}~{10bit}")
			(pinfunction "1")
			(pintype "passive")
		)
	)
	(footprint "antmicro-footprints:R_Array_4x0402"
		(layer "B.Cu")
		(at 127.06 57.44 180)
		(property "Reference" "R45"
			(at -0.97 1 0)
			(layer "B.SilkS")
			(effects
				(font
					(size 0.65 0.65)
					(thickness 0.15)
				)
				(justify left bottom mirror)
			)
		)
		(property "Value" "R_4x51R_0402_array"
			(at -1.5 -2 0)
			(layer "B.Fab")
			(hide yes)
			(effects
				(font
					(size 0.7 0.7)
					(thickness 0.15)
				)
				(justify left bottom mirror)
			)
		)
		(property "Datasheet" "http://industrial.panasonic.com/cdbs/www-data/pdf/AOC0000/AOC0000C14.pdf"
			(at 0 0 180)
			(layer "F.Fab")
			(hide yes)
			(effects
				(font
					(size 1.27 1.27)
					(thickness 0.15)
				)
			)
		)
		(property "Description" "Fixed Network Resistor, 51 ohm, Isolated, 4 Resistors, 0804 [2010 Metric], Convex, ± 5%"
			(at 0 0 180)
			(layer "F.Fab")
			(hide yes)
			(effects
				(font
					(size 1.27 1.27)
					(thickness 0.15)
				)
			)
		)
		(property "Author" "Antmicro"
			(at 254.12 114.88 0)
			(layer "B.Fab")
			(hide yes)
			(effects
				(font
					(size 1 1)
					(thickness 0.15)
				)
				(justify mirror)
			)
		)
		(property "License" "Apache-2.0"
			(at 254.12 114.88 0)
			(layer "B.Fab")
			(hide yes)
			(effects
				(font
					(size 1 1)
					(thickness 0.15)
				)
				(justify mirror)
			)
		)
		(property "MPN" "EXB28V510JX"
			(at 254.12 114.88 0)
			(layer "B.Fab")
			(hide yes)
			(effects
				(font
					(size 1 1)
					(thickness 0.15)
				)
				(justify mirror)
			)
		)
		(property "Manufacturer" "Panasonic"
			(at 254.12 114.88 0)
			(layer "B.Fab")
			(hide yes)
			(effects
				(font
					(size 1 1)
					(thickness 0.15)
				)
				(justify mirror)
			)
		)
		(property "Val" "R_4x51R_0402"
			(at 254.12 114.88 0)
			(layer "B.Fab")
			(hide yes)
			(effects
				(font
					(size 1 1)
					(thickness 0.15)
				)
				(justify mirror)
			)
		)
		(sheetname "/DDR3/")
		(sheetfile "ddr3.kicad_sch")
		(attr smd)
		(fp_line
			(start 1.167 -0.498)
			(end 1.167 0.5)
			(stroke
				(width 0.15)
				(type solid)
			)
			(layer "B.SilkS")
		)
		(fp_line
			(start -1.17 0.5)
			(end -1.17 -0.498)
			(stroke
				(width 0.15)
				(type solid)
			)
			(layer "B.SilkS")
		)
		(fp_rect
			(start -1.2 0.9)
			(end 1.2 -0.9)
			(stroke
				(width 0.05)
				(type solid)
			)
			(fill no)
			(layer "B.CrtYd")
		)
		(fp_line
			(start 0.998 0.5)
			(end 0.998 -0.498)
			(stroke
				(width 0.15)
				(type solid)
			)
			(layer "B.Fab")
		)
		(fp_line
			(start 0.998 -0.498)
			(end -1 -0.498)
			(stroke
				(width 0.15)
				(type solid)
			)
			(layer "B.Fab")
		)
		(fp_line
			(start -1 0.5)
			(end 0.998 0.5)
			(stroke
				(width 0.15)
				(type solid)
			)
			(layer "B.Fab")
		)
		(fp_line
			(start -1 -0.498)
			(end -1 0.5)
			(stroke
				(width 0.15)
				(type solid)
			)
			(layer "B.Fab")
		)
		(pad "1" smd roundrect
			(at -0.802 -0.45 180)
			(size 0.4 0.5)
			(layers "B.Cu" "B.Mask" "B.Paste")
			(roundrect_rratio 0.25)
			(net 149 "/DDR3/DDR3_A5")
			(pinfunction "R1.1")
			(pintype "passive")
		)
		(pad "2" smd roundrect
			(at -0.272 -0.45 180)
			(size 0.4 0.5)
			(layers "B.Cu" "B.Mask" "B.Paste")
			(roundrect_rratio 0.25)
			(net 150 "/DDR3/DDR3_A7")
			(pinfunction "R2.1")
			(pintype "passive")
		)
		(pad "3" smd roundrect
			(at 0.27 -0.45 180)
			(size 0.4 0.5)
			(layers "B.Cu" "B.Mask" "B.Paste")
			(roundrect_rratio 0.25)
			(net 164 "/DDR3/~{DDR3_RESET}")
			(pinfunction "R3.1")
			(pintype "passive")
		)
		(pad "4" smd roundrect
			(at 0.8 -0.45 180)
			(size 0.4 0.5)
			(layers "B.Cu" "B.Mask" "B.Paste")
			(roundrect_rratio 0.25)
			(net 153 "/DDR3/DDR3_A9")
			(pinfunction "R4.1")
			(pintype "passive")
		)
		(pad "5" smd roundrect
			(at 0.8 0.452 180)
			(size 0.4 0.5)
			(layers "B.Cu" "B.Mask" "B.Paste")
			(roundrect_rratio 0.25)
			(net 6 "Vtt")
			(pinfunction "R4.2")
			(pintype "passive")
		)
		(pad "6" smd roundrect
			(at 0.27 0.452 180)
			(size 0.4 0.5)
			(layers "B.Cu" "B.Mask" "B.Paste")
			(roundrect_rratio 0.25)
			(net 6 "Vtt")
			(pinfunction "R3.2")
			(pintype "passive")
		)
		(pad "7" smd roundrect
			(at -0.272 0.452 180)
			(size 0.4 0.5)
			(layers "B.Cu" "B.Mask" "B.Paste")
			(roundrect_rratio 0.25)
			(net 6 "Vtt")
			(pinfunction "R2.2")
			(pintype "passive")
		)
		(pad "8" smd roundrect
			(at -0.802 0.452 180)
			(size 0.4 0.5)
			(layers "B.Cu" "B.Mask" "B.Paste")
			(roundrect_rratio 0.25)
			(net 6 "Vtt")
			(pinfunction "R1.2")
			(pintype "passive")
		)
	)
	(footprint "antmicro-footprints:MSOP-8-1EP_3x3x1.1mm_P0.65mm"
		(layer "B.Cu")
		(at 133.1 59.24 -90)
		(descr "http://www.ti.com/lit/ds/symlink/tpa2005d1-q1.pdf")
		(property "Reference" "U1"
			(at -0.3 1.97 90)
			(layer "B.SilkS")
			(effects
				(font
					(size 0.65 0.65)
					(thickness 0.15)
				)
				(justify left bottom mirror)
			)
		)
		(property "Value" "MP20073DH"
			(at 7.2 -2.6 90)
			(layer "B.Fab")
			(hide yes)
			(effects
				(font
					(size 0.7 0.7)
					(thickness 0.15)
				)
				(justify left bottom mirror)
			)
		)
		(property "Datasheet" "https://www.farnell.com/datasheets/2915039.pdf"
			(at 0 0 90)
			(layer "F.Fab")
			(hide yes)
			(effects
				(font
					(size 1.27 1.27)
					(thickness 0.15)
				)
			)
		)
		(property "Description" "DDR Termination Regulator, DDR2, DDR3, 1.3V to 6V in, 2A, MSOP-EP-8"
			(at 0 0 90)
			(layer "F.Fab")
			(hide yes)
			(effects
				(font
					(size 1.27 1.27)
					(thickness 0.15)
				)
			)
		)
		(property "Author" "Antmicro"
			(at 73.86 192.34 0)
			(layer "B.Fab")
			(hide yes)
			(effects
				(font
					(size 1 1)
					(thickness 0.15)
				)
				(justify mirror)
			)
		)
		(property "License" "Apache-2.0"
			(at 73.86 192.34 0)
			(layer "B.Fab")
			(hide yes)
			(effects
				(font
					(size 1 1)
					(thickness 0.15)
				)
				(justify mirror)
			)
		)
		(property "MPN" "MP20073DH-LF-P"
			(at 73.86 192.34 0)
			(layer "B.Fab")
			(hide yes)
			(effects
				(font
					(size 1 1)
					(thickness 0.15)
				)
				(justify mirror)
			)
		)
		(property "Manufacturer" "Monolithic Power Systems"
			(at 73.86 192.34 0)
			(layer "B.Fab")
			(hide yes)
			(effects
				(font
					(size 1 1)
					(thickness 0.15)
				)
				(justify mirror)
			)
		)
		(sheetname "/Power Supply/")
		(sheetfile "supply.kicad_sch")
		(attr smd)
		(fp_line
			(start -1.299 1.601)
			(end -1.6 1.302)
			(stroke
				(width 0.15)
				(type solid)
			)
			(layer "B.SilkS")
		)
		(fp_line
			(start 1.3 1.601)
			(end 1.601 1.601)
			(stroke
				(width 0.15)
				(type solid)
			)
			(layer "B.SilkS")
		)
		(fp_line
			(start 1.601 1.601)
			(end 1.601 1.302)
			(stroke
				(width 0.15)
				(type solid)
			)
			(layer "B.SilkS")
		)
		(fp_line
			(start 1.601 -1.298)
			(end 1.601 -1.6)
			(stroke
				(width 0.15)
				(type solid)
			)
			(layer "B.SilkS")
		)
		(fp_line
			(start -1.6 -1.6)
			(end -1.6 -1.298)
			(stroke
				(width 0.15)
				(type solid)
			)
			(layer "B.SilkS")
		)
		(fp_line
			(start -1.299 -1.6)
			(end -1.6 -1.6)
			(stroke
				(width 0.15)
				(type solid)
			)
			(layer "B.SilkS")
		)
		(fp_line
			(start 1.601 -1.6)
			(end 1.3 -1.6)
			(stroke
				(width 0.15)
				(type solid)
			)
			(layer "B.SilkS")
		)
		(fp_circle
			(center -2.1 1.4)
			(end -2.15 1.45)
			(stroke
				(width 0.15)
				(type solid)
			)
			(fill yes)
			(layer "B.SilkS")
		)
		(fp_rect
			(start -3.179 1.747)
			(end 3.171 -1.753)
			(stroke
				(width 0.05)
				(type solid)
			)
			(fill no)
			(layer "B.CrtYd")
		)
		(fp_line
			(start -1.099 1.451)
			(end -1.45 1.101)
			(stroke
				(width 0.15)
				(type solid)
			)
			(layer "B.Fab")
		)
		(fp_line
			(start 1.45 1.451)
			(end -1.099 1.451)
			(stroke
				(width 0.15)
				(type solid)
			)
			(layer "B.Fab")
		)
		(fp_line
			(start 1.45 1.451)
			(end 1.45 -1.449)
			(stroke
				(width 0.15)
				(type solid)
			)
			(layer "B.Fab")
		)
		(fp_line
			(start -1.45 1.101)
			(end -1.45 -1.449)
			(stroke
				(width 0.15)
				(type solid)
			)
			(layer "B.Fab")
		)
		(fp_line
			(start 1.45 -1.449)
			(end -1.45 -1.449)
			(stroke
				(width 0.15)
				(type solid)
			)
			(layer "B.Fab")
		)
		(fp_text user "${REFERENCE}"
			(at -3.179 -4.6 90)
			(layer "B.Fab")
			(effects
				(font
					(size 0.7 0.7)
					(thickness 0.15)
				)
				(justify left bottom mirror)
			)
		)
		(fp_text user "Author: Antmicro"
			(at -3.179 -5.8 90)
			(layer "B.Fab")
			(effects
				(font
					(size 0.7 0.7)
					(thickness 0.15)
				)
				(justify left bottom mirror)
			)
		)
		(fp_text user "License: Apache-2.0"
			(at -3.179 -7 90)
			(layer "B.Fab")
			(effects
				(font
					(size 0.7 0.7)
					(thickness 0.15)
				)
				(justify left bottom mirror)
			)
		)
		(pad "1" smd roundrect
			(at -2.199 0.977)
			(size 0.45 1.45)
			(layers "B.Cu" "B.Mask" "B.Paste")
			(roundrect_rratio 0.25)
			(net 60 "Net-(U1-DDQ)")
			(pinfunction "DDQ")
			(pintype "power_in")
		)
		(pad "2" smd roundrect
			(at -2.199 0.326)
			(size 0.45 1.45)
			(layers "B.Cu" "B.Mask" "B.Paste")
			(roundrect_rratio 0.25)
			(net 6 "Vtt")
			(pinfunction "V_{TT}")
			(pintype "passive")
		)
		(pad "3" smd roundrect
			(at -2.199 -0.324)
			(size 0.45 1.45)
			(layers "B.Cu" "B.Mask" "B.Paste")
			(roundrect_rratio 0.25)
			(net 1 "GND")
			(pinfunction "GND")
			(pintype "power_in")
		)
		(pad "4" smd roundrect
			(at -2.199 -0.973)
			(size 0.45 1.45)
			(layers "B.Cu" "B.Mask" "B.Paste")
			(roundrect_rratio 0.25)
			(net 6 "Vtt")
			(pinfunction "V_{TTSEN}")
			(pintype "passive")
		)
		(pad "5" smd roundrect
			(at 2.201 -0.973)
			(size 0.45 1.45)
			(layers "B.Cu" "B.Mask" "B.Paste")
			(roundrect_rratio 0.25)
			(net 2 "+3V3")
			(pinfunction "V_{DRV}")
			(pintype "passive")
		)
		(pad "6" smd roundrect
			(at 2.201 -0.324)
			(size 0.45 1.45)
			(layers "B.Cu" "B.Mask" "B.Paste")
			(roundrect_rratio 0.25)
			(net 30 "Net-(U1-REF)")
			(pinfunction "REF")
			(pintype "passive")
		)
		(pad "7" smd roundrect
			(at 2.201 0.326)
			(size 0.45 1.45)
			(layers "B.Cu" "B.Mask" "B.Paste")
			(roundrect_rratio 0.25)
			(net 262 "Net-(U1-V_{TT_EN})")
			(pinfunction "V_{TT_EN}")
			(pintype "passive")
		)
		(pad "8" smd roundrect
			(at 2.201 0.977)
			(size 0.45 1.45)
			(layers "B.Cu" "B.Mask" "B.Paste")
			(roundrect_rratio 0.25)
			(net 5 "Vref")
			(pinfunction "V_{TTREF}")
			(pintype "passive")
		)
		(pad "9" smd rect
			(at 0 0 270)
			(size 1.98 1.88)
			(layers "B.Cu" "B.Mask" "B.Paste")
			(net 1 "GND")
			(pinfunction "GND")
			(pintype "passive")
		)
	)
	(footprint "antmicro-footprints:C_0402_1005Metric"
		(layer "B.Cu")
		(at 97.1 84 90)
		(descr "Capacitor SMD 0402")
		(tags "capacitor SMD 0402")
		(property "Reference" "C67"
			(at -0.94 -0.67 90)
			(layer "B.SilkS")
			(effects
				(font
					(size 0.65 0.65)
					(thickness 0.15)
				)
				(justify right bottom mirror)
			)
		)
		(property "Value" "C_100n_0402"
			(at 0 -1.4 90)
			(layer "B.Fab")
			(hide yes)
			(effects
				(font
					(size 0.7 0.7)
					(thickness 0.15)
				)
				(justify right bottom mirror)
			)
		)
		(property "Datasheet" "https://www.murata.com/products/productdetail?partno=GRM155R61H104KE14%23"
			(at 0 0 90)
			(layer "F.Fab")
			(hide yes)
			(effects
				(font
					(size 1.27 1.27)
					(thickness 0.15)
				)
			)
		)
		(property "Description" "SMD Multilayer Ceramic Capacitor, 0.1 µF, 50 V, 0402 [1005 Metric], ± 10%, X5R, GRM Series"
			(at 0 0 90)
			(layer "F.Fab")
			(hide yes)
			(effects
				(font
					(size 1.27 1.27)
					(thickness 0.15)
				)
			)
		)
		(property "Author" "Antmicro"
			(at 181.1 -13.1 0)
			(layer "B.Fab")
			(hide yes)
			(effects
				(font
					(size 1 1)
					(thickness 0.15)
				)
				(justify mirror)
			)
		)
		(property "Dielectric" "X5R"
			(at 181.1 -13.1 0)
			(layer "B.Fab")
			(hide yes)
			(effects
				(font
					(size 1 1)
					(thickness 0.15)
				)
				(justify mirror)
			)
		)
		(property "License" "Apache-2.0"
			(at 181.1 -13.1 0)
			(layer "B.Fab")
			(hide yes)
			(effects
				(font
					(size 1 1)
					(thickness 0.15)
				)
				(justify mirror)
			)
		)
		(property "MPN" "GRM155R61H104KE14D"
			(at 181.1 -13.1 0)
			(layer "B.Fab")
			(hide yes)
			(effects
				(font
					(size 1 1)
					(thickness 0.15)
				)
				(justify mirror)
			)
		)
		(property "Manufacturer" "Murata"
			(at 181.1 -13.1 0)
			(layer "B.Fab")
			(hide yes)
			(effects
				(font
					(size 1 1)
					(thickness 0.15)
				)
				(justify mirror)
			)
		)
		(property "Val" "100n"
			(at 181.1 -13.1 0)
			(layer "B.Fab")
			(hide yes)
			(effects
				(font
					(size 1 1)
					(thickness 0.15)
				)
				(justify mirror)
			)
		)
		(property "Voltage" "50V"
			(at 181.1 -13.1 0)
			(layer "B.Fab")
			(hide yes)
			(effects
				(font
					(size 1 1)
					(thickness 0.15)
				)
				(justify mirror)
			)
		)
		(sheetname "/SDI/")
		(sheetfile "sdi.kicad_sch")
		(attr smd)
		(fp_rect
			(start -0.925 0.47)
			(end 0.925 -0.47)
			(stroke
				(width 0.05)
				(type default)
			)
			(fill no)
			(layer "B.CrtYd")
		)
		(fp_line
			(start 0.504 -0.248)
			(end -0.494 -0.248)
			(stroke
				(width 0.15)
				(type solid)
			)
			(layer "B.Fab")
		)
		(fp_line
			(start -0.494 -0.248)
			(end -0.494 0.25)
			(stroke
				(width 0.15)
				(type solid)
			)
			(layer "B.Fab")
		)
		(fp_line
			(start 0.504 0.25)
			(end 0.504 -0.248)
			(stroke
				(width 0.15)
				(type solid)
			)
			(layer "B.Fab")
		)
		(fp_line
			(start -0.494 0.25)
			(end 0.504 0.25)
			(stroke
				(width 0.15)
				(type solid)
			)
			(layer "B.Fab")
		)
		(fp_text user "${REFERENCE}"
			(at -0.939 -4.599 270)
			(layer "B.Fab")
			(effects
				(font
					(size 0.7 0.7)
					(thickness 0.15)
				)
				(justify left bottom mirror)
			)
		)
		(fp_text user "License: Apache-2.0"
			(at -0.939 -5.799 270)
			(layer "B.Fab")
			(effects
				(font
					(size 0.7 0.7)
					(thickness 0.15)
				)
				(justify left bottom mirror)
			)
		)
		(fp_text user "Author: Antmicro"
			(at -0.939 -3.399 270)
			(layer "B.Fab")
			(effects
				(font
					(size 0.7 0.7)
					(thickness 0.15)
				)
				(justify left bottom mirror)
			)
		)
		(pad "1" smd roundrect
			(at -0.48 0 90)
			(size 0.59 0.64)
			(layers "B.Cu" "B.Mask" "B.Paste")
			(roundrect_rratio 0.25)
			(net 1 "GND")
			(pintype "passive")
		)
		(pad "2" smd roundrect
			(at 0.48 0 90)
			(size 0.59 0.64)
			(layers "B.Cu" "B.Mask" "B.Paste")
			(roundrect_rratio 0.25)
			(net 2 "+3V3")
			(pintype "passive")
		)
	)
	(footprint "antmicro-footprints:R_0402_1005Metric"
		(layer "B.Cu")
		(at 104.19 96.8 -90)
		(descr "Resistor SMD 0402")
		(tags "resistor SMD 0402")
		(property "Reference" "R71"
			(at 0.94 -0.34 90)
			(layer "B.SilkS")
			(effects
				(font
					(size 0.65 0.65)
					(thickness 0.15)
				)
				(justify left bottom mirror)
			)
		)
		(property "Value" "R_0R_0402"
			(at 0 -1.4 90)
			(layer "B.Fab")
			(hide yes)
			(effects
				(font
					(size 0.7 0.7)
					(thickness 0.15)
				)
				(justify left bottom mirror)
			)
		)
		(property "Datasheet" "https://industrial.panasonic.com/cdbs/www-data/pdf/RDA0000/AOA0000C301.pdf"
			(at 0 0 270)
			(layer "F.Fab")
			(hide yes)
			(effects
				(font
					(size 1.27 1.27)
					(thickness 0.15)
				)
			)
		)
		(property "Description" "SMD Chip Resistor, Jumper, 0 ohm, 100 mW, 0402 [1005 Metric], Thick Film, General Purpose"
			(at 0 0 270)
			(layer "F.Fab")
			(hide yes)
			(effects
				(font
					(size 1.27 1.27)
					(thickness 0.15)
				)
			)
		)
		(property "Author" "Antmicro"
			(at 7.39 200.99 0)
			(layer "B.Fab")
			(hide yes)
			(effects
				(font
					(size 1 1)
					(thickness 0.15)
				)
				(justify mirror)
			)
		)
		(property "Current" "1A"
			(at 7.39 200.99 0)
			(layer "B.Fab")
			(hide yes)
			(effects
				(font
					(size 1 1)
					(thickness 0.15)
				)
				(justify mirror)
			)
		)
		(property "License" "Apache-2.0"
			(at 7.39 200.99 0)
			(layer "B.Fab")
			(hide yes)
			(effects
				(font
					(size 1 1)
					(thickness 0.15)
				)
				(justify mirror)
			)
		)
		(property "MPN" "ERJ2GE0R00X"
			(at 7.39 200.99 0)
			(layer "B.Fab")
			(hide yes)
			(effects
				(font
					(size 1 1)
					(thickness 0.15)
				)
				(justify mirror)
			)
		)
		(property "Manufacturer" "Panasonic"
			(at 7.39 200.99 0)
			(layer "B.Fab")
			(hide yes)
			(effects
				(font
					(size 1 1)
					(thickness 0.15)
				)
				(justify mirror)
			)
		)
		(property "Tolerance" "~"
			(at 7.39 200.99 0)
			(layer "B.Fab")
			(hide yes)
			(effects
				(font
					(size 1 1)
					(thickness 0.15)
				)
				(justify mirror)
			)
		)
		(property "Val" "0R"
			(at 7.39 200.99 0)
			(layer "B.Fab")
			(hide yes)
			(effects
				(font
					(size 1 1)
					(thickness 0.15)
				)
				(justify mirror)
			)
		)
		(sheetname "/FPGA/")
		(sheetfile "fpga.kicad_sch")
		(attr smd)
		(fp_rect
			(start -0.925 0.47)
			(end 0.925 -0.47)
			(stroke
				(width 0.05)
				(type default)
			)
			(fill no)
			(layer "B.CrtYd")
		)
		(fp_rect
			(start -0.5 0.25)
			(end 0.5 -0.25)
			(stroke
				(width 0.15)
				(type solid)
			)
			(fill no)
			(layer "B.Fab")
		)
		(fp_text user "${REFERENCE}"
			(at -0.95 -3.168 90)
			(layer "B.Fab")
			(effects
				(font
					(size 0.7 0.7)
					(thickness 0.15)
				)
				(justify left bottom mirror)
			)
		)
		(fp_text user "License: Apache-2.0"
			(at -0.95 -5.169 90)
			(layer "B.Fab")
			(effects
				(font
					(size 0.7 0.7)
					(thickness 0.15)
				)
				(justify left bottom mirror)
			)
		)
		(fp_text user "Author: Antmicro"
			(at -0.95 -4.169 90)
			(layer "B.Fab")
			(effects
				(font
					(size 0.7 0.7)
					(thickness 0.15)
				)
				(justify left bottom mirror)
			)
		)
		(pad "1" smd roundrect
			(at -0.48 0 270)
			(size 0.59 0.64)
			(layers "B.Cu" "B.Mask" "B.Paste")
			(roundrect_rratio 0.25)
			(net 301 "Net-(U18-SO{slash}IO1)")
			(pintype "passive")
		)
		(pad "2" smd roundrect
			(at 0.48 0 270)
			(size 0.59 0.64)
			(layers "B.Cu" "B.Mask" "B.Paste")
			(roundrect_rratio 0.25)
			(net 38 "/FPGA/SPI_DQ1_MISO")
			(pintype "passive")
		)
	)
	(footprint "antmicro-footprints:TP_SMD_0.75mm"
		(layer "B.Cu")
		(at 99.94 88.2 90)
		(property "Reference" "TP37"
			(at 0.76 0.39 90)
			(layer "B.SilkS")
			(effects
				(font
					(size 0.65 0.65)
					(thickness 0.15)
				)
				(justify right bottom mirror)
			)
		)
		(property "Value" "TP_0.75mm_SMD"
			(at 0 -1.2 90)
			(layer "B.Fab")
			(hide yes)
			(effects
				(font
					(size 0.7 0.7)
					(thickness 0.15)
				)
				(justify right bottom mirror)
			)
		)
		(property "Description" "SMT test point"
			(at 0 0 90)
			(layer "F.Fab")
			(hide yes)
			(effects
				(font
					(size 1.27 1.27)
					(thickness 0.15)
				)
			)
		)
		(property "Author" "Antmicro"
			(at 188.14 -11.74 0)
			(layer "B.Fab")
			(hide yes)
			(effects
				(font
					(size 1 1)
					(thickness 0.15)
				)
				(justify mirror)
			)
		)
		(property "License" "Apache-2.0"
			(at 188.14 -11.74 0)
			(layer "B.Fab")
			(hide yes)
			(effects
				(font
					(size 1 1)
					(thickness 0.15)
				)
				(justify mirror)
			)
		)
		(property "MPN" ""
			(at 188.14 -11.74 0)
			(layer "B.Fab")
			(hide yes)
			(effects
				(font
					(size 1 1)
					(thickness 0.15)
				)
				(justify mirror)
			)
		)
		(property "Manufacturer" ""
			(at 188.14 -11.74 0)
			(layer "B.Fab")
			(hide yes)
			(effects
				(font
					(size 1 1)
					(thickness 0.15)
				)
				(justify mirror)
			)
		)
		(sheetname "/SDI/")
		(sheetfile "sdi.kicad_sch")
		(attr exclude_from_pos_files)
		(fp_circle
			(center 0 0)
			(end 0.475 0)
			(stroke
				(width 0.05)
				(type default)
			)
			(fill no)
			(layer "B.CrtYd")
		)
		(fp_text user "${REFERENCE}"
			(at -0.4 -2.7 270)
			(layer "B.Fab")
			(effects
				(font
					(size 0.7 0.7)
					(thickness 0.15)
				)
				(justify left bottom mirror)
			)
		)
		(fp_text user "Author: Antmicro"
			(at -0.4 -3.901 270)
			(layer "B.Fab")
			(effects
				(font
					(size 0.7 0.7)
					(thickness 0.15)
				)
				(justify left bottom mirror)
			)
		)
		(fp_text user "License: Apache-2.0"
			(at -0.4 -5.101 270)
			(layer "B.Fab")
			(effects
				(font
					(size 0.7 0.7)
					(thickness 0.15)
				)
				(justify left bottom mirror)
			)
		)
		(pad "1" smd circle
			(at 0 0 90)
			(size 0.75 0.75)
			(layers "B.Cu" "B.Mask")
			(net 179 "/SDI/SCLK_TCK")
			(pinfunction "1")
			(pintype "passive")
		)
	)
	(footprint "antmicro-footprints:C_0402_1005Metric"
		(layer "B.Cu")
		(at 120.32 59.7 -135)
		(descr "Capacitor SMD 0402")
		(tags "capacitor SMD 0402")
		(property "Reference" "C42"
			(at -0.827315 0.671751 45)
			(layer "B.SilkS")
			(effects
				(font
					(size 0.65 0.65)
					(thickness 0.15)
				)
				(justify left bottom mirror)
			)
		)
		(property "Value" "C_100n_0402"
			(at 0 -1.399999 45)
			(layer "B.Fab")
			(hide yes)
			(effects
				(font
					(size 0.7 0.7)
					(thickness 0.15)
				)
				(justify left bottom mirror)
			)
		)
		(property "Datasheet" "https://www.murata.com/products/productdetail?partno=GRM155R61H104KE14%23"
			(at 0 0 225)
			(layer "F.Fab")
			(hide yes)
			(effects
				(font
					(size 1.27 1.27)
					(thickness 0.15)
				)
			)
		)
		(property "Description" "SMD Multilayer Ceramic Capacitor, 0.1 µF, 50 V, 0402 [1005 Metric], ± 10%, X5R, GRM Series"
			(at 0 0 225)
			(layer "F.Fab")
			(hide yes)
			(effects
				(font
					(size 1.27 1.27)
					(thickness 0.15)
				)
			)
		)
		(property "Author" "Antmicro"
			(at 163.184813 186.993363 0)
			(layer "B.Fab")
			(hide yes)
			(effects
				(font
					(size 1 1)
					(thickness 0.15)
				)
				(justify mirror)
			)
		)
		(property "Dielectric" "X5R"
			(at 163.184813 186.993363 0)
			(layer "B.Fab")
			(hide yes)
			(effects
				(font
					(size 1 1)
					(thickness 0.15)
				)
				(justify mirror)
			)
		)
		(property "License" "Apache-2.0"
			(at 163.184813 186.993363 0)
			(layer "B.Fab")
			(hide yes)
			(effects
				(font
					(size 1 1)
					(thickness 0.15)
				)
				(justify mirror)
			)
		)
		(property "MPN" "GRM155R61H104KE14D"
			(at 163.184813 186.993363 0)
			(layer "B.Fab")
			(hide yes)
			(effects
				(font
					(size 1 1)
					(thickness 0.15)
				)
				(justify mirror)
			)
		)
		(property "Manufacturer" "Murata"
			(at 163.184813 186.993363 0)
			(layer "B.Fab")
			(hide yes)
			(effects
				(font
					(size 1 1)
					(thickness 0.15)
				)
				(justify mirror)
			)
		)
		(property "Val" "100n"
			(at 163.184813 186.993363 0)
			(layer "B.Fab")
			(hide yes)
			(effects
				(font
					(size 1 1)
					(thickness 0.15)
				)
				(justify mirror)
			)
		)
		(property "Voltage" "50V"
			(at 163.184813 186.993363 0)
			(layer "B.Fab")
			(hide yes)
			(effects
				(font
					(size 1 1)
					(thickness 0.15)
				)
				(justify mirror)
			)
		)
		(sheetname "/DDR3/")
		(sheetfile "ddr3.kicad_sch")
		(attr smd)
		(fp_poly
			(pts
				(xy -0.925 0.47) (xy 0.925 0.47) (xy 0.925 -0.47) (xy -0.925 -0.47)
			)
			(stroke
				(width 0.05)
				(type default)
			)
			(fill no)
			(layer "B.CrtYd")
		)
		(fp_line
			(start 0.504 0.25)
			(end 0.504 -0.248)
			(stroke
				(width 0.15)
				(type solid)
			)
			(layer "B.Fab")
		)
		(fp_line
			(start 0.504 -0.248)
			(end -0.494 -0.248)
			(stroke
				(width 0.15)
				(type solid)
			)
			(layer "B.Fab")
		)
		(fp_line
			(start -0.494 0.25)
			(end 0.504 0.25)
			(stroke
				(width 0.15)
				(type solid)
			)
			(layer "B.Fab")
		)
		(fp_line
			(start -0.494 -0.248)
			(end -0.494 0.25)
			(stroke
				(width 0.15)
				(type solid)
			)
			(layer "B.Fab")
		)
		(fp_text user "Author: Antmicro"
			(at -0.939 -3.399 45)
			(layer "B.Fab")
			(effects
				(font
					(size 0.7 0.7)
					(thickness 0.15)
				)
				(justify left bottom mirror)
			)
		)
		(fp_text user "${REFERENCE}"
			(at -0.939 -4.599 45)
			(layer "B.Fab")
			(effects
				(font
					(size 0.7 0.7)
					(thickness 0.15)
				)
				(justify left bottom mirror)
			)
		)
		(fp_text user "License: Apache-2.0"
			(at -0.939 -5.799 45)
			(layer "B.Fab")
			(effects
				(font
					(size 0.7 0.7)
					(thickness 0.15)
				)
				(justify left bottom mirror)
			)
		)
		(pad "1" smd roundrect
			(at -0.48 0 225)
			(size 0.59 0.64)
			(layers "B.Cu" "B.Mask" "B.Paste")
			(roundrect_rratio 0.25)
			(net 1 "GND")
			(pintype "passive")
		)
		(pad "2" smd roundrect
			(at 0.48 0 225)
			(size 0.59 0.64)
			(layers "B.Cu" "B.Mask" "B.Paste")
			(roundrect_rratio 0.25)
			(net 248 "+1V5")
			(pintype "passive")
		)
	)
	(footprint "antmicro-footprints:C_0402_1005Metric"
		(layer "B.Cu")
		(at 93.65 75.79 -90)
		(descr "Capacitor SMD 0402")
		(tags "capacitor SMD 0402")
		(property "Reference" "C63"
			(at -0.95 0.7 90)
			(layer "B.SilkS")
			(effects
				(font
					(size 0.65 0.65)
					(thickness 0.15)
				)
				(justify left bottom mirror)
			)
		)
		(property "Value" "C_100n_0402"
			(at 0 -1.4 90)
			(layer "B.Fab")
			(hide yes)
			(effects
				(font
					(size 0.7 0.7)
					(thickness 0.15)
				)
				(justify left bottom mirror)
			)
		)
		(property "Datasheet" "https://www.murata.com/products/productdetail?partno=GRM155R61H104KE14%23"
			(at 0 0 270)
			(layer "F.Fab")
			(hide yes)
			(effects
				(font
					(size 1.27 1.27)
					(thickness 0.15)
				)
			)
		)
		(property "Description" "SMD Multilayer Ceramic Capacitor, 0.1 µF, 50 V, 0402 [1005 Metric], ± 10%, X5R, GRM Series"
			(at 0 0 270)
			(layer "F.Fab")
			(hide yes)
			(effects
				(font
					(size 1.27 1.27)
					(thickness 0.15)
				)
			)
		)
		(property "Author" "Antmicro"
			(at 17.86 169.44 0)
			(layer "B.Fab")
			(hide yes)
			(effects
				(font
					(size 1 1)
					(thickness 0.15)
				)
				(justify mirror)
			)
		)
		(property "Dielectric" "X5R"
			(at 17.86 169.44 0)
			(layer "B.Fab")
			(hide yes)
			(effects
				(font
					(size 1 1)
					(thickness 0.15)
				)
				(justify mirror)
			)
		)
		(property "License" "Apache-2.0"
			(at 17.86 169.44 0)
			(layer "B.Fab")
			(hide yes)
			(effects
				(font
					(size 1 1)
					(thickness 0.15)
				)
				(justify mirror)
			)
		)
		(property "MPN" "GRM155R61H104KE14D"
			(at 17.86 169.44 0)
			(layer "B.Fab")
			(hide yes)
			(effects
				(font
					(size 1 1)
					(thickness 0.15)
				)
				(justify mirror)
			)
		)
		(property "Manufacturer" "Murata"
			(at 17.86 169.44 0)
			(layer "B.Fab")
			(hide yes)
			(effects
				(font
					(size 1 1)
					(thickness 0.15)
				)
				(justify mirror)
			)
		)
		(property "Val" "100n"
			(at 17.86 169.44 0)
			(layer "B.Fab")
			(hide yes)
			(effects
				(font
					(size 1 1)
					(thickness 0.15)
				)
				(justify mirror)
			)
		)
		(property "Voltage" "50V"
			(at 17.86 169.44 0)
			(layer "B.Fab")
			(hide yes)
			(effects
				(font
					(size 1 1)
					(thickness 0.15)
				)
				(justify mirror)
			)
		)
		(sheetname "/SDI/")
		(sheetfile "sdi.kicad_sch")
		(attr smd)
		(fp_rect
			(start -0.925 0.47)
			(end 0.925 -0.47)
			(stroke
				(width 0.05)
				(type default)
			)
			(fill no)
			(layer "B.CrtYd")
		)
		(fp_line
			(start -0.494 0.25)
			(end 0.504 0.25)
			(stroke
				(width 0.15)
				(type solid)
			)
			(layer "B.Fab")
		)
		(fp_line
			(start 0.504 0.25)
			(end 0.504 -0.248)
			(stroke
				(width 0.15)
				(type solid)
			)
			(layer "B.Fab")
		)
		(fp_line
			(start -0.494 -0.248)
			(end -0.494 0.25)
			(stroke
				(width 0.15)
				(type solid)
			)
			(layer "B.Fab")
		)
		(fp_line
			(start 0.504 -0.248)
			(end -0.494 -0.248)
			(stroke
				(width 0.15)
				(type solid)
			)
			(layer "B.Fab")
		)
		(fp_text user "Author: Antmicro"
			(at -0.939 -3.399 90)
			(layer "B.Fab")
			(effects
				(font
					(size 0.7 0.7)
					(thickness 0.15)
				)
				(justify left bottom mirror)
			)
		)
		(fp_text user "License: Apache-2.0"
			(at -0.939 -5.799 90)
			(layer "B.Fab")
			(effects
				(font
					(size 0.7 0.7)
					(thickness 0.15)
				)
				(justify left bottom mirror)
			)
		)
		(fp_text user "${REFERENCE}"
			(at -0.939 -4.599 90)
			(layer "B.Fab")
			(effects
				(font
					(size 0.7 0.7)
					(thickness 0.15)
				)
				(justify left bottom mirror)
			)
		)
		(pad "1" smd roundrect
			(at -0.48 0 270)
			(size 0.59 0.64)
			(layers "B.Cu" "B.Mask" "B.Paste")
			(roundrect_rratio 0.25)
			(net 1 "GND")
			(pintype "passive")
		)
		(pad "2" smd roundrect
			(at 0.48 0 270)
			(size 0.59 0.64)
			(layers "B.Cu" "B.Mask" "B.Paste")
			(roundrect_rratio 0.25)
			(net 3 "+1V2")
			(pintype "passive")
		)
	)
	(footprint "antmicro-footprints:C_0402_1005Metric"
		(layer "B.Cu")
		(at 120.45 66.13 90)
		(descr "Capacitor SMD 0402")
		(tags "capacitor SMD 0402")
		(property "Reference" "C46"
			(at -0.91 -0.72 90)
			(layer "B.SilkS")
			(effects
				(font
					(size 0.65 0.65)
					(thickness 0.15)
				)
				(justify right bottom mirror)
			)
		)
		(property "Value" "C_100n_0402"
			(at 0 -1.4 90)
			(layer "B.Fab")
			(hide yes)
			(effects
				(font
					(size 0.7 0.7)
					(thickness 0.15)
				)
				(justify right bottom mirror)
			)
		)
		(property "Datasheet" "https://www.murata.com/products/productdetail?partno=GRM155R61H104KE14%23"
			(at 0 0 90)
			(layer "F.Fab")
			(hide yes)
			(effects
				(font
					(size 1.27 1.27)
					(thickness 0.15)
				)
			)
		)
		(property "Description" "SMD Multilayer Ceramic Capacitor, 0.1 µF, 50 V, 0402 [1005 Metric], ± 10%, X5R, GRM Series"
			(at 0 0 90)
			(layer "F.Fab")
			(hide yes)
			(effects
				(font
					(size 1.27 1.27)
					(thickness 0.15)
				)
			)
		)
		(property "Author" "Antmicro"
			(at 186.58 -54.32 0)
			(layer "B.Fab")
			(hide yes)
			(effects
				(font
					(size 1 1)
					(thickness 0.15)
				)
				(justify mirror)
			)
		)
		(property "Dielectric" "X5R"
			(at 186.58 -54.32 0)
			(layer "B.Fab")
			(hide yes)
			(effects
				(font
					(size 1 1)
					(thickness 0.15)
				)
				(justify mirror)
			)
		)
		(property "License" "Apache-2.0"
			(at 186.58 -54.32 0)
			(layer "B.Fab")
			(hide yes)
			(effects
				(font
					(size 1 1)
					(thickness 0.15)
				)
				(justify mirror)
			)
		)
		(property "MPN" "GRM155R61H104KE14D"
			(at 186.58 -54.32 0)
			(layer "B.Fab")
			(hide yes)
			(effects
				(font
					(size 1 1)
					(thickness 0.15)
				)
				(justify mirror)
			)
		)
		(property "Manufacturer" "Murata"
			(at 186.58 -54.32 0)
			(layer "B.Fab")
			(hide yes)
			(effects
				(font
					(size 1 1)
					(thickness 0.15)
				)
				(justify mirror)
			)
		)
		(property "Val" "100n"
			(at 186.58 -54.32 0)
			(layer "B.Fab")
			(hide yes)
			(effects
				(font
					(size 1 1)
					(thickness 0.15)
				)
				(justify mirror)
			)
		)
		(property "Voltage" "50V"
			(at 186.58 -54.32 0)
			(layer "B.Fab")
			(hide yes)
			(effects
				(font
					(size 1 1)
					(thickness 0.15)
				)
				(justify mirror)
			)
		)
		(sheetname "/DDR3/")
		(sheetfile "ddr3.kicad_sch")
		(attr smd)
		(fp_rect
			(start -0.925 0.47)
			(end 0.925 -0.47)
			(stroke
				(width 0.05)
				(type default)
			)
			(fill no)
			(layer "B.CrtYd")
		)
		(fp_line
			(start 0.504 -0.248)
			(end -0.494 -0.248)
			(stroke
				(width 0.15)
				(type solid)
			)
			(layer "B.Fab")
		)
		(fp_line
			(start -0.494 -0.248)
			(end -0.494 0.25)
			(stroke
				(width 0.15)
				(type solid)
			)
			(layer "B.Fab")
		)
		(fp_line
			(start 0.504 0.25)
			(end 0.504 -0.248)
			(stroke
				(width 0.15)
				(type solid)
			)
			(layer "B.Fab")
		)
		(fp_line
			(start -0.494 0.25)
			(end 0.504 0.25)
			(stroke
				(width 0.15)
				(type solid)
			)
			(layer "B.Fab")
		)
		(fp_text user "License: Apache-2.0"
			(at -0.939 -5.799 270)
			(layer "B.Fab")
			(effects
				(font
					(size 0.7 0.7)
					(thickness 0.15)
				)
				(justify left bottom mirror)
			)
		)
		(fp_text user "Author: Antmicro"
			(at -0.939 -3.399 270)
			(layer "B.Fab")
			(effects
				(font
					(size 0.7 0.7)
					(thickness 0.15)
				)
				(justify left bottom mirror)
			)
		)
		(fp_text user "${REFERENCE}"
			(at -0.939 -4.599 270)
			(layer "B.Fab")
			(effects
				(font
					(size 0.7 0.7)
					(thickness 0.15)
				)
				(justify left bottom mirror)
			)
		)
		(pad "1" smd roundrect
			(at -0.48 0 90)
			(size 0.59 0.64)
			(layers "B.Cu" "B.Mask" "B.Paste")
			(roundrect_rratio 0.25)
			(net 1 "GND")
			(pintype "passive")
		)
		(pad "2" smd roundrect
			(at 0.48 0 90)
			(size 0.59 0.64)
			(layers "B.Cu" "B.Mask" "B.Paste")
			(roundrect_rratio 0.25)
			(net 248 "+1V5")
			(pintype "passive")
		)
	)
	(footprint "antmicro-footprints:C_0201"
		(layer "B.Cu")
		(at 125.9 94.3 180)
		(descr "Capacitor SMD 0201")
		(tags "capacitor SMD 0201")
		(property "Reference" "C107"
			(at 8.27 12.295736 0)
			(layer "B.SilkS")
			(effects
				(font
					(size 0.65 0.65)
					(thickness 0.15)
				)
				(justify left bottom mirror)
			)
		)
		(property "Value" "C_100n_0201"
			(at 0 -1.4 0)
			(layer "B.Fab")
			(hide yes)
			(effects
				(font
					(size 0.7 0.7)
					(thickness 0.15)
				)
				(justify left bottom mirror)
			)
		)
		(property "Datasheet" "https://www.yageo.com/en/Chart/Download/pdf/CC0201KRX6S5BB104"
			(at 0 0 180)
			(layer "F.Fab")
			(hide yes)
			(effects
				(font
					(size 1.27 1.27)
					(thickness 0.15)
				)
			)
		)
		(property "Description" "SMD Multilayer Ceramic Capacitor, 0.1 µF, 6.3 V, 0201 [0603 Metric], ± 10%, X6S, CC Series"
			(at 0 0 180)
			(layer "F.Fab")
			(hide yes)
			(effects
				(font
					(size 1.27 1.27)
					(thickness 0.15)
				)
			)
		)
		(property "Author" "Antmicro"
			(at 251.8 188.6 0)
			(layer "B.Fab")
			(hide yes)
			(effects
				(font
					(size 1 1)
					(thickness 0.15)
				)
				(justify mirror)
			)
		)
		(property "Dielectric" ""
			(at 251.8 188.6 0)
			(layer "B.Fab")
			(hide yes)
			(effects
				(font
					(size 1 1)
					(thickness 0.15)
				)
				(justify mirror)
			)
		)
		(property "License" "Apache-2.0"
			(at 251.8 188.6 0)
			(layer "B.Fab")
			(hide yes)
			(effects
				(font
					(size 1 1)
					(thickness 0.15)
				)
				(justify mirror)
			)
		)
		(property "MPN" "CC0201KRX6S5BB104"
			(at 251.8 188.6 0)
			(layer "B.Fab")
			(hide yes)
			(effects
				(font
					(size 1 1)
					(thickness 0.15)
				)
				(justify mirror)
			)
		)
		(property "Manufacturer" "YAGEO"
			(at 251.8 188.6 0)
			(layer "B.Fab")
			(hide yes)
			(effects
				(font
					(size 1 1)
					(thickness 0.15)
				)
				(justify mirror)
			)
		)
		(property "Val" "100n"
			(at 251.8 188.6 0)
			(layer "B.Fab")
			(hide yes)
			(effects
				(font
					(size 1 1)
					(thickness 0.15)
				)
				(justify mirror)
			)
		)
		(property "Voltage" ""
			(at 251.8 188.6 0)
			(layer "B.Fab")
			(hide yes)
			(effects
				(font
					(size 1 1)
					(thickness 0.15)
				)
				(justify mirror)
			)
		)
		(property "Public" "False"
			(at 0 0 180)
			(unlocked yes)
			(layer "B.Fab")
			(hide yes)
			(effects
				(font
					(size 1 1)
					(thickness 0.15)
				)
				(justify mirror)
			)
		)
		(sheetname "/FPGA Power/")
		(sheetfile "FPGA_Power.kicad_sch")
		(attr smd)
		(fp_rect
			(start -0.7 0.35)
			(end 0.7 -0.35)
			(stroke
				(width 0.05)
				(type default)
			)
			(fill no)
			(layer "B.CrtYd")
		)
		(fp_rect
			(start 0.3 -0.15)
			(end -0.301 0.149)
			(stroke
				(width 0.15)
				(type solid)
			)
			(fill no)
			(layer "B.Fab")
		)
		(fp_text user "Author: Antmicro"
			(at -0.72 -5.4 0)
			(layer "B.Fab")
			(effects
				(font
					(size 0.7 0.7)
					(thickness 0.15)
				)
				(justify left bottom mirror)
			)
		)
		(fp_text user "License: Apache-2.0"
			(at -0.72 -4.4 0)
			(layer "B.Fab")
			(effects
				(font
					(size 0.7 0.7)
					(thickness 0.15)
				)
				(justify left bottom mirror)
			)
		)
		(fp_text user "${REFERENCE}"
			(at -0.72 -3.4 0)
			(layer "B.Fab")
			(effects
				(font
					(size 0.7 0.7)
					(thickness 0.15)
				)
				(justify left bottom mirror)
			)
		)
		(pad "" smd roundrect
			(at -0.349 0.002 180)
			(size 0.318 0.36)
			(layers "B.Paste")
			(roundrect_rratio 0.25)
		)
		(pad "" smd roundrect
			(at 0.341 0.002 180)
			(size 0.318 0.36)
			(layers "B.Paste")
			(roundrect_rratio 0.25)
		)
		(pad "1" smd roundrect
			(at -0.321 0.002 180)
			(size 0.46 0.4)
			(layers "B.Cu" "B.Mask")
			(roundrect_rratio 0.25)
			(net 1 "GND")
			(pintype "passive")
		)
		(pad "2" smd roundrect
			(at 0.32 0.002 180)
			(size 0.46 0.4)
			(layers "B.Cu" "B.Mask")
			(roundrect_rratio 0.25)
			(net 4 "1V0_Power")
			(pintype "passive")
		)
	)
	(footprint "antmicro-footprints:R_0402_1005Metric"
		(layer "B.Cu")
		(at 104.89 91.8 -90)
		(descr "Resistor SMD 0402")
		(tags "resistor SMD 0402")
		(property "Reference" "R83"
			(at 1.04 0.66 90)
			(layer "B.SilkS")
			(effects
				(font
					(size 0.65 0.65)
					(thickness 0.15)
				)
				(justify left bottom mirror)
			)
		)
		(property "Value" "R_4k7_0402"
			(at 0 -1.4 90)
			(layer "B.Fab")
			(hide yes)
			(effects
				(font
					(size 0.7 0.7)
					(thickness 0.15)
				)
				(justify left bottom mirror)
			)
		)
		(property "Datasheet" "https://www.bourns.com/docs/product-datasheets/cr.pdf"
			(at 0 0 270)
			(layer "F.Fab")
			(hide yes)
			(effects
				(font
					(size 1.27 1.27)
					(thickness 0.15)
				)
			)
		)
		(property "Description" "SMD Chip Resistor, 4.7 kohm, ± 1%, 62.5 mW, 0402 [1005 Metric], Thick Film, General Purpose"
			(at 0 0 270)
			(layer "F.Fab")
			(hide yes)
			(effects
				(font
					(size 1.27 1.27)
					(thickness 0.15)
				)
			)
		)
		(property "Author" "Antmicro"
			(at 13.09 196.69 0)
			(layer "B.Fab")
			(hide yes)
			(effects
				(font
					(size 1 1)
					(thickness 0.15)
				)
				(justify mirror)
			)
		)
		(property "License" "Apache-2.0"
			(at 13.09 196.69 0)
			(layer "B.Fab")
			(hide yes)
			(effects
				(font
					(size 1 1)
					(thickness 0.15)
				)
				(justify mirror)
			)
		)
		(property "MPN" "CR0402-FX-4701GLF"
			(at 13.09 196.69 0)
			(layer "B.Fab")
			(hide yes)
			(effects
				(font
					(size 1 1)
					(thickness 0.15)
				)
				(justify mirror)
			)
		)
		(property "Manufacturer" "Bourns"
			(at 13.09 196.69 0)
			(layer "B.Fab")
			(hide yes)
			(effects
				(font
					(size 1 1)
					(thickness 0.15)
				)
				(justify mirror)
			)
		)
		(property "Tolerance" "1%"
			(at 13.09 196.69 0)
			(layer "B.Fab")
			(hide yes)
			(effects
				(font
					(size 1 1)
					(thickness 0.15)
				)
				(justify mirror)
			)
		)
		(property "Val" "4k7"
			(at 13.09 196.69 0)
			(layer "B.Fab")
			(hide yes)
			(effects
				(font
					(size 1 1)
					(thickness 0.15)
				)
				(justify mirror)
			)
		)
		(sheetname "/FPGA/")
		(sheetfile "fpga.kicad_sch")
		(attr smd)
		(fp_rect
			(start -0.925 0.47)
			(end 0.925 -0.47)
			(stroke
				(width 0.05)
				(type default)
			)
			(fill no)
			(layer "B.CrtYd")
		)
		(fp_rect
			(start -0.5 0.25)
			(end 0.5 -0.25)
			(stroke
				(width 0.15)
				(type solid)
			)
			(fill no)
			(layer "B.Fab")
		)
		(fp_text user "${REFERENCE}"
			(at -0.95 -3.168 90)
			(layer "B.Fab")
			(effects
				(font
					(size 0.7 0.7)
					(thickness 0.15)
				)
				(justify left bottom mirror)
			)
		)
		(fp_text user "License: Apache-2.0"
			(at -0.95 -5.169 90)
			(layer "B.Fab")
			(effects
				(font
					(size 0.7 0.7)
					(thickness 0.15)
				)
				(justify left bottom mirror)
			)
		)
		(fp_text user "Author: Antmicro"
			(at -0.95 -4.169 90)
			(layer "B.Fab")
			(effects
				(font
					(size 0.7 0.7)
					(thickness 0.15)
				)
				(justify left bottom mirror)
			)
		)
		(pad "1" smd roundrect
			(at -0.48 0 270)
			(size 0.59 0.64)
			(layers "B.Cu" "B.Mask" "B.Paste")
			(roundrect_rratio 0.25)
			(net 2 "+3V3")
			(pintype "passive")
		)
		(pad "2" smd roundrect
			(at 0.48 0 270)
			(size 0.59 0.64)
			(layers "B.Cu" "B.Mask" "B.Paste")
			(roundrect_rratio 0.25)
			(net 28 "/FPGA/SPI_DQ2")
			(pintype "passive")
		)
	)
	(footprint "antmicro-footprints:C_0402_1005Metric"
		(layer "B.Cu")
		(at 89.3 80.4)
		(descr "Capacitor SMD 0402")
		(tags "capacitor SMD 0402")
		(property "Reference" "C62"
			(at -0.97 1.34 0)
			(layer "B.SilkS")
			(effects
				(font
					(size 0.65 0.65)
					(thickness 0.15)
				)
				(justify right bottom mirror)
			)
		)
		(property "Value" "C_100n_0402"
			(at 0 -1.4 0)
			(layer "B.Fab")
			(hide yes)
			(effects
				(font
					(size 0.7 0.7)
					(thickness 0.15)
				)
				(justify right bottom mirror)
			)
		)
		(property "Datasheet" "https://www.murata.com/products/productdetail?partno=GRM155R61H104KE14%23"
			(at 0 0 0)
			(layer "F.Fab")
			(hide yes)
			(effects
				(font
					(size 1.27 1.27)
					(thickness 0.15)
				)
			)
		)
		(property "Description" "SMD Multilayer Ceramic Capacitor, 0.1 µF, 50 V, 0402 [1005 Metric], ± 10%, X5R, GRM Series"
			(at 0 0 0)
			(layer "F.Fab")
			(hide yes)
			(effects
				(font
					(size 1.27 1.27)
					(thickness 0.15)
				)
			)
		)
		(property "Author" "Antmicro"
			(at 0 0 0)
			(layer "B.Fab")
			(hide yes)
			(effects
				(font
					(size 1 1)
					(thickness 0.15)
				)
				(justify mirror)
			)
		)
		(property "Dielectric" "X5R"
			(at 0 0 0)
			(layer "B.Fab")
			(hide yes)
			(effects
				(font
					(size 1 1)
					(thickness 0.15)
				)
				(justify mirror)
			)
		)
		(property "License" "Apache-2.0"
			(at 0 0 0)
			(layer "B.Fab")
			(hide yes)
			(effects
				(font
					(size 1 1)
					(thickness 0.15)
				)
				(justify mirror)
			)
		)
		(property "MPN" "GRM155R61H104KE14D"
			(at 0 0 0)
			(layer "B.Fab")
			(hide yes)
			(effects
				(font
					(size 1 1)
					(thickness 0.15)
				)
				(justify mirror)
			)
		)
		(property "Manufacturer" "Murata"
			(at 0 0 0)
			(layer "B.Fab")
			(hide yes)
			(effects
				(font
					(size 1 1)
					(thickness 0.15)
				)
				(justify mirror)
			)
		)
		(property "Val" "100n"
			(at 0 0 0)
			(layer "B.Fab")
			(hide yes)
			(effects
				(font
					(size 1 1)
					(thickness 0.15)
				)
				(justify mirror)
			)
		)
		(property "Voltage" "50V"
			(at 0 0 0)
			(layer "B.Fab")
			(hide yes)
			(effects
				(font
					(size 1 1)
					(thickness 0.15)
				)
				(justify mirror)
			)
		)
		(sheetname "/SDI/")
		(sheetfile "sdi.kicad_sch")
		(attr smd)
		(fp_rect
			(start -0.925 0.47)
			(end 0.925 -0.47)
			(stroke
				(width 0.05)
				(type default)
			)
			(fill no)
			(layer "B.CrtYd")
		)
		(fp_line
			(start -0.494 -0.248)
			(end -0.494 0.25)
			(stroke
				(width 0.15)
				(type solid)
			)
			(layer "B.Fab")
		)
		(fp_line
			(start -0.494 0.25)
			(end 0.504 0.25)
			(stroke
				(width 0.15)
				(type solid)
			)
			(layer "B.Fab")
		)
		(fp_line
			(start 0.504 -0.248)
			(end -0.494 -0.248)
			(stroke
				(width 0.15)
				(type solid)
			)
			(layer "B.Fab")
		)
		(fp_line
			(start 0.504 0.25)
			(end 0.504 -0.248)
			(stroke
				(width 0.15)
				(type solid)
			)
			(layer "B.Fab")
		)
		(fp_text user "License: Apache-2.0"
			(at -0.939 -5.799 180)
			(layer "B.Fab")
			(effects
				(font
					(size 0.7 0.7)
					(thickness 0.15)
				)
				(justify left bottom mirror)
			)
		)
		(fp_text user "${REFERENCE}"
			(at -0.939 -4.599 180)
			(layer "B.Fab")
			(effects
				(font
					(size 0.7 0.7)
					(thickness 0.15)
				)
				(justify left bottom mirror)
			)
		)
		(fp_text user "Author: Antmicro"
			(at -0.939 -3.399 180)
			(layer "B.Fab")
			(effects
				(font
					(size 0.7 0.7)
					(thickness 0.15)
				)
				(justify left bottom mirror)
			)
		)
		(pad "1" smd roundrect
			(at -0.48 0)
			(size 0.59 0.64)
			(layers "B.Cu" "B.Mask" "B.Paste")
			(roundrect_rratio 0.25)
			(net 1 "GND")
			(pintype "passive")
		)
		(pad "2" smd roundrect
			(at 0.48 0)
			(size 0.59 0.64)
			(layers "B.Cu" "B.Mask" "B.Paste")
			(roundrect_rratio 0.25)
			(net 2 "+3V3")
			(pintype "passive")
		)
	)
	(footprint "antmicro-footprints:R_0402_1005Metric"
		(layer "B.Cu")
		(at 103.89 91.8 90)
		(descr "Resistor SMD 0402")
		(tags "resistor SMD 0402")
		(property "Reference" "R87"
			(at -1.04 1.34 270)
			(layer "B.SilkS")
			(effects
				(font
					(size 0.65 0.65)
					(thickness 0.15)
				)
				(justify left bottom mirror)
			)
		)
		(property "Value" "R_4k7_0402"
			(at 0 -1.4 270)
			(layer "B.Fab")
			(hide yes)
			(effects
				(font
					(size 0.7 0.7)
					(thickness 0.15)
				)
				(justify left bottom mirror)
			)
		)
		(property "Datasheet" "https://www.bourns.com/docs/product-datasheets/cr.pdf"
			(at 0 0 90)
			(layer "F.Fab")
			(hide yes)
			(effects
				(font
					(size 1.27 1.27)
					(thickness 0.15)
				)
			)
		)
		(property "Description" "SMD Chip Resistor, 4.7 kohm, ± 1%, 62.5 mW, 0402 [1005 Metric], Thick Film, General Purpose"
			(at 0 0 90)
			(layer "F.Fab")
			(hide yes)
			(effects
				(font
					(size 1.27 1.27)
					(thickness 0.15)
				)
			)
		)
		(property "Author" "Antmicro"
			(at 195.69 -12.09 0)
			(layer "B.Fab")
			(hide yes)
			(effects
				(font
					(size 1 1)
					(thickness 0.15)
				)
				(justify mirror)
			)
		)
		(property "License" "Apache-2.0"
			(at 195.69 -12.09 0)
			(layer "B.Fab")
			(hide yes)
			(effects
				(font
					(size 1 1)
					(thickness 0.15)
				)
				(justify mirror)
			)
		)
		(property "MPN" "CR0402-FX-4701GLF"
			(at 195.69 -12.09 0)
			(layer "B.Fab")
			(hide yes)
			(effects
				(font
					(size 1 1)
					(thickness 0.15)
				)
				(justify mirror)
			)
		)
		(property "Manufacturer" "Bourns"
			(at 195.69 -12.09 0)
			(layer "B.Fab")
			(hide yes)
			(effects
				(font
					(size 1 1)
					(thickness 0.15)
				)
				(justify mirror)
			)
		)
		(property "Tolerance" "1%"
			(at 195.69 -12.09 0)
			(layer "B.Fab")
			(hide yes)
			(effects
				(font
					(size 1 1)
					(thickness 0.15)
				)
				(justify mirror)
			)
		)
		(property "Val" "4k7"
			(at 195.69 -12.09 0)
			(layer "B.Fab")
			(hide yes)
			(effects
				(font
					(size 1 1)
					(thickness 0.15)
				)
				(justify mirror)
			)
		)
		(sheetname "/FPGA/")
		(sheetfile "fpga.kicad_sch")
		(attr smd)
		(fp_rect
			(start -0.925 0.47)
			(end 0.925 -0.47)
			(stroke
				(width 0.05)
				(type default)
			)
			(fill no)
			(layer "B.CrtYd")
		)
		(fp_rect
			(start -0.5 0.25)
			(end 0.5 -0.25)
			(stroke
				(width 0.15)
				(type solid)
			)
			(fill no)
			(layer "B.Fab")
		)
		(fp_text user "Author: Antmicro"
			(at -0.95 -4.169 270)
			(layer "B.Fab")
			(effects
				(font
					(size 0.7 0.7)
					(thickness 0.15)
				)
				(justify left bottom mirror)
			)
		)
		(fp_text user "${REFERENCE}"
			(at -0.95 -3.168 270)
			(layer "B.Fab")
			(effects
				(font
					(size 0.7 0.7)
					(thickness 0.15)
				)
				(justify left bottom mirror)
			)
		)
		(fp_text user "License: Apache-2.0"
			(at -0.95 -5.169 270)
			(layer "B.Fab")
			(effects
				(font
					(size 0.7 0.7)
					(thickness 0.15)
				)
				(justify left bottom mirror)
			)
		)
		(pad "1" smd roundrect
			(at -0.48 0 90)
			(size 0.59 0.64)
			(layers "B.Cu" "B.Mask" "B.Paste")
			(roundrect_rratio 0.25)
			(net 27 "/FPGA/SPI_DQ3")
			(pintype "passive")
		)
		(pad "2" smd roundrect
			(at 0.48 0 90)
			(size 0.59 0.64)
			(layers "B.Cu" "B.Mask" "B.Paste")
			(roundrect_rratio 0.25)
			(net 2 "+3V3")
			(pintype "passive")
		)
	)
	(footprint "antmicro-footprints:R_Array_4x0402"
		(layer "B.Cu")
		(at 124.36 57.44 180)
		(property "Reference" "R49"
			(at -0.97 1 0)
			(layer "B.SilkS")
			(effects
				(font
					(size 0.65 0.65)
					(thickness 0.15)
				)
				(justify left bottom mirror)
			)
		)
		(property "Value" "R_4x51R_0402_array"
			(at -1.5 -2 0)
			(layer "B.Fab")
			(hide yes)
			(effects
				(font
					(size 0.7 0.7)
					(thickness 0.15)
				)
				(justify left bottom mirror)
			)
		)
		(property "Datasheet" "http://industrial.panasonic.com/cdbs/www-data/pdf/AOC0000/AOC0000C14.pdf"
			(at 0 0 180)
			(layer "F.Fab")
			(hide yes)
			(effects
				(font
					(size 1.27 1.27)
					(thickness 0.15)
				)
			)
		)
		(property "Description" "Fixed Network Resistor, 51 ohm, Isolated, 4 Resistors, 0804 [2010 Metric], Convex, ± 5%"
			(at 0 0 180)
			(layer "F.Fab")
			(hide yes)
			(effects
				(font
					(size 1.27 1.27)
					(thickness 0.15)
				)
			)
		)
		(property "Author" "Antmicro"
			(at 248.72 114.88 0)
			(layer "B.Fab")
			(hide yes)
			(effects
				(font
					(size 1 1)
					(thickness 0.15)
				)
				(justify mirror)
			)
		)
		(property "License" "Apache-2.0"
			(at 248.72 114.88 0)
			(layer "B.Fab")
			(hide yes)
			(effects
				(font
					(size 1 1)
					(thickness 0.15)
				)
				(justify mirror)
			)
		)
		(property "MPN" "EXB28V510JX"
			(at 248.72 114.88 0)
			(layer "B.Fab")
			(hide yes)
			(effects
				(font
					(size 1 1)
					(thickness 0.15)
				)
				(justify mirror)
			)
		)
		(property "Manufacturer" "Panasonic"
			(at 248.72 114.88 0)
			(layer "B.Fab")
			(hide yes)
			(effects
				(font
					(size 1 1)
					(thickness 0.15)
				)
				(justify mirror)
			)
		)
		(property "Val" "R_4x51R_0402"
			(at 248.72 114.88 0)
			(layer "B.Fab")
			(hide yes)
			(effects
				(font
					(size 1 1)
					(thickness 0.15)
				)
				(justify mirror)
			)
		)
		(sheetname "/DDR3/")
		(sheetfile "ddr3.kicad_sch")
		(attr smd)
		(fp_line
			(start 1.167 -0.498)
			(end 1.167 0.5)
			(stroke
				(width 0.15)
				(type solid)
			)
			(layer "B.SilkS")
		)
		(fp_line
			(start -1.17 0.5)
			(end -1.17 -0.498)
			(stroke
				(width 0.15)
				(type solid)
			)
			(layer "B.SilkS")
		)
		(fp_rect
			(start -1.2 0.9)
			(end 1.2 -0.9)
			(stroke
				(width 0.05)
				(type solid)
			)
			(fill no)
			(layer "B.CrtYd")
		)
		(fp_line
			(start 0.998 0.5)
			(end 0.998 -0.498)
			(stroke
				(width 0.15)
				(type solid)
			)
			(layer "B.Fab")
		)
		(fp_line
			(start 0.998 -0.498)
			(end -1 -0.498)
			(stroke
				(width 0.15)
				(type solid)
			)
			(layer "B.Fab")
		)
		(fp_line
			(start -1 0.5)
			(end 0.998 0.5)
			(stroke
				(width 0.15)
				(type solid)
			)
			(layer "B.Fab")
		)
		(fp_line
			(start -1 -0.498)
			(end -1 0.5)
			(stroke
				(width 0.15)
				(type solid)
			)
			(layer "B.Fab")
		)
		(pad "1" smd roundrect
			(at -0.802 -0.45 180)
			(size 0.4 0.5)
			(layers "B.Cu" "B.Mask" "B.Paste")
			(roundrect_rratio 0.25)
			(net 158 "/DDR3/DDR3_A13")
			(pinfunction "R1.1")
			(pintype "passive")
		)
		(pad "2" smd roundrect
			(at -0.272 -0.45 180)
			(size 0.4 0.5)
			(layers "B.Cu" "B.Mask" "B.Paste")
			(roundrect_rratio 0.25)
			(net 144 "/DDR3/DDR3_A2")
			(pinfunction "R2.1")
			(pintype "passive")
		)
		(pad "3" smd roundrect
			(at 0.27 -0.45 180)
			(size 0.4 0.5)
			(layers "B.Cu" "B.Mask" "B.Paste")
			(roundrect_rratio 0.25)
			(net 146 "/DDR3/DDR3_A3")
			(pinfunction "R3.1")
			(pintype "passive")
		)
		(pad "4" smd roundrect
			(at 0.8 -0.45 180)
			(size 0.4 0.5)
			(layers "B.Cu" "B.Mask" "B.Paste")
			(roundrect_rratio 0.25)
			(net 147 "/DDR3/DDR3_A0")
			(pinfunction "R4.1")
			(pintype "passive")
		)
		(pad "5" smd roundrect
			(at 0.8 0.452 180)
			(size 0.4 0.5)
			(layers "B.Cu" "B.Mask" "B.Paste")
			(roundrect_rratio 0.25)
			(net 6 "Vtt")
			(pinfunction "R4.2")
			(pintype "passive")
		)
		(pad "6" smd roundrect
			(at 0.27 0.452 180)
			(size 0.4 0.5)
			(layers "B.Cu" "B.Mask" "B.Paste")
			(roundrect_rratio 0.25)
			(net 6 "Vtt")
			(pinfunction "R3.2")
			(pintype "passive")
		)
		(pad "7" smd roundrect
			(at -0.272 0.452 180)
			(size 0.4 0.5)
			(layers "B.Cu" "B.Mask" "B.Paste")
			(roundrect_rratio 0.25)
			(net 6 "Vtt")
			(pinfunction "R2.2")
			(pintype "passive")
		)
		(pad "8" smd roundrect
			(at -0.802 0.452 180)
			(size 0.4 0.5)
			(layers "B.Cu" "B.Mask" "B.Paste")
			(roundrect_rratio 0.25)
			(net 6 "Vtt")
			(pinfunction "R1.2")
			(pintype "passive")
		)
	)
	(footprint "antmicro-footprints:FB_0603_1608Metric"
		(layer "B.Cu")
		(at 135.13 98.04)
		(property "Reference" "FB5"
			(at 3.4 0.35 180)
			(layer "B.SilkS")
			(effects
				(font
					(size 0.65 0.65)
					(thickness 0.15)
				)
				(justify left bottom mirror)
			)
		)
		(property "Value" "FB_120Z_2A_0603"
			(at 0 -1.5 180)
			(layer "B.Fab")
			(hide yes)
			(effects
				(font
					(size 0.7 0.7)
					(thickness 0.15)
				)
				(justify left bottom mirror)
			)
		)
		(property "Datasheet" "https://www.murata.com/en-us/products/productdata/8796738650142/ENFA0003.pdf"
			(at 0 0 0)
			(layer "F.Fab")
			(hide yes)
			(effects
				(font
					(size 1.27 1.27)
					(thickness 0.15)
				)
			)
		)
		(property "Description" "Ferrite Bead, 0603 [1608 Metric], 120 ohm, 2 A, BLM18P, 0.05 ohm, ± 25%, DC power line"
			(at 0 0 0)
			(layer "F.Fab")
			(hide yes)
			(effects
				(font
					(size 1.27 1.27)
					(thickness 0.15)
				)
			)
		)
		(property "Author" "Antmicro"
			(at 0 0 0)
			(layer "B.Fab")
			(hide yes)
			(effects
				(font
					(size 1 1)
					(thickness 0.15)
				)
				(justify mirror)
			)
		)
		(property "License" "Apache-2.0"
			(at 0 0 0)
			(layer "B.Fab")
			(hide yes)
			(effects
				(font
					(size 1 1)
					(thickness 0.15)
				)
				(justify mirror)
			)
		)
		(property "MPN" "BLM18PG121SN1D"
			(at 0 0 0)
			(layer "B.Fab")
			(hide yes)
			(effects
				(font
					(size 1 1)
					(thickness 0.15)
				)
				(justify mirror)
			)
		)
		(property "Manufacturer" "Murata"
			(at 0 0 0)
			(layer "B.Fab")
			(hide yes)
			(effects
				(font
					(size 1 1)
					(thickness 0.15)
				)
				(justify mirror)
			)
		)
		(property "Val" "120Z/2A"
			(at 0 0 0)
			(unlocked yes)
			(layer "B.Fab")
			(hide yes)
			(effects
				(font
					(size 1 1)
					(thickness 0.15)
				)
				(justify mirror)
			)
		)
		(property "Current" ""
			(at 0 0 0)
			(unlocked yes)
			(layer "B.Fab")
			(hide yes)
			(effects
				(font
					(size 1 1)
					(thickness 0.15)
				)
				(justify mirror)
			)
		)
		(sheetname "/FPGA Power/")
		(sheetfile "FPGA_Power.kicad_sch")
		(attr smd)
		(fp_line
			(start -0.15 -0.4)
			(end 0.15 -0.4)
			(stroke
				(width 0.15)
				(type solid)
			)
			(layer "B.SilkS")
		)
		(fp_line
			(start -0.15 0.4)
			(end 0.15 0.4)
			(stroke
				(width 0.15)
				(type solid)
			)
			(layer "B.SilkS")
		)
		(fp_rect
			(start -1.25 0.65)
			(end 1.25 -0.65)
			(stroke
				(width 0.05)
				(type solid)
			)
			(fill no)
			(layer "B.CrtYd")
		)
		(fp_line
			(start -0.803 -0.406)
			(end -0.803 0.408)
			(stroke
				(width 0.15)
				(type solid)
			)
			(layer "B.Fab")
		)
		(fp_line
			(start 0.8 -0.406)
			(end -0.803 -0.406)
			(stroke
				(width 0.15)
				(type solid)
			)
			(layer "B.Fab")
		)
		(fp_line
			(start 0.8 0.408)
			(end -0.803 0.408)
			(stroke
				(width 0.15)
				(type solid)
			)
			(layer "B.Fab")
		)
		(fp_line
			(start 0.8 0.408)
			(end 0.8 -0.406)
			(stroke
				(width 0.15)
				(type solid)
			)
			(layer "B.Fab")
		)
		(fp_text user "${REFERENCE}"
			(at -1.653 -4.6 180)
			(layer "B.Fab")
			(effects
				(font
					(size 0.7 0.7)
					(thickness 0.15)
				)
				(justify left bottom mirror)
			)
		)
		(fp_text user "Author: Antmicro"
			(at -1.653 -3.162 180)
			(layer "B.Fab")
			(effects
				(font
					(size 0.7 0.7)
					(thickness 0.15)
				)
				(justify left bottom mirror)
			)
		)
		(fp_text user "License: Apache-2.0"
			(at -1.653 -5.9 180)
			(layer "B.Fab")
			(effects
				(font
					(size 0.7 0.7)
					(thickness 0.15)
				)
				(justify left bottom mirror)
			)
		)
		(pad "1" smd roundrect
			(at -0.7 0)
			(size 0.8 1)
			(layers "B.Cu" "B.Mask" "B.Paste")
			(roundrect_rratio 0.2)
			(net 13 "/FPGA Power/VCC_PLLDPHY")
			(pintype "passive")
		)
		(pad "2" smd roundrect
			(at 0.7 0)
			(size 0.8 1)
			(layers "B.Cu" "B.Mask" "B.Paste")
			(roundrect_rratio 0.2)
			(net 49 "1V0_Clean")
			(pintype "passive")
		)
	)
	(footprint "antmicro-footprints:R_0402_1005Metric"
		(layer "B.Cu")
		(at 156.23 65.35 90)
		(descr "Resistor SMD 0402")
		(tags "resistor SMD 0402")
		(property "Reference" "R64"
			(at 2.91 0.4 270)
			(layer "B.SilkS")
			(effects
				(font
					(size 0.65 0.65)
					(thickness 0.15)
				)
				(justify left bottom mirror)
			)
		)
		(property "Value" "R_10k_0402"
			(at 0 -1.4 270)
			(layer "B.Fab")
			(hide yes)
			(effects
				(font
					(size 0.7 0.7)
					(thickness 0.15)
				)
				(justify left bottom mirror)
			)
		)
		(property "Datasheet" "https://www.bourns.com/docs/product-datasheets/cr.pdf"
			(at 0 0 90)
			(layer "F.Fab")
			(hide yes)
			(effects
				(font
					(size 1.27 1.27)
					(thickness 0.15)
				)
			)
		)
		(property "Description" "SMD Chip Resistor, 10 kohm, ± 1%, 62.5 mW, 0402 [1005 Metric], Thick Film, General Purpose"
			(at 0 0 90)
			(layer "F.Fab")
			(hide yes)
			(effects
				(font
					(size 1.27 1.27)
					(thickness 0.15)
				)
			)
		)
		(property "Author" "Antmicro"
			(at 221.58 -90.88 0)
			(layer "B.Fab")
			(hide yes)
			(effects
				(font
					(size 1 1)
					(thickness 0.15)
				)
				(justify mirror)
			)
		)
		(property "License" "Apache-2.0"
			(at 221.58 -90.88 0)
			(layer "B.Fab")
			(hide yes)
			(effects
				(font
					(size 1 1)
					(thickness 0.15)
				)
				(justify mirror)
			)
		)
		(property "MPN" "CR0402-FX-1002GLF"
			(at 221.58 -90.88 0)
			(layer "B.Fab")
			(hide yes)
			(effects
				(font
					(size 1 1)
					(thickness 0.15)
				)
				(justify mirror)
			)
		)
		(property "Manufacturer" "Bourns"
			(at 221.58 -90.88 0)
			(layer "B.Fab")
			(hide yes)
			(effects
				(font
					(size 1 1)
					(thickness 0.15)
				)
				(justify mirror)
			)
		)
		(property "Tolerance" "1%"
			(at 221.58 -90.88 0)
			(layer "B.Fab")
			(hide yes)
			(effects
				(font
					(size 1 1)
					(thickness 0.15)
				)
				(justify mirror)
			)
		)
		(property "Val" "10k"
			(at 221.58 -90.88 0)
			(layer "B.Fab")
			(hide yes)
			(effects
				(font
					(size 1 1)
					(thickness 0.15)
				)
				(justify mirror)
			)
		)
		(sheetname "/Power Supply/")
		(sheetfile "supply.kicad_sch")
		(attr smd)
		(fp_rect
			(start -0.925 0.47)
			(end 0.925 -0.47)
			(stroke
				(width 0.05)
				(type default)
			)
			(fill no)
			(layer "B.CrtYd")
		)
		(fp_rect
			(start -0.5 0.25)
			(end 0.5 -0.25)
			(stroke
				(width 0.15)
				(type solid)
			)
			(fill no)
			(layer "B.Fab")
		)
		(fp_text user "${REFERENCE}"
			(at -0.95 -3.168 270)
			(layer "B.Fab")
			(effects
				(font
					(size 0.7 0.7)
					(thickness 0.15)
				)
				(justify left bottom mirror)
			)
		)
		(fp_text user "Author: Antmicro"
			(at -0.95 -4.169 270)
			(layer "B.Fab")
			(effects
				(font
					(size 0.7 0.7)
					(thickness 0.15)
				)
				(justify left bottom mirror)
			)
		)
		(fp_text user "License: Apache-2.0"
			(at -0.95 -5.169 270)
			(layer "B.Fab")
			(effects
				(font
					(size 0.7 0.7)
					(thickness 0.15)
				)
				(justify left bottom mirror)
			)
		)
		(pad "1" smd roundrect
			(at -0.48 0 90)
			(size 0.59 0.64)
			(layers "B.Cu" "B.Mask" "B.Paste")
			(roundrect_rratio 0.25)
			(net 1 "GND")
			(pintype "passive")
		)
		(pad "2" smd roundrect
			(at 0.48 0 90)
			(size 0.59 0.64)
			(layers "B.Cu" "B.Mask" "B.Paste")
			(roundrect_rratio 0.25)
			(net 382 "Net-(Q2-Pad2)")
			(pintype "passive")
		)
	)
	(footprint "antmicro-footprints:C_0603_1608Metric"
		(layer "B.Cu")
		(at 127.82 82.21)
		(descr "Capacitor SMD 0603")
		(tags "capacitor 0603")
		(property "Reference" "C87"
			(at -3.29 0.43 0)
			(layer "B.SilkS")
			(effects
				(font
					(size 0.65 0.65)
					(thickness 0.15)
				)
				(justify right bottom mirror)
			)
		)
		(property "Value" "C_10u_0603"
			(at 0 -1.6 0)
			(layer "B.Fab")
			(hide yes)
			(effects
				(font
					(size 0.7 0.7)
					(thickness 0.15)
				)
				(justify right bottom mirror)
			)
		)
		(property "Datasheet" "https://www.murata.com/products/productdetail?partno=GRM188R61A106KE69%23"
			(at 0 0 0)
			(layer "F.Fab")
			(hide yes)
			(effects
				(font
					(size 1.27 1.27)
					(thickness 0.15)
				)
			)
		)
		(property "Description" "SMD Multilayer Ceramic Capacitor, 10 µF, 10 V, 0603 [1608 Metric], ± 10%, X5R, GRM Series"
			(at 0 0 0)
			(layer "F.Fab")
			(hide yes)
			(effects
				(font
					(size 1.27 1.27)
					(thickness 0.15)
				)
			)
		)
		(property "Author" "Antmicro"
			(at 0 0 0)
			(layer "B.Fab")
			(hide yes)
			(effects
				(font
					(size 1 1)
					(thickness 0.15)
				)
				(justify mirror)
			)
		)
		(property "License" "Apache-2.0"
			(at 0 0 0)
			(layer "B.Fab")
			(hide yes)
			(effects
				(font
					(size 1 1)
					(thickness 0.15)
				)
				(justify mirror)
			)
		)
		(property "MPN" "GRM188R61A106KE69D"
			(at 0 0 0)
			(layer "B.Fab")
			(hide yes)
			(effects
				(font
					(size 1 1)
					(thickness 0.15)
				)
				(justify mirror)
			)
		)
		(property "Manufacturer" "Murata"
			(at 0 0 0)
			(layer "B.Fab")
			(hide yes)
			(effects
				(font
					(size 1 1)
					(thickness 0.15)
				)
				(justify mirror)
			)
		)
		(property "Val" "10u"
			(at 0 0 0)
			(layer "B.Fab")
			(hide yes)
			(effects
				(font
					(size 1 1)
					(thickness 0.15)
				)
				(justify mirror)
			)
		)
		(property "Voltage" ""
			(at 0 0 0)
			(layer "B.Fab")
			(hide yes)
			(effects
				(font
					(size 1 1)
					(thickness 0.15)
				)
				(justify mirror)
			)
		)
		(property "Dielectric" "template_dielectric"
			(at 0 0 0)
			(unlocked yes)
			(layer "B.Fab")
			(hide yes)
			(effects
				(font
					(size 1 1)
					(thickness 0.15)
				)
				(justify mirror)
			)
		)
		(sheetname "/FPGA Power/")
		(sheetfile "FPGA_Power.kicad_sch")
		(attr smd)
		(fp_line
			(start -0.15 -0.4)
			(end 0.15 -0.4)
			(stroke
				(width 0.15)
				(type solid)
			)
			(layer "B.SilkS")
		)
		(fp_line
			(start -0.15 0.4)
			(end 0.15 0.4)
			(stroke
				(width 0.15)
				(type solid)
			)
			(layer "B.SilkS")
		)
		(fp_rect
			(start -1.25 0.65)
			(end 1.25 -0.65)
			(stroke
				(width 0.05)
				(type solid)
			)
			(fill no)
			(layer "B.CrtYd")
		)
		(fp_rect
			(start -0.8 0.4)
			(end 0.8 -0.4)
			(stroke
				(width 0.15)
				(type solid)
			)
			(fill no)
			(layer "B.Fab")
		)
		(fp_text user "${REFERENCE}"
			(at -1.682 -3.895 180)
			(layer "B.Fab")
			(effects
				(font
					(size 0.7 0.7)
					(thickness 0.15)
				)
				(justify left bottom mirror)
			)
		)
		(fp_text user "Author: Antmicro"
			(at -1.682 -4.894 180)
			(layer "B.Fab")
			(effects
				(font
					(size 0.7 0.7)
					(thickness 0.15)
				)
				(justify left bottom mirror)
			)
		)
		(fp_text user "License: Apache-2.0"
			(at -1.682 -5.895 180)
			(layer "B.Fab")
			(effects
				(font
					(size 0.7 0.7)
					(thickness 0.15)
				)
				(justify left bottom mirror)
			)
		)
		(pad "1" smd roundrect
			(at -0.7 0)
			(size 0.8 1)
			(layers "B.Cu" "B.Mask" "B.Paste")
			(roundrect_rratio 0.2)
			(net 1 "GND")
			(pintype "passive")
		)
		(pad "2" smd roundrect
			(at 0.7 0)
			(size 0.8 1)
			(layers "B.Cu" "B.Mask" "B.Paste")
			(roundrect_rratio 0.2)
			(net 9 "/FPGA Power/VCC_AUX")
			(pintype "passive")
		)
	)
	(footprint "antmicro-footprints:SOT-23-3"
		(layer "B.Cu")
		(at 158.63 68.35 -90)
		(property "Reference" "Q1"
			(at -1.01 -2.9 180)
			(layer "B.SilkS")
			(effects
				(font
					(size 0.65 0.65)
					(thickness 0.15)
				)
				(justify left bottom mirror)
			)
		)
		(property "Value" "2N7002_SOT-23-3"
			(at -1.9 -2.7 90)
			(layer "B.Fab")
			(hide yes)
			(effects
				(font
					(size 0.7 0.7)
					(thickness 0.15)
				)
				(justify left bottom mirror)
			)
		)
		(property "Datasheet" "https://www.onsemi.com/pub/Collateral/NDS7002A-D.PDF"
			(at 0 0 270)
			(layer "F.Fab")
			(hide yes)
			(effects
				(font
					(size 1.27 1.27)
					(thickness 0.15)
				)
			)
		)
		(property "Description" "Power MOSFET, N Channel, 60 V, 115 mA, 1.2 ohm, SOT-23, Surface Mount"
			(at 0 0 270)
			(layer "F.Fab")
			(hide yes)
			(effects
				(font
					(size 1.27 1.27)
					(thickness 0.15)
				)
			)
		)
		(property "Author" "Antmicro"
			(at 90.28 226.98 0)
			(layer "B.Fab")
			(hide yes)
			(effects
				(font
					(size 1 1)
					(thickness 0.15)
				)
				(justify mirror)
			)
		)
		(property "License" "Apache-2.0"
			(at 90.28 226.98 0)
			(layer "B.Fab")
			(hide yes)
			(effects
				(font
					(size 1 1)
					(thickness 0.15)
				)
				(justify mirror)
			)
		)
		(property "MPN" "2N7002"
			(at 90.28 226.98 0)
			(layer "B.Fab")
			(hide yes)
			(effects
				(font
					(size 1 1)
					(thickness 0.15)
				)
				(justify mirror)
			)
		)
		(property "Manufacturer" "ON Semiconductor"
			(at 90.28 226.98 0)
			(layer "B.Fab")
			(hide yes)
			(effects
				(font
					(size 1 1)
					(thickness 0.15)
				)
				(justify mirror)
			)
		)
		(sheetname "/Power Supply/")
		(sheetfile "supply.kicad_sch")
		(attr smd)
		(fp_line
			(start 0.7 1.5)
			(end -0.7 1.5)
			(stroke
				(width 0.15)
				(type solid)
			)
			(layer "B.SilkS")
		)
		(fp_line
			(start -1.45 1.35)
			(end -0.85 1.35)
			(stroke
				(width 0.15)
				(type solid)
			)
			(layer "B.SilkS")
		)
		(fp_line
			(start -0.85 1.35)
			(end -0.7 1.5)
			(stroke
				(width 0.15)
				(type solid)
			)
			(layer "B.SilkS")
		)
		(fp_line
			(start 0.7 0.4)
			(end 0.7 1.5)
			(stroke
				(width 0.15)
				(type solid)
			)
			(layer "B.SilkS")
		)
		(fp_line
			(start 0.7 -0.4)
			(end 0.7 -1.5)
			(stroke
				(width 0.15)
				(type solid)
			)
			(layer "B.SilkS")
		)
		(fp_line
			(start -0.7 -1.5)
			(end -0.7 -1.35)
			(stroke
				(width 0.15)
				(type solid)
			)
			(layer "B.SilkS")
		)
		(fp_line
			(start 0.7 -1.5)
			(end -0.7 -1.5)
			(stroke
				(width 0.15)
				(type solid)
			)
			(layer "B.SilkS")
		)
		(fp_line
			(start -0.9 1.6)
			(end 0.825 1.6)
			(stroke
				(width 0.05)
				(type solid)
			)
			(layer "B.CrtYd")
		)
		(fp_line
			(start -0.9 1.6)
			(end -0.9 1.4)
			(stroke
				(width 0.05)
				(type solid)
			)
			(layer "B.CrtYd")
		)
		(fp_line
			(start 0.825 1.6)
			(end 0.825 0.45)
			(stroke
				(width 0.05)
				(type solid)
			)
			(layer "B.CrtYd")
		)
		(fp_line
			(start -0.9 1.4)
			(end -1.75 1.4)
			(stroke
				(width 0.05)
				(type solid)
			)
			(layer "B.CrtYd")
		)
		(fp_line
			(start -1.75 0.5)
			(end -1.75 1.4)
			(stroke
				(width 0.05)
				(type solid)
			)
			(layer "B.CrtYd")
		)
		(fp_line
			(start -0.85 0.5)
			(end -1.75 0.5)
			(stroke
				(width 0.05)
				(type solid)
			)
			(layer "B.CrtYd")
		)
		(fp_line
			(start 0.825 0.45)
			(end 1.75 0.45)
			(stroke
				(width 0.05)
				(type solid)
			)
			(layer "B.CrtYd")
		)
		(fp_line
			(start 1.75 0.45)
			(end 1.75 -0.45)
			(stroke
				(width 0.05)
				(type solid)
			)
			(layer "B.CrtYd")
		)
		(fp_line
			(start 0.85 -0.45)
			(end 0.85 -1.65)
			(stroke
				(width 0.05)
				(type solid)
			)
			(layer "B.CrtYd")
		)
		(fp_line
			(start 1.75 -0.45)
			(end 0.85 -0.45)
			(stroke
				(width 0.05)
				(type solid)
			)
			(layer "B.CrtYd")
		)
		(fp_line
			(start -1.75 -0.5)
			(end -0.85 -0.5)
			(stroke
				(width 0.05)
				(type solid)
			)
			(layer "B.CrtYd")
		)
		(fp_line
			(start -0.85 -0.5)
			(end -0.85 0.5)
			(stroke
				(width 0.05)
				(type solid)
			)
			(layer "B.CrtYd")
		)
		(fp_line
			(start -1.75 -1.4)
			(end -1.75 -0.5)
			(stroke
				(width 0.05)
				(type solid)
			)
			(layer "B.CrtYd")
		)
		(fp_line
			(start -0.85 -1.4)
			(end -1.75 -1.4)
			(stroke
				(width 0.05)
				(type solid)
			)
			(layer "B.CrtYd")
		)
		(fp_line
			(start -0.85 -1.65)
			(end -0.85 -1.4)
			(stroke
				(width 0.05)
				(type solid)
			)
			(layer "B.CrtYd")
		)
		(fp_line
			(start 0.85 -1.65)
			(end -0.85 -1.65)
			(stroke
				(width 0.05)
				(type solid)
			)
			(layer "B.CrtYd")
		)
		(fp_line
			(start -0.437 1.526)
			(end 0.688 1.526)
			(stroke
				(width 0.15)
				(type solid)
			)
			(layer "B.Fab")
		)
		(fp_line
			(start -0.437 1.526)
			(end -0.712 1.325)
			(stroke
				(width 0.15)
				(type solid)
			)
			(layer "B.Fab")
		)
		(fp_line
			(start -0.712 1.325)
			(end -0.712 -1.523)
			(stroke
				(width 0.15)
				(type solid)
			)
			(layer "B.Fab")
		)
		(fp_line
			(start -0.712 -1.519)
			(end 0.688 -1.519)
			(stroke
				(width 0.15)
				(type solid)
			)
			(layer "B.Fab")
		)
		(fp_line
			(start 0.688 -1.519)
			(end 0.688 1.52)
			(stroke
				(width 0.15)
				(type solid)
			)
			(layer "B.Fab")
		)
		(pad "1" smd roundrect
			(at -1.1 0.951 270)
			(size 1 0.6)
			(layers "B.Cu" "B.Mask" "B.Paste")
			(roundrect_rratio 0.15)
			(net 325 "USB_POWER_IN")
			(pinfunction "G")
			(pintype "input")
		)
		(pad "2" smd roundrect
			(at -1.1 -0.949 270)
			(size 1 0.6)
			(layers "B.Cu" "B.Mask" "B.Paste")
			(roundrect_rratio 0.15)
			(net 1 "GND")
			(pinfunction "S")
			(pintype "passive")
		)
		(pad "3" smd roundrect
			(at 1.1 0.0005 270)
			(size 1 0.6)
			(layers "B.Cu" "B.Mask" "B.Paste")
			(roundrect_rratio 0.15)
			(net 259 "Net-(Q1-D)")
			(pinfunction "D")
			(pintype "passive")
		)
	)
	(footprint "antmicro-footprints:C_0201"
		(layer "B.Cu")
		(at 123.65 85.85 -90)
		(descr "Capacitor SMD 0201")
		(tags "capacitor SMD 0201")
		(property "Reference" "C38"
			(at -13.71 9.17 90)
			(layer "B.SilkS")
			(effects
				(font
					(size 0.65 0.65)
					(thickness 0.15)
				)
				(justify left bottom mirror)
			)
		)
		(property "Value" "C_100n_0201"
			(at 0 -1.4 90)
			(layer "B.Fab")
			(hide yes)
			(effects
				(font
					(size 0.7 0.7)
					(thickness 0.15)
				)
				(justify left bottom mirror)
			)
		)
		(property "Datasheet" "https://www.yageo.com/en/Chart/Download/pdf/CC0201KRX6S5BB104"
			(at 0 0 270)
			(layer "F.Fab")
			(hide yes)
			(effects
				(font
					(size 1.27 1.27)
					(thickness 0.15)
				)
			)
		)
		(property "Description" "SMD Multilayer Ceramic Capacitor, 0.1 µF, 6.3 V, 0201 [0603 Metric], ± 10%, X6S, CC Series"
			(at 0 0 270)
			(layer "F.Fab")
			(hide yes)
			(effects
				(font
					(size 1.27 1.27)
					(thickness 0.15)
				)
			)
		)
		(property "Author" "Antmicro"
			(at 37.8 209.5 0)
			(layer "B.Fab")
			(hide yes)
			(effects
				(font
					(size 1 1)
					(thickness 0.15)
				)
				(justify mirror)
			)
		)
		(property "Dielectric" ""
			(at 37.8 209.5 0)
			(layer "B.Fab")
			(hide yes)
			(effects
				(font
					(size 1 1)
					(thickness 0.15)
				)
				(justify mirror)
			)
		)
		(property "License" "Apache-2.0"
			(at 37.8 209.5 0)
			(layer "B.Fab")
			(hide yes)
			(effects
				(font
					(size 1 1)
					(thickness 0.15)
				)
				(justify mirror)
			)
		)
		(property "MPN" "CC0201KRX6S5BB104"
			(at 37.8 209.5 0)
			(layer "B.Fab")
			(hide yes)
			(effects
				(font
					(size 1 1)
					(thickness 0.15)
				)
				(justify mirror)
			)
		)
		(property "Manufacturer" "YAGEO"
			(at 37.8 209.5 0)
			(layer "B.Fab")
			(hide yes)
			(effects
				(font
					(size 1 1)
					(thickness 0.15)
				)
				(justify mirror)
			)
		)
		(property "Val" "100n"
			(at 37.8 209.5 0)
			(layer "B.Fab")
			(hide yes)
			(effects
				(font
					(size 1 1)
					(thickness 0.15)
				)
				(justify mirror)
			)
		)
		(property "Voltage" ""
			(at 37.8 209.5 0)
			(layer "B.Fab")
			(hide yes)
			(effects
				(font
					(size 1 1)
					(thickness 0.15)
				)
				(justify mirror)
			)
		)
		(property "Public" "False"
			(at 0 0 270)
			(unlocked yes)
			(layer "B.Fab")
			(hide yes)
			(effects
				(font
					(size 1 1)
					(thickness 0.15)
				)
				(justify mirror)
			)
		)
		(sheetname "/DDR3/")
		(sheetfile "ddr3.kicad_sch")
		(attr smd)
		(fp_rect
			(start -0.7 0.35)
			(end 0.7 -0.35)
			(stroke
				(width 0.05)
				(type default)
			)
			(fill no)
			(layer "B.CrtYd")
		)
		(fp_rect
			(start 0.3 -0.15)
			(end -0.301 0.149)
			(stroke
				(width 0.15)
				(type solid)
			)
			(fill no)
			(layer "B.Fab")
		)
		(fp_text user "License: Apache-2.0"
			(at -0.72 -4.4 90)
			(layer "B.Fab")
			(effects
				(font
					(size 0.7 0.7)
					(thickness 0.15)
				)
				(justify left bottom mirror)
			)
		)
		(fp_text user "${REFERENCE}"
			(at -0.72 -3.4 90)
			(layer "B.Fab")
			(effects
				(font
					(size 0.7 0.7)
					(thickness 0.15)
				)
				(justify left bottom mirror)
			)
		)
		(fp_text user "Author: Antmicro"
			(at -0.72 -5.4 90)
			(layer "B.Fab")
			(effects
				(font
					(size 0.7 0.7)
					(thickness 0.15)
				)
				(justify left bottom mirror)
			)
		)
		(pad "" smd roundrect
			(at -0.349 0.002 270)
			(size 0.318 0.36)
			(layers "B.Paste")
			(roundrect_rratio 0.25)
		)
		(pad "" smd roundrect
			(at 0.341 0.002 270)
			(size 0.318 0.36)
			(layers "B.Paste")
			(roundrect_rratio 0.25)
		)
		(pad "1" smd roundrect
			(at -0.321 0.002 270)
			(size 0.46 0.4)
			(layers "B.Cu" "B.Mask")
			(roundrect_rratio 0.25)
			(net 5 "Vref")
			(pintype "passive")
		)
		(pad "2" smd roundrect
			(at 0.32 0.002 270)
			(size 0.46 0.4)
			(layers "B.Cu" "B.Mask")
			(roundrect_rratio 0.25)
			(net 248 "+1V5")
			(pintype "passive")
		)
	)
	(footprint "antmicro-footprints:C_0201"
		(layer "B.Cu")
		(at 127.97 85.52 -45)
		(descr "Capacitor SMD 0201")
		(tags "capacitor SMD 0201")
		(property "Reference" "C83"
			(at -16.444289 -2.669849 315)
			(layer "B.SilkS")
			(effects
				(font
					(size 0.65 0.65)
					(thickness 0.15)
				)
				(justify left bottom mirror)
			)
		)
		(property "Value" "C_100n_0201"
			(at 0 -1.399999 135)
			(layer "B.Fab")
			(hide yes)
			(effects
				(font
					(size 0.7 0.7)
					(thickness 0.15)
				)
				(justify left bottom mirror)
			)
		)
		(property "Datasheet" "https://www.yageo.com/en/Chart/Download/pdf/CC0201KRX6S5BB104"
			(at 0 0 315)
			(layer "F.Fab")
			(hide yes)
			(effects
				(font
					(size 1.27 1.27)
					(thickness 0.15)
				)
			)
		)
		(property "Description" "SMD Multilayer Ceramic Capacitor, 0.1 µF, 6.3 V, 0201 [0603 Metric], ± 10%, X6S, CC Series"
			(at 0 0 315)
			(layer "F.Fab")
			(hide yes)
			(effects
				(font
					(size 1.27 1.27)
					(thickness 0.15)
				)
			)
		)
		(property "Author" "Antmicro"
			(at -22.990226 115.536683 0)
			(layer "B.Fab")
			(hide yes)
			(effects
				(font
					(size 1 1)
					(thickness 0.15)
				)
				(justify mirror)
			)
		)
		(property "Dielectric" ""
			(at -22.990226 115.536683 0)
			(layer "B.Fab")
			(hide yes)
			(effects
				(font
					(size 1 1)
					(thickness 0.15)
				)
				(justify mirror)
			)
		)
		(property "License" "Apache-2.0"
			(at -22.990226 115.536683 0)
			(layer "B.Fab")
			(hide yes)
			(effects
				(font
					(size 1 1)
					(thickness 0.15)
				)
				(justify mirror)
			)
		)
		(property "MPN" "CC0201KRX6S5BB104"
			(at -22.990226 115.536683 0)
			(layer "B.Fab")
			(hide yes)
			(effects
				(font
					(size 1 1)
					(thickness 0.15)
				)
				(justify mirror)
			)
		)
		(property "Manufacturer" "YAGEO"
			(at -22.990226 115.536683 0)
			(layer "B.Fab")
			(hide yes)
			(effects
				(font
					(size 1 1)
					(thickness 0.15)
				)
				(justify mirror)
			)
		)
		(property "Val" "100n"
			(at -22.990226 115.536683 0)
			(layer "B.Fab")
			(hide yes)
			(effects
				(font
					(size 1 1)
					(thickness 0.15)
				)
				(justify mirror)
			)
		)
		(property "Voltage" ""
			(at -22.990226 115.536683 0)
			(layer "B.Fab")
			(hide yes)
			(effects
				(font
					(size 1 1)
					(thickness 0.15)
				)
				(justify mirror)
			)
		)
		(property "Public" "False"
			(at 0 0 315)
			(unlocked yes)
			(layer "B.Fab")
			(hide yes)
			(effects
				(font
					(size 1 1)
					(thickness 0.15)
				)
				(justify mirror)
			)
		)
		(sheetname "/Peripherals/")
		(sheetfile "peripherals.kicad_sch")
		(attr smd)
		(fp_poly
			(pts
				(xy -0.7 0.35) (xy 0.7 0.35) (xy 0.7 -0.35) (xy -0.7 -0.35)
			)
			(stroke
				(width 0.05)
				(type default)
			)
			(fill no)
			(layer "B.CrtYd")
		)
		(fp_poly
			(pts
				(xy 0.3 -0.15) (xy -0.301 -0.15) (xy -0.301 0.149) (xy 0.3 0.149)
			)
			(stroke
				(width 0.15)
				(type solid)
			)
			(fill no)
			(layer "B.Fab")
		)
		(fp_text user "License: Apache-2.0"
			(at -0.72 -4.4 135)
			(layer "B.Fab")
			(effects
				(font
					(size 0.7 0.7)
					(thickness 0.15)
				)
				(justify left bottom mirror)
			)
		)
		(fp_text user "Author: Antmicro"
			(at -0.72 -5.400001 135)
			(layer "B.Fab")
			(effects
				(font
					(size 0.7 0.7)
					(thickness 0.15)
				)
				(justify left bottom mirror)
			)
		)
		(fp_text user "${REFERENCE}"
			(at -0.72 -3.4 135)
			(layer "B.Fab")
			(effects
				(font
					(size 0.7 0.7)
					(thickness 0.15)
				)
				(justify left bottom mirror)
			)
		)
		(pad "" smd roundrect
			(at -0.349 0.002 315)
			(size 0.318 0.36)
			(layers "B.Paste")
			(roundrect_rratio 0.25)
		)
		(pad "" smd roundrect
			(at 0.341 0.002 315)
			(size 0.318 0.36)
			(layers "B.Paste")
			(roundrect_rratio 0.25)
		)
		(pad "1" smd roundrect
			(at -0.321 0.002 315)
			(size 0.46 0.4)
			(layers "B.Cu" "B.Mask")
			(roundrect_rratio 0.25)
			(net 1 "GND")
			(pintype "passive")
		)
		(pad "2" smd roundrect
			(at 0.32 0.002 315)
			(size 0.46 0.4)
			(layers "B.Cu" "B.Mask")
			(roundrect_rratio 0.25)
			(net 3 "+1V2")
			(pintype "passive")
		)
	)
	(footprint "antmicro-footprints:C_0402_1005Metric"
		(layer "B.Cu")
		(at 128.58 62.02 90)
		(descr "Capacitor SMD 0402")
		(tags "capacitor SMD 0402")
		(property "Reference" "C45"
			(at -2.92 0.35 90)
			(layer "B.SilkS")
			(effects
				(font
					(size 0.65 0.65)
					(thickness 0.15)
				)
				(justify right bottom mirror)
			)
		)
		(property "Value" "C_100n_0402"
			(at 0 -1.4 90)
			(layer "B.Fab")
			(hide yes)
			(effects
				(font
					(size 0.7 0.7)
					(thickness 0.15)
				)
				(justify right bottom mirror)
			)
		)
		(property "Datasheet" "https://www.murata.com/products/productdetail?partno=GRM155R61H104KE14%23"
			(at 0 0 90)
			(layer "F.Fab")
			(hide yes)
			(effects
				(font
					(size 1.27 1.27)
					(thickness 0.15)
				)
			)
		)
		(property "Description" "SMD Multilayer Ceramic Capacitor, 0.1 µF, 50 V, 0402 [1005 Metric], ± 10%, X5R, GRM Series"
			(at 0 0 90)
			(layer "F.Fab")
			(hide yes)
			(effects
				(font
					(size 1.27 1.27)
					(thickness 0.15)
				)
			)
		)
		(property "Author" "Antmicro"
			(at 190.6 -66.56 0)
			(layer "B.Fab")
			(hide yes)
			(effects
				(font
					(size 1 1)
					(thickness 0.15)
				)
				(justify mirror)
			)
		)
		(property "Dielectric" "X5R"
			(at 190.6 -66.56 0)
			(layer "B.Fab")
			(hide yes)
			(effects
				(font
					(size 1 1)
					(thickness 0.15)
				)
				(justify mirror)
			)
		)
		(property "License" "Apache-2.0"
			(at 190.6 -66.56 0)
			(layer "B.Fab")
			(hide yes)
			(effects
				(font
					(size 1 1)
					(thickness 0.15)
				)
				(justify mirror)
			)
		)
		(property "MPN" "GRM155R61H104KE14D"
			(at 190.6 -66.56 0)
			(layer "B.Fab")
			(hide yes)
			(effects
				(font
					(size 1 1)
					(thickness 0.15)
				)
				(justify mirror)
			)
		)
		(property "Manufacturer" "Murata"
			(at 190.6 -66.56 0)
			(layer "B.Fab")
			(hide yes)
			(effects
				(font
					(size 1 1)
					(thickness 0.15)
				)
				(justify mirror)
			)
		)
		(property "Val" "100n"
			(at 190.6 -66.56 0)
			(layer "B.Fab")
			(hide yes)
			(effects
				(font
					(size 1 1)
					(thickness 0.15)
				)
				(justify mirror)
			)
		)
		(property "Voltage" "50V"
			(at 190.6 -66.56 0)
			(layer "B.Fab")
			(hide yes)
			(effects
				(font
					(size 1 1)
					(thickness 0.15)
				)
				(justify mirror)
			)
		)
		(sheetname "/DDR3/")
		(sheetfile "ddr3.kicad_sch")
		(attr smd)
		(fp_rect
			(start -0.925 0.47)
			(end 0.925 -0.47)
			(stroke
				(width 0.05)
				(type default)
			)
			(fill no)
			(layer "B.CrtYd")
		)
		(fp_line
			(start 0.504 -0.248)
			(end -0.494 -0.248)
			(stroke
				(width 0.15)
				(type solid)
			)
			(layer "B.Fab")
		)
		(fp_line
			(start -0.494 -0.248)
			(end -0.494 0.25)
			(stroke
				(width 0.15)
				(type solid)
			)
			(layer "B.Fab")
		)
		(fp_line
			(start 0.504 0.25)
			(end 0.504 -0.248)
			(stroke
				(width 0.15)
				(type solid)
			)
			(layer "B.Fab")
		)
		(fp_line
			(start -0.494 0.25)
			(end 0.504 0.25)
			(stroke
				(width 0.15)
				(type solid)
			)
			(layer "B.Fab")
		)
		(fp_text user "${REFERENCE}"
			(at -0.939 -4.599 270)
			(layer "B.Fab")
			(effects
				(font
					(size 0.7 0.7)
					(thickness 0.15)
				)
				(justify left bottom mirror)
			)
		)
		(fp_text user "Author: Antmicro"
			(at -0.939 -3.399 270)
			(layer "B.Fab")
			(effects
				(font
					(size 0.7 0.7)
					(thickness 0.15)
				)
				(justify left bottom mirror)
			)
		)
		(fp_text user "License: Apache-2.0"
			(at -0.939 -5.799 270)
			(layer "B.Fab")
			(effects
				(font
					(size 0.7 0.7)
					(thickness 0.15)
				)
				(justify left bottom mirror)
			)
		)
		(pad "1" smd roundrect
			(at -0.48 0 90)
			(size 0.59 0.64)
			(layers "B.Cu" "B.Mask" "B.Paste")
			(roundrect_rratio 0.25)
			(net 1 "GND")
			(pintype "passive")
		)
		(pad "2" smd roundrect
			(at 0.48 0 90)
			(size 0.59 0.64)
			(layers "B.Cu" "B.Mask" "B.Paste")
			(roundrect_rratio 0.25)
			(net 248 "+1V5")
			(pintype "passive")
		)
	)
	(footprint "antmicro-footprints:C_0402_1005Metric"
		(layer "B.Cu")
		(at 119.02 62.41)
		(descr "Capacitor SMD 0402")
		(tags "capacitor SMD 0402")
		(property "Reference" "C44"
			(at -5.09 0.33 0)
			(layer "B.SilkS")
			(effects
				(font
					(size 0.65 0.65)
					(thickness 0.15)
				)
				(justify right bottom mirror)
			)
		)
		(property "Value" "C_100n_0402"
			(at 0 -1.4 0)
			(layer "B.Fab")
			(hide yes)
			(effects
				(font
					(size 0.7 0.7)
					(thickness 0.15)
				)
				(justify right bottom mirror)
			)
		)
		(property "Datasheet" "https://www.murata.com/products/productdetail?partno=GRM155R61H104KE14%23"
			(at 0 0 0)
			(layer "F.Fab")
			(hide yes)
			(effects
				(font
					(size 1.27 1.27)
					(thickness 0.15)
				)
			)
		)
		(property "Description" "SMD Multilayer Ceramic Capacitor, 0.1 µF, 50 V, 0402 [1005 Metric], ± 10%, X5R, GRM Series"
			(at 0 0 0)
			(layer "F.Fab")
			(hide yes)
			(effects
				(font
					(size 1.27 1.27)
					(thickness 0.15)
				)
			)
		)
		(property "Author" "Antmicro"
			(at 0 0 0)
			(layer "B.Fab")
			(hide yes)
			(effects
				(font
					(size 1 1)
					(thickness 0.15)
				)
				(justify mirror)
			)
		)
		(property "Dielectric" "X5R"
			(at 0 0 0)
			(layer "B.Fab")
			(hide yes)
			(effects
				(font
					(size 1 1)
					(thickness 0.15)
				)
				(justify mirror)
			)
		)
		(property "License" "Apache-2.0"
			(at 0 0 0)
			(layer "B.Fab")
			(hide yes)
			(effects
				(font
					(size 1 1)
					(thickness 0.15)
				)
				(justify mirror)
			)
		)
		(property "MPN" "GRM155R61H104KE14D"
			(at 0 0 0)
			(layer "B.Fab")
			(hide yes)
			(effects
				(font
					(size 1 1)
					(thickness 0.15)
				)
				(justify mirror)
			)
		)
		(property "Manufacturer" "Murata"
			(at 0 0 0)
			(layer "B.Fab")
			(hide yes)
			(effects
				(font
					(size 1 1)
					(thickness 0.15)
				)
				(justify mirror)
			)
		)
		(property "Val" "100n"
			(at 0 0 0)
			(layer "B.Fab")
			(hide yes)
			(effects
				(font
					(size 1 1)
					(thickness 0.15)
				)
				(justify mirror)
			)
		)
		(property "Voltage" "50V"
			(at 0 0 0)
			(layer "B.Fab")
			(hide yes)
			(effects
				(font
					(size 1 1)
					(thickness 0.15)
				)
				(justify mirror)
			)
		)
		(sheetname "/DDR3/")
		(sheetfile "ddr3.kicad_sch")
		(attr smd)
		(fp_rect
			(start -0.925 0.47)
			(end 0.925 -0.47)
			(stroke
				(width 0.05)
				(type default)
			)
			(fill no)
			(layer "B.CrtYd")
		)
		(fp_line
			(start -0.494 -0.248)
			(end -0.494 0.25)
			(stroke
				(width 0.15)
				(type solid)
			)
			(layer "B.Fab")
		)
		(fp_line
			(start -0.494 0.25)
			(end 0.504 0.25)
			(stroke
				(width 0.15)
				(type solid)
			)
			(layer "B.Fab")
		)
		(fp_line
			(start 0.504 -0.248)
			(end -0.494 -0.248)
			(stroke
				(width 0.15)
				(type solid)
			)
			(layer "B.Fab")
		)
		(fp_line
			(start 0.504 0.25)
			(end 0.504 -0.248)
			(stroke
				(width 0.15)
				(type solid)
			)
			(layer "B.Fab")
		)
		(fp_text user "${REFERENCE}"
			(at -0.939 -4.599 180)
			(layer "B.Fab")
			(effects
				(font
					(size 0.7 0.7)
					(thickness 0.15)
				)
				(justify left bottom mirror)
			)
		)
		(fp_text user "License: Apache-2.0"
			(at -0.939 -5.799 180)
			(layer "B.Fab")
			(effects
				(font
					(size 0.7 0.7)
					(thickness 0.15)
				)
				(justify left bottom mirror)
			)
		)
		(fp_text user "Author: Antmicro"
			(at -0.939 -3.399 180)
			(layer "B.Fab")
			(effects
				(font
					(size 0.7 0.7)
					(thickness 0.15)
				)
				(justify left bottom mirror)
			)
		)
		(pad "1" smd roundrect
			(at -0.48 0)
			(size 0.59 0.64)
			(layers "B.Cu" "B.Mask" "B.Paste")
			(roundrect_rratio 0.25)
			(net 1 "GND")
			(pintype "passive")
		)
		(pad "2" smd roundrect
			(at 0.48 0)
			(size 0.59 0.64)
			(layers "B.Cu" "B.Mask" "B.Paste")
			(roundrect_rratio 0.25)
			(net 248 "+1V5")
			(pintype "passive")
		)
	)
	(footprint "antmicro-footprints:C_0201"
		(layer "B.Cu")
		(at 134.63 92.2)
		(descr "Capacitor SMD 0201")
		(tags "capacitor SMD 0201")
		(property "Reference" "C94"
			(at -0.85 1.34 0)
			(layer "B.SilkS")
			(effects
				(font
					(size 0.65 0.65)
					(thickness 0.15)
				)
				(justify right bottom mirror)
			)
		)
		(property "Value" "C_100n_0201"
			(at 0 -1.4 0)
			(layer "B.Fab")
			(hide yes)
			(effects
				(font
					(size 0.7 0.7)
					(thickness 0.15)
				)
				(justify right bottom mirror)
			)
		)
		(property "Datasheet" "https://www.yageo.com/en/Chart/Download/pdf/CC0201KRX6S5BB104"
			(at 0 0 0)
			(layer "F.Fab")
			(hide yes)
			(effects
				(font
					(size 1.27 1.27)
					(thickness 0.15)
				)
			)
		)
		(property "Description" "SMD Multilayer Ceramic Capacitor, 0.1 µF, 6.3 V, 0201 [0603 Metric], ± 10%, X6S, CC Series"
			(at 0 0 0)
			(layer "F.Fab")
			(hide yes)
			(effects
				(font
					(size 1.27 1.27)
					(thickness 0.15)
				)
			)
		)
		(property "Author" "Antmicro"
			(at 0 0 0)
			(layer "B.Fab")
			(hide yes)
			(effects
				(font
					(size 1 1)
					(thickness 0.15)
				)
				(justify mirror)
			)
		)
		(property "Dielectric" ""
			(at 0 0 0)
			(layer "B.Fab")
			(hide yes)
			(effects
				(font
					(size 1 1)
					(thickness 0.15)
				)
				(justify mirror)
			)
		)
		(property "License" "Apache-2.0"
			(at 0 0 0)
			(layer "B.Fab")
			(hide yes)
			(effects
				(font
					(size 1 1)
					(thickness 0.15)
				)
				(justify mirror)
			)
		)
		(property "MPN" "CC0201KRX6S5BB104"
			(at 0 0 0)
			(layer "B.Fab")
			(hide yes)
			(effects
				(font
					(size 1 1)
					(thickness 0.15)
				)
				(justify mirror)
			)
		)
		(property "Manufacturer" "YAGEO"
			(at 0 0 0)
			(layer "B.Fab")
			(hide yes)
			(effects
				(font
					(size 1 1)
					(thickness 0.15)
				)
				(justify mirror)
			)
		)
		(property "Val" "100n"
			(at 0 0 0)
			(layer "B.Fab")
			(hide yes)
			(effects
				(font
					(size 1 1)
					(thickness 0.15)
				)
				(justify mirror)
			)
		)
		(property "Voltage" ""
			(at 0 0 0)
			(layer "B.Fab")
			(hide yes)
			(effects
				(font
					(size 1 1)
					(thickness 0.15)
				)
				(justify mirror)
			)
		)
		(property "Public" "False"
			(at 0 0 0)
			(unlocked yes)
			(layer "B.Fab")
			(hide yes)
			(effects
				(font
					(size 1 1)
					(thickness 0.15)
				)
				(justify mirror)
			)
		)
		(sheetname "/FPGA Power/")
		(sheetfile "FPGA_Power.kicad_sch")
		(attr smd)
		(fp_rect
			(start -0.7 0.35)
			(end 0.7 -0.35)
			(stroke
				(width 0.05)
				(type default)
			)
			(fill no)
			(layer "B.CrtYd")
		)
		(fp_rect
			(start 0.3 -0.15)
			(end -0.301 0.149)
			(stroke
				(width 0.15)
				(type solid)
			)
			(fill no)
			(layer "B.Fab")
		)
		(fp_text user "License: Apache-2.0"
			(at -0.72 -4.4 180)
			(layer "B.Fab")
			(effects
				(font
					(size 0.7 0.7)
					(thickness 0.15)
				)
				(justify left bottom mirror)
			)
		)
		(fp_text user "Author: Antmicro"
			(at -0.72 -5.4 180)
			(layer "B.Fab")
			(effects
				(font
					(size 0.7 0.7)
					(thickness 0.15)
				)
				(justify left bottom mirror)
			)
		)
		(fp_text user "${REFERENCE}"
			(at -0.72 -3.4 180)
			(layer "B.Fab")
			(effects
				(font
					(size 0.7 0.7)
					(thickness 0.15)
				)
				(justify left bottom mirror)
			)
		)
		(pad "" smd roundrect
			(at -0.349 0.002)
			(size 0.318 0.36)
			(layers "B.Paste")
			(roundrect_rratio 0.25)
		)
		(pad "" smd roundrect
			(at 0.341 0.002)
			(size 0.318 0.36)
			(layers "B.Paste")
			(roundrect_rratio 0.25)
		)
		(pad "1" smd roundrect
			(at -0.321 0.002)
			(size 0.46 0.4)
			(layers "B.Cu" "B.Mask")
			(roundrect_rratio 0.25)
			(net 1 "GND")
			(pintype "passive")
		)
		(pad "2" smd roundrect
			(at 0.32 0.002)
			(size 0.46 0.4)
			(layers "B.Cu" "B.Mask")
			(roundrect_rratio 0.25)
			(net 10 "/FPGA Power/VCC_AUXA")
			(pintype "passive")
		)
	)
	(footprint "antmicro-footprints:SOT-363"
		(layer "B.Cu")
		(at 154.23 65.75 -90)
		(property "Reference" "Q2"
			(at 2.19 -0.1 180)
			(layer "B.SilkS")
			(effects
				(font
					(size 0.65 0.65)
					(thickness 0.15)
				)
				(justify left bottom mirror)
			)
		)
		(property "Value" "BCM857BS-7-F"
			(at 0 -2.2 90)
			(layer "B.Fab")
			(hide yes)
			(effects
				(font
					(size 0.7 0.7)
					(thickness 0.15)
				)
				(justify left bottom mirror)
			)
		)
		(property "Datasheet" "https://www.diodes.com/assets/Datasheets/BCM857BS.pdf"
			(at 0 0 270)
			(layer "F.Fab")
			(hide yes)
			(effects
				(font
					(size 1.27 1.27)
					(thickness 0.15)
				)
			)
		)
		(property "Description" "Bipolar (BJT) Transistor Array, 2 Transistors, PNP, 45V, 100mA, SOT-363, Surface Mount"
			(at 0 0 270)
			(layer "F.Fab")
			(hide yes)
			(effects
				(font
					(size 1.27 1.27)
					(thickness 0.15)
				)
			)
		)
		(property "Author" "Antmicro"
			(at 88.48 219.98 0)
			(layer "B.Fab")
			(hide yes)
			(effects
				(font
					(size 1 1)
					(thickness 0.15)
				)
				(justify mirror)
			)
		)
		(property "License" "Apache-2.0"
			(at 88.48 219.98 0)
			(layer "B.Fab")
			(hide yes)
			(effects
				(font
					(size 1 1)
					(thickness 0.15)
				)
				(justify mirror)
			)
		)
		(property "MPN" "BCM857BS-7-F"
			(at 88.48 219.98 0)
			(layer "B.Fab")
			(hide yes)
			(effects
				(font
					(size 1 1)
					(thickness 0.15)
				)
				(justify mirror)
			)
		)
		(property "Manufacturer" "Diodes Incorporated"
			(at 88.48 219.98 0)
			(layer "B.Fab")
			(hide yes)
			(effects
				(font
					(size 1 1)
					(thickness 0.15)
				)
				(justify mirror)
			)
		)
		(sheetname "/Power Supply/")
		(sheetfile "supply.kicad_sch")
		(attr smd)
		(fp_line
			(start 0.803 1.228)
			(end -0.72 1.228)
			(stroke
				(width 0.15)
				(type solid)
			)
			(layer "B.SilkS")
		)
		(fp_line
			(start -0.72 1.153)
			(end -0.72 1.228)
			(stroke
				(width 0.15)
				(type solid)
			)
			(layer "B.SilkS")
		)
		(fp_line
			(start 0.803 1.153)
			(end 0.803 1.228)
			(stroke
				(width 0.15)
				(type solid)
			)
			(layer "B.SilkS")
		)
		(fp_line
			(start -0.8 -1.146)
			(end -0.8 -1.223)
			(stroke
				(width 0.15)
				(type solid)
			)
			(layer "B.SilkS")
		)
		(fp_line
			(start 0.803 -1.146)
			(end 0.803 -1.223)
			(stroke
				(width 0.15)
				(type solid)
			)
			(layer "B.SilkS")
		)
		(fp_line
			(start -0.8 -1.223)
			(end 0.803 -1.223)
			(stroke
				(width 0.15)
				(type solid)
			)
			(layer "B.SilkS")
		)
		(fp_circle
			(center -0.978102 1.2)
			(end -0.928102 1.2)
			(stroke
				(width 0.15)
				(type solid)
			)
			(fill yes)
			(layer "B.SilkS")
		)
		(fp_rect
			(start 1.3 1.3)
			(end -1.3 -1.3)
			(stroke
				(width 0.05)
				(type solid)
			)
			(fill no)
			(layer "B.CrtYd")
		)
		(fp_line
			(start -0.1 1.1)
			(end -0.68 0.52)
			(stroke
				(width 0.15)
				(type solid)
			)
			(layer "B.Fab")
		)
		(fp_rect
			(start 0.68 -1.1)
			(end -0.68 1.1)
			(stroke
				(width 0.15)
				(type solid)
			)
			(fill no)
			(layer "B.Fab")
		)
		(pad "1" smd custom
			(at -0.948 0.752)
			(size 0.6 0.6)
			(layers "B.Cu" "B.Mask" "B.Paste")
			(net 304 "/Power Supply/5V_I")
			(pintype "passive")
			(zone_connect 0)
			(options
				(clearance outline)
				(anchor rect)
			)
			(primitives)
		)
		(pad "2" smd rect
			(at -0.948 0.002)
			(size 0.4 0.6)
			(layers "B.Cu" "B.Mask" "B.Paste")
			(net 382 "Net-(Q2-Pad2)")
			(pintype "input")
		)
		(pad "3" smd custom
			(at -0.948 -0.745)
			(size 0.6 0.6)
			(layers "B.Cu" "B.Mask" "B.Paste")
			(net 382 "Net-(Q2-Pad2)")
			(pintype "passive")
			(zone_connect 0)
			(options
				(clearance outline)
				(anchor rect)
			)
			(primitives)
		)
		(pad "4" smd custom
			(at 0.951 -0.745)
			(size 0.6 0.6)
			(layers "B.Cu" "B.Mask" "B.Paste")
			(net 325 "USB_POWER_IN")
			(pintype "passive")
			(zone_connect 0)
			(options
				(clearance outline)
				(anchor rect)
			)
			(primitives)
		)
		(pad "5" smd rect
			(at 0.951 0.002)
			(size 0.4 0.6)
			(layers "B.Cu" "B.Mask" "B.Paste")
			(net 382 "Net-(Q2-Pad2)")
			(pintype "input")
		)
		(pad "6" smd custom
			(at 0.951 0.752)
			(size 0.6 0.6)
			(layers "B.Cu" "B.Mask" "B.Paste")
			(net 260 "Net-(Q3-G)")
			(pintype "passive")
			(zone_connect 0)
			(options
				(clearance outline)
				(anchor rect)
			)
			(primitives)
		)
	)
	(footprint "antmicro-footprints:TP_SMD_0.75mm"
		(layer "B.Cu")
		(at 93.94 88.2 90)
		(property "Reference" "TP42"
			(at 0.76 0.39 90)
			(layer "B.SilkS")
			(effects
				(font
					(size 0.65 0.65)
					(thickness 0.15)
				)
				(justify right bottom mirror)
			)
		)
		(property "Value" "TP_0.75mm_SMD"
			(at 0 -1.2 90)
			(layer "B.Fab")
			(hide yes)
			(effects
				(font
					(size 0.7 0.7)
					(thickness 0.15)
				)
				(justify right bottom mirror)
			)
		)
		(property "Description" "SMT test point"
			(at 0 0 90)
			(layer "F.Fab")
			(hide yes)
			(effects
				(font
					(size 1.27 1.27)
					(thickness 0.15)
				)
			)
		)
		(property "Author" "Antmicro"
			(at 182.14 -5.74 0)
			(layer "B.Fab")
			(hide yes)
			(effects
				(font
					(size 1 1)
					(thickness 0.15)
				)
				(justify mirror)
			)
		)
		(property "License" "Apache-2.0"
			(at 182.14 -5.74 0)
			(layer "B.Fab")
			(hide yes)
			(effects
				(font
					(size 1 1)
					(thickness 0.15)
				)
				(justify mirror)
			)
		)
		(property "MPN" ""
			(at 182.14 -5.74 0)
			(layer "B.Fab")
			(hide yes)
			(effects
				(font
					(size 1 1)
					(thickness 0.15)
				)
				(justify mirror)
			)
		)
		(property "Manufacturer" ""
			(at 182.14 -5.74 0)
			(layer "B.Fab")
			(hide yes)
			(effects
				(font
					(size 1 1)
					(thickness 0.15)
				)
				(justify mirror)
			)
		)
		(sheetname "/SDI/")
		(sheetfile "sdi.kicad_sch")
		(attr exclude_from_pos_files)
		(fp_circle
			(center 0 0)
			(end 0.475 0)
			(stroke
				(width 0.05)
				(type default)
			)
			(fill no)
			(layer "B.CrtYd")
		)
		(fp_text user "Author: Antmicro"
			(at -0.4 -3.901 270)
			(layer "B.Fab")
			(effects
				(font
					(size 0.7 0.7)
					(thickness 0.15)
				)
				(justify left bottom mirror)
			)
		)
		(fp_text user "${REFERENCE}"
			(at -0.4 -2.7 270)
			(layer "B.Fab")
			(effects
				(font
					(size 0.7 0.7)
					(thickness 0.15)
				)
				(justify left bottom mirror)
			)
		)
		(fp_text user "License: Apache-2.0"
			(at -0.4 -5.101 270)
			(layer "B.Fab")
			(effects
				(font
					(size 0.7 0.7)
					(thickness 0.15)
				)
				(justify left bottom mirror)
			)
		)
		(pad "1" smd circle
			(at 0 0 90)
			(size 0.75 0.75)
			(layers "B.Cu" "B.Mask")
			(net 180 "/SDI/TIM_861")
			(pinfunction "1")
			(pintype "passive")
		)
	)
	(footprint "antmicro-footprints:C_0201"
		(layer "B.Cu")
		(at 132.3 84.3 -135)
		(descr "Capacitor SMD 0201")
		(tags "capacitor SMD 0201")
		(property "Reference" "C16"
			(at -0.982878 0.657609 45)
			(layer "B.SilkS")
			(effects
				(font
					(size 0.65 0.65)
					(thickness 0.15)
				)
				(justify left bottom mirror)
			)
		)
		(property "Value" "C_100n_0201"
			(at 0 -1.399999 45)
			(layer "B.Fab")
			(hide yes)
			(effects
				(font
					(size 0.7 0.7)
					(thickness 0.15)
				)
				(justify left bottom mirror)
			)
		)
		(property "Datasheet" "https://www.yageo.com/en/Chart/Download/pdf/CC0201KRX6S5BB104"
			(at 0 0 225)
			(layer "F.Fab")
			(hide yes)
			(effects
				(font
					(size 1.27 1.27)
					(thickness 0.15)
				)
			)
		)
		(property "Description" "SMD Multilayer Ceramic Capacitor, 0.1 µF, 6.3 V, 0201 [0603 Metric], ± 10%, X6S, CC Series"
			(at 0 0 225)
			(layer "F.Fab")
			(hide yes)
			(effects
				(font
					(size 1.27 1.27)
					(thickness 0.15)
				)
			)
		)
		(property "Author" "Antmicro"
			(at 166.241125 237.459329 0)
			(layer "B.Fab")
			(hide yes)
			(effects
				(font
					(size 1 1)
					(thickness 0.15)
				)
				(justify mirror)
			)
		)
		(property "Dielectric" ""
			(at 166.241125 237.459329 0)
			(layer "B.Fab")
			(hide yes)
			(effects
				(font
					(size 1 1)
					(thickness 0.15)
				)
				(justify mirror)
			)
		)
		(property "License" "Apache-2.0"
			(at 166.241125 237.459329 0)
			(layer "B.Fab")
			(hide yes)
			(effects
				(font
					(size 1 1)
					(thickness 0.15)
				)
				(justify mirror)
			)
		)
		(property "MPN" "CC0201KRX6S5BB104"
			(at 166.241125 237.459329 0)
			(layer "B.Fab")
			(hide yes)
			(effects
				(font
					(size 1 1)
					(thickness 0.15)
				)
				(justify mirror)
			)
		)
		(property "Manufacturer" "YAGEO"
			(at 166.241125 237.459329 0)
			(layer "B.Fab")
			(hide yes)
			(effects
				(font
					(size 1 1)
					(thickness 0.15)
				)
				(justify mirror)
			)
		)
		(property "Val" "100n"
			(at 166.241125 237.459329 0)
			(layer "B.Fab")
			(hide yes)
			(effects
				(font
					(size 1 1)
					(thickness 0.15)
				)
				(justify mirror)
			)
		)
		(property "Voltage" ""
			(at 166.241125 237.459329 0)
			(layer "B.Fab")
			(hide yes)
			(effects
				(font
					(size 1 1)
					(thickness 0.15)
				)
				(justify mirror)
			)
		)
		(property "Public" "False"
			(at 0 0 225)
			(unlocked yes)
			(layer "B.Fab")
			(hide yes)
			(effects
				(font
					(size 1 1)
					(thickness 0.15)
				)
				(justify mirror)
			)
		)
		(sheetname "/DDR3/")
		(sheetfile "ddr3.kicad_sch")
		(attr smd)
		(fp_poly
			(pts
				(xy -0.7 0.35) (xy 0.7 0.35) (xy 0.7 -0.35) (xy -0.7 -0.35)
			)
			(stroke
				(width 0.05)
				(type default)
			)
			(fill no)
			(layer "B.CrtYd")
		)
		(fp_poly
			(pts
				(xy 0.3 -0.15) (xy -0.301 -0.15) (xy -0.301 0.149) (xy 0.3 0.149)
			)
			(stroke
				(width 0.15)
				(type solid)
			)
			(fill no)
			(layer "B.Fab")
		)
		(fp_text user "Author: Antmicro"
			(at -0.72 -5.400001 45)
			(layer "B.Fab")
			(effects
				(font
					(size 0.7 0.7)
					(thickness 0.15)
				)
				(justify left bottom mirror)
			)
		)
		(fp_text user "License: Apache-2.0"
			(at -0.72 -4.4 45)
			(layer "B.Fab")
			(effects
				(font
					(size 0.7 0.7)
					(thickness 0.15)
				)
				(justify left bottom mirror)
			)
		)
		(fp_text user "${REFERENCE}"
			(at -0.72 -3.4 45)
			(layer "B.Fab")
			(effects
				(font
					(size 0.7 0.7)
					(thickness 0.15)
				)
				(justify left bottom mirror)
			)
		)
		(pad "" smd roundrect
			(at -0.349 0.002 225)
			(size 0.318 0.36)
			(layers "B.Paste")
			(roundrect_rratio 0.25)
		)
		(pad "" smd roundrect
			(at 0.341 0.002 225)
			(size 0.318 0.36)
			(layers "B.Paste")
			(roundrect_rratio 0.25)
		)
		(pad "1" smd roundrect
			(at -0.321 0.002 225)
			(size 0.46 0.4)
			(layers "B.Cu" "B.Mask")
			(roundrect_rratio 0.25)
			(net 1 "GND")
			(pintype "passive")
		)
		(pad "2" smd roundrect
			(at 0.32 0.002 225)
			(size 0.46 0.4)
			(layers "B.Cu" "B.Mask")
			(roundrect_rratio 0.25)
			(net 248 "+1V5")
			(pintype "passive")
		)
	)
	(footprint "antmicro-footprints:C_0402_1005Metric"
		(layer "B.Cu")
		(at 101.8 79.4 180)
		(descr "Capacitor SMD 0402")
		(tags "capacitor SMD 0402")
		(property "Reference" "C72"
			(at -1.03 0.66 0)
			(layer "B.SilkS")
			(effects
				(font
					(size 0.65 0.65)
					(thickness 0.15)
				)
				(justify left bottom mirror)
			)
		)
		(property "Value" "C_100n_0402"
			(at 0 -1.4 0)
			(layer "B.Fab")
			(hide yes)
			(effects
				(font
					(size 0.7 0.7)
					(thickness 0.15)
				)
				(justify left bottom mirror)
			)
		)
		(property "Datasheet" "https://www.murata.com/products/productdetail?partno=GRM155R61H104KE14%23"
			(at 0 0 180)
			(layer "F.Fab")
			(hide yes)
			(effects
				(font
					(size 1.27 1.27)
					(thickness 0.15)
				)
			)
		)
		(property "Description" "SMD Multilayer Ceramic Capacitor, 0.1 µF, 50 V, 0402 [1005 Metric], ± 10%, X5R, GRM Series"
			(at 0 0 180)
			(layer "F.Fab")
			(hide yes)
			(effects
				(font
					(size 1.27 1.27)
					(thickness 0.15)
				)
			)
		)
		(property "Author" "Antmicro"
			(at 203.6 158.8 0)
			(layer "B.Fab")
			(hide yes)
			(effects
				(font
					(size 1 1)
					(thickness 0.15)
				)
				(justify mirror)
			)
		)
		(property "Dielectric" "X5R"
			(at 203.6 158.8 0)
			(layer "B.Fab")
			(hide yes)
			(effects
				(font
					(size 1 1)
					(thickness 0.15)
				)
				(justify mirror)
			)
		)
		(property "License" "Apache-2.0"
			(at 203.6 158.8 0)
			(layer "B.Fab")
			(hide yes)
			(effects
				(font
					(size 1 1)
					(thickness 0.15)
				)
				(justify mirror)
			)
		)
		(property "MPN" "GRM155R61H104KE14D"
			(at 203.6 158.8 0)
			(layer "B.Fab")
			(hide yes)
			(effects
				(font
					(size 1 1)
					(thickness 0.15)
				)
				(justify mirror)
			)
		)
		(property "Manufacturer" "Murata"
			(at 203.6 158.8 0)
			(layer "B.Fab")
			(hide yes)
			(effects
				(font
					(size 1 1)
					(thickness 0.15)
				)
				(justify mirror)
			)
		)
		(property "Val" "100n"
			(at 203.6 158.8 0)
			(layer "B.Fab")
			(hide yes)
			(effects
				(font
					(size 1 1)
					(thickness 0.15)
				)
				(justify mirror)
			)
		)
		(property "Voltage" "50V"
			(at 203.6 158.8 0)
			(layer "B.Fab")
			(hide yes)
			(effects
				(font
					(size 1 1)
					(thickness 0.15)
				)
				(justify mirror)
			)
		)
		(sheetname "/SDI/")
		(sheetfile "sdi.kicad_sch")
		(attr smd)
		(fp_rect
			(start -0.925 0.47)
			(end 0.925 -0.47)
			(stroke
				(width 0.05)
				(type default)
			)
			(fill no)
			(layer "B.CrtYd")
		)
		(fp_line
			(start 0.504 0.25)
			(end 0.504 -0.248)
			(stroke
				(width 0.15)
				(type solid)
			)
			(layer "B.Fab")
		)
		(fp_line
			(start 0.504 -0.248)
			(end -0.494 -0.248)
			(stroke
				(width 0.15)
				(type solid)
			)
			(layer "B.Fab")
		)
		(fp_line
			(start -0.494 0.25)
			(end 0.504 0.25)
			(stroke
				(width 0.15)
				(type solid)
			)
			(layer "B.Fab")
		)
		(fp_line
			(start -0.494 -0.248)
			(end -0.494 0.25)
			(stroke
				(width 0.15)
				(type solid)
			)
			(layer "B.Fab")
		)
		(fp_text user "Author: Antmicro"
			(at -0.939 -3.399 0)
			(layer "B.Fab")
			(effects
				(font
					(size 0.7 0.7)
					(thickness 0.15)
				)
				(justify left bottom mirror)
			)
		)
		(fp_text user "${REFERENCE}"
			(at -0.939 -4.599 0)
			(layer "B.Fab")
			(effects
				(font
					(size 0.7 0.7)
					(thickness 0.15)
				)
				(justify left bottom mirror)
			)
		)
		(fp_text user "License: Apache-2.0"
			(at -0.939 -5.799 0)
			(layer "B.Fab")
			(effects
				(font
					(size 0.7 0.7)
					(thickness 0.15)
				)
				(justify left bottom mirror)
			)
		)
		(pad "1" smd roundrect
			(at -0.48 0 180)
			(size 0.59 0.64)
			(layers "B.Cu" "B.Mask" "B.Paste")
			(roundrect_rratio 0.25)
			(net 1 "GND")
			(pintype "passive")
		)
		(pad "2" smd roundrect
			(at 0.48 0 180)
			(size 0.59 0.64)
			(layers "B.Cu" "B.Mask" "B.Paste")
			(roundrect_rratio 0.25)
			(net 2 "+3V3")
			(pintype "passive")
		)
	)
	(footprint "antmicro-footprints:R_0402_1005Metric"
		(layer "B.Cu")
		(at 94.255 95.25)
		(descr "Resistor SMD 0402")
		(tags "resistor SMD 0402")
		(property "Reference" "R138"
			(at -1.025 0.29 180)
			(layer "B.SilkS")
			(effects
				(font
					(size 0.65 0.65)
					(thickness 0.15)
				)
				(justify left bottom mirror)
			)
		)
		(property "Value" "R_1k_0402"
			(at 0 -1.4 180)
			(layer "B.Fab")
			(hide yes)
			(effects
				(font
					(size 0.7 0.7)
					(thickness 0.15)
				)
				(justify left bottom mirror)
			)
		)
		(property "Datasheet" "https://www.bourns.com/docs/product-datasheets/cr.pdf"
			(at 0 0 0)
			(layer "F.Fab")
			(hide yes)
			(effects
				(font
					(size 1.27 1.27)
					(thickness 0.15)
				)
			)
		)
		(property "Description" "SMD Chip Resistor, 1 kohm, ± 1%, 63 mW, 0402 [1005 Metric], Thick Film, General Purpose"
			(at 0 0 0)
			(layer "F.Fab")
			(hide yes)
			(effects
				(font
					(size 1.27 1.27)
					(thickness 0.15)
				)
			)
		)
		(property "Author" "Antmicro"
			(at 0 0 0)
			(layer "B.Fab")
			(hide yes)
			(effects
				(font
					(size 1 1)
					(thickness 0.15)
				)
				(justify mirror)
			)
		)
		(property "License" "Apache-2.0"
			(at 0 0 0)
			(layer "B.Fab")
			(hide yes)
			(effects
				(font
					(size 1 1)
					(thickness 0.15)
				)
				(justify mirror)
			)
		)
		(property "MPN" "CR0402-FX-1001GLF"
			(at 0 0 0)
			(layer "B.Fab")
			(hide yes)
			(effects
				(font
					(size 1 1)
					(thickness 0.15)
				)
				(justify mirror)
			)
		)
		(property "Manufacturer" "Bourns"
			(at 0 0 0)
			(layer "B.Fab")
			(hide yes)
			(effects
				(font
					(size 1 1)
					(thickness 0.15)
				)
				(justify mirror)
			)
		)
		(property "Tolerance" "1%"
			(at 0 0 0)
			(layer "B.Fab")
			(hide yes)
			(effects
				(font
					(size 1 1)
					(thickness 0.15)
				)
				(justify mirror)
			)
		)
		(property "Val" "1k"
			(at 0 0 0)
			(layer "B.Fab")
			(hide yes)
			(effects
				(font
					(size 1 1)
					(thickness 0.15)
				)
				(justify mirror)
			)
		)
		(sheetname "/SDI/")
		(sheetfile "sdi.kicad_sch")
		(attr smd exclude_from_pos_files exclude_from_bom dnp)
		(fp_rect
			(start -0.925 0.47)
			(end 0.925 -0.47)
			(stroke
				(width 0.05)
				(type default)
			)
			(fill no)
			(layer "B.CrtYd")
		)
		(fp_rect
			(start -0.5 0.25)
			(end 0.5 -0.25)
			(stroke
				(width 0.15)
				(type solid)
			)
			(fill no)
			(layer "B.Fab")
		)
		(fp_text user "Author: Antmicro"
			(at -0.95 -4.169 180)
			(layer "B.Fab")
			(effects
				(font
					(size 0.7 0.7)
					(thickness 0.15)
				)
				(justify left bottom mirror)
			)
		)
		(fp_text user "License: Apache-2.0"
			(at -0.95 -5.169 180)
			(layer "B.Fab")
			(effects
				(font
					(size 0.7 0.7)
					(thickness 0.15)
				)
				(justify left bottom mirror)
			)
		)
		(fp_text user "${REFERENCE}"
			(at -0.95 -3.168 180)
			(layer "B.Fab")
			(effects
				(font
					(size 0.7 0.7)
					(thickness 0.15)
				)
				(justify left bottom mirror)
			)
		)
		(pad "1" smd roundrect
			(at -0.48 0)
			(size 0.59 0.64)
			(layers "B.Cu" "B.Mask" "B.Paste")
			(roundrect_rratio 0.25)
			(net 1 "GND")
			(pintype "passive")
		)
		(pad "2" smd roundrect
			(at 0.48 0)
			(size 0.59 0.64)
			(layers "B.Cu" "B.Mask" "B.Paste")
			(roundrect_rratio 0.25)
			(net 200 "/SDI/20bit{slash}~{10bit}")
			(pintype "passive")
		)
	)
	(footprint "antmicro-footprints:C_0201"
		(layer "B.Cu")
		(at 131.96 96.61 180)
		(descr "Capacitor SMD 0201")
		(tags "capacitor SMD 0201")
		(property "Reference" "C103"
			(at 0.73 -0.53 0)
			(layer "B.SilkS")
			(effects
				(font
					(size 0.65 0.65)
					(thickness 0.15)
				)
				(justify left bottom mirror)
			)
		)
		(property "Value" "C_100n_0201"
			(at 0 -1.4 0)
			(layer "B.Fab")
			(hide yes)
			(effects
				(font
					(size 0.7 0.7)
					(thickness 0.15)
				)
				(justify left bottom mirror)
			)
		)
		(property "Datasheet" "https://www.yageo.com/en/Chart/Download/pdf/CC0201KRX6S5BB104"
			(at 0 0 180)
			(layer "F.Fab")
			(hide yes)
			(effects
				(font
					(size 1.27 1.27)
					(thickness 0.15)
				)
			)
		)
		(property "Description" "SMD Multilayer Ceramic Capacitor, 0.1 µF, 6.3 V, 0201 [0603 Metric], ± 10%, X6S, CC Series"
			(at 0 0 180)
			(layer "F.Fab")
			(hide yes)
			(effects
				(font
					(size 1.27 1.27)
					(thickness 0.15)
				)
			)
		)
		(property "Author" "Antmicro"
			(at 263.92 193.22 0)
			(layer "B.Fab")
			(hide yes)
			(effects
				(font
					(size 1 1)
					(thickness 0.15)
				)
				(justify mirror)
			)
		)
		(property "Dielectric" ""
			(at 263.92 193.22 0)
			(layer "B.Fab")
			(hide yes)
			(effects
				(font
					(size 1 1)
					(thickness 0.15)
				)
				(justify mirror)
			)
		)
		(property "License" "Apache-2.0"
			(at 263.92 193.22 0)
			(layer "B.Fab")
			(hide yes)
			(effects
				(font
					(size 1 1)
					(thickness 0.15)
				)
				(justify mirror)
			)
		)
		(property "MPN" "CC0201KRX6S5BB104"
			(at 263.92 193.22 0)
			(layer "B.Fab")
			(hide yes)
			(effects
				(font
					(size 1 1)
					(thickness 0.15)
				)
				(justify mirror)
			)
		)
		(property "Manufacturer" "YAGEO"
			(at 263.92 193.22 0)
			(layer "B.Fab")
			(hide yes)
			(effects
				(font
					(size 1 1)
					(thickness 0.15)
				)
				(justify mirror)
			)
		)
		(property "Val" "100n"
			(at 263.92 193.22 0)
			(layer "B.Fab")
			(hide yes)
			(effects
				(font
					(size 1 1)
					(thickness 0.15)
				)
				(justify mirror)
			)
		)
		(property "Voltage" ""
			(at 263.92 193.22 0)
			(layer "B.Fab")
			(hide yes)
			(effects
				(font
					(size 1 1)
					(thickness 0.15)
				)
				(justify mirror)
			)
		)
		(property "Public" "False"
			(at 0 0 180)
			(unlocked yes)
			(layer "B.Fab")
			(hide yes)
			(effects
				(font
					(size 1 1)
					(thickness 0.15)
				)
				(justify mirror)
			)
		)
		(sheetname "/FPGA Power/")
		(sheetfile "FPGA_Power.kicad_sch")
		(attr smd)
		(fp_rect
			(start -0.7 0.35)
			(end 0.7 -0.35)
			(stroke
				(width 0.05)
				(type default)
			)
			(fill no)
			(layer "B.CrtYd")
		)
		(fp_rect
			(start 0.3 -0.15)
			(end -0.301 0.149)
			(stroke
				(width 0.15)
				(type solid)
			)
			(fill no)
			(layer "B.Fab")
		)
		(fp_text user "${REFERENCE}"
			(at -0.72 -3.4 0)
			(layer "B.Fab")
			(effects
				(font
					(size 0.7 0.7)
					(thickness 0.15)
				)
				(justify left bottom mirror)
			)
		)
		(fp_text user "Author: Antmicro"
			(at -0.72 -5.4 0)
			(layer "B.Fab")
			(effects
				(font
					(size 0.7 0.7)
					(thickness 0.15)
				)
				(justify left bottom mirror)
			)
		)
		(fp_text user "License: Apache-2.0"
			(at -0.72 -4.4 0)
			(layer "B.Fab")
			(effects
				(font
					(size 0.7 0.7)
					(thickness 0.15)
				)
				(justify left bottom mirror)
			)
		)
		(pad "" smd roundrect
			(at -0.349 0.002 180)
			(size 0.318 0.36)
			(layers "B.Paste")
			(roundrect_rratio 0.25)
		)
		(pad "" smd roundrect
			(at 0.341 0.002 180)
			(size 0.318 0.36)
			(layers "B.Paste")
			(roundrect_rratio 0.25)
		)
		(pad "1" smd roundrect
			(at -0.321 0.002 180)
			(size 0.46 0.4)
			(layers "B.Cu" "B.Mask")
			(roundrect_rratio 0.25)
			(net 1 "GND")
			(pintype "passive")
		)
		(pad "2" smd roundrect
			(at 0.32 0.002 180)
			(size 0.46 0.4)
			(layers "B.Cu" "B.Mask")
			(roundrect_rratio 0.25)
			(net 13 "/FPGA Power/VCC_PLLDPHY")
			(pintype "passive")
		)
	)
	(footprint "antmicro-footprints:R_0402_1005Metric"
		(layer "B.Cu")
		(at 94.255 94.25 180)
		(descr "Resistor SMD 0402")
		(tags "resistor SMD 0402")
		(property "Reference" "R137"
			(at 1.025 -0.29 0)
			(layer "B.SilkS")
			(effects
				(font
					(size 0.65 0.65)
					(thickness 0.15)
				)
				(justify left bottom mirror)
			)
		)
		(property "Value" "R_1k_0402"
			(at 0 -1.4 0)
			(layer "B.Fab")
			(hide yes)
			(effects
				(font
					(size 0.7 0.7)
					(thickness 0.15)
				)
				(justify left bottom mirror)
			)
		)
		(property "Datasheet" "https://www.bourns.com/docs/product-datasheets/cr.pdf"
			(at 0 0 180)
			(layer "F.Fab")
			(hide yes)
			(effects
				(font
					(size 1.27 1.27)
					(thickness 0.15)
				)
			)
		)
		(property "Description" "SMD Chip Resistor, 1 kohm, ± 1%, 63 mW, 0402 [1005 Metric], Thick Film, General Purpose"
			(at 0 0 180)
			(layer "F.Fab")
			(hide yes)
			(effects
				(font
					(size 1.27 1.27)
					(thickness 0.15)
				)
			)
		)
		(property "Author" "Antmicro"
			(at 188.51 188.5 0)
			(layer "B.Fab")
			(hide yes)
			(effects
				(font
					(size 1 1)
					(thickness 0.15)
				)
				(justify mirror)
			)
		)
		(property "License" "Apache-2.0"
			(at 188.51 188.5 0)
			(layer "B.Fab")
			(hide yes)
			(effects
				(font
					(size 1 1)
					(thickness 0.15)
				)
				(justify mirror)
			)
		)
		(property "MPN" "CR0402-FX-1001GLF"
			(at 188.51 188.5 0)
			(layer "B.Fab")
			(hide yes)
			(effects
				(font
					(size 1 1)
					(thickness 0.15)
				)
				(justify mirror)
			)
		)
		(property "Manufacturer" "Bourns"
			(at 188.51 188.5 0)
			(layer "B.Fab")
			(hide yes)
			(effects
				(font
					(size 1 1)
					(thickness 0.15)
				)
				(justify mirror)
			)
		)
		(property "Tolerance" "1%"
			(at 188.51 188.5 0)
			(layer "B.Fab")
			(hide yes)
			(effects
				(font
					(size 1 1)
					(thickness 0.15)
				)
				(justify mirror)
			)
		)
		(property "Val" "1k"
			(at 188.51 188.5 0)
			(layer "B.Fab")
			(hide yes)
			(effects
				(font
					(size 1 1)
					(thickness 0.15)
				)
				(justify mirror)
			)
		)
		(sheetname "/SDI/")
		(sheetfile "sdi.kicad_sch")
		(attr smd)
		(fp_rect
			(start -0.925 0.47)
			(end 0.925 -0.47)
			(stroke
				(width 0.05)
				(type default)
			)
			(fill no)
			(layer "B.CrtYd")
		)
		(fp_rect
			(start -0.5 0.25)
			(end 0.5 -0.25)
			(stroke
				(width 0.15)
				(type solid)
			)
			(fill no)
			(layer "B.Fab")
		)
		(fp_text user "${REFERENCE}"
			(at -0.95 -3.168 0)
			(layer "B.Fab")
			(effects
				(font
					(size 0.7 0.7)
					(thickness 0.15)
				)
				(justify left bottom mirror)
			)
		)
		(fp_text user "Author: Antmicro"
			(at -0.95 -4.169 0)
			(layer "B.Fab")
			(effects
				(font
					(size 0.7 0.7)
					(thickness 0.15)
				)
				(justify left bottom mirror)
			)
		)
		(fp_text user "License: Apache-2.0"
			(at -0.95 -5.169 0)
			(layer "B.Fab")
			(effects
				(font
					(size 0.7 0.7)
					(thickness 0.15)
				)
				(justify left bottom mirror)
			)
		)
		(pad "1" smd roundrect
			(at -0.48 0 180)
			(size 0.59 0.64)
			(layers "B.Cu" "B.Mask" "B.Paste")
			(roundrect_rratio 0.25)
			(net 200 "/SDI/20bit{slash}~{10bit}")
			(pintype "passive")
		)
		(pad "2" smd roundrect
			(at 0.48 0 180)
			(size 0.59 0.64)
			(layers "B.Cu" "B.Mask" "B.Paste")
			(roundrect_rratio 0.25)
			(net 2 "+3V3")
			(pintype "passive")
		)
	)
	(footprint "antmicro-footprints:C_0201"
		(layer "B.Cu")
		(at 129.9 89.9 -135)
		(descr "Capacitor SMD 0201")
		(tags "capacitor SMD 0201")
		(property "Reference" "C65"
			(at -3.129468 15.107857 45)
			(layer "B.SilkS")
			(effects
				(font
					(size 0.65 0.65)
					(thickness 0.15)
				)
				(justify left bottom mirror)
			)
		)
		(property "Value" "C_100n_0201"
			(at 0 -1.399999 45)
			(layer "B.Fab")
			(hide yes)
			(effects
				(font
					(size 0.7 0.7)
					(thickness 0.15)
				)
				(justify left bottom mirror)
			)
		)
		(property "Datasheet" "https://www.yageo.com/en/Chart/Download/pdf/CC0201KRX6S5BB104"
			(at 0 0 225)
			(layer "F.Fab")
			(hide yes)
			(effects
				(font
					(size 1.27 1.27)
					(thickness 0.15)
				)
			)
		)
		(property "Description" "SMD Multilayer Ceramic Capacitor, 0.1 µF, 6.3 V, 0201 [0603 Metric], ± 10%, X6S, CC Series"
			(at 0 0 225)
			(layer "F.Fab")
			(hide yes)
			(effects
				(font
					(size 1.27 1.27)
					(thickness 0.15)
				)
			)
		)
		(property "Author" "Antmicro"
			(at 158.184271 245.322071 0)
			(layer "B.Fab")
			(hide yes)
			(effects
				(font
					(size 1 1)
					(thickness 0.15)
				)
				(justify mirror)
			)
		)
		(property "Dielectric" ""
			(at 158.184271 245.322071 0)
			(layer "B.Fab")
			(hide yes)
			(effects
				(font
					(size 1 1)
					(thickness 0.15)
				)
				(justify mirror)
			)
		)
		(property "License" "Apache-2.0"
			(at 158.184271 245.322071 0)
			(layer "B.Fab")
			(hide yes)
			(effects
				(font
					(size 1 1)
					(thickness 0.15)
				)
				(justify mirror)
			)
		)
		(property "MPN" "CC0201KRX6S5BB104"
			(at 158.184271 245.322071 0)
			(layer "B.Fab")
			(hide yes)
			(effects
				(font
					(size 1 1)
					(thickness 0.15)
				)
				(justify mirror)
			)
		)
		(property "Manufacturer" "YAGEO"
			(at 158.184271 245.322071 0)
			(layer "B.Fab")
			(hide yes)
			(effects
				(font
					(size 1 1)
					(thickness 0.15)
				)
				(justify mirror)
			)
		)
		(property "Val" "100n"
			(at 158.184271 245.322071 0)
			(layer "B.Fab")
			(hide yes)
			(effects
				(font
					(size 1 1)
					(thickness 0.15)
				)
				(justify mirror)
			)
		)
		(property "Voltage" ""
			(at 158.184271 245.322071 0)
			(layer "B.Fab")
			(hide yes)
			(effects
				(font
					(size 1 1)
					(thickness 0.15)
				)
				(justify mirror)
			)
		)
		(property "Public" "False"
			(at 0 0 225)
			(unlocked yes)
			(layer "B.Fab")
			(hide yes)
			(effects
				(font
					(size 1 1)
					(thickness 0.15)
				)
				(justify mirror)
			)
		)
		(sheetname "/SDI/")
		(sheetfile "sdi.kicad_sch")
		(attr smd)
		(fp_poly
			(pts
				(xy -0.7 0.35) (xy 0.7 0.35) (xy 0.7 -0.35) (xy -0.7 -0.35)
			)
			(stroke
				(width 0.05)
				(type default)
			)
			(fill no)
			(layer "B.CrtYd")
		)
		(fp_poly
			(pts
				(xy 0.3 -0.15) (xy -0.301 -0.15) (xy -0.301 0.149) (xy 0.3 0.149)
			)
			(stroke
				(width 0.15)
				(type solid)
			)
			(fill no)
			(layer "B.Fab")
		)
		(fp_text user "License: Apache-2.0"
			(at -0.72 -4.4 45)
			(layer "B.Fab")
			(effects
				(font
					(size 0.7 0.7)
					(thickness 0.15)
				)
				(justify left bottom mirror)
			)
		)
		(fp_text user "Author: Antmicro"
			(at -0.72 -5.400001 45)
			(layer "B.Fab")
			(effects
				(font
					(size 0.7 0.7)
					(thickness 0.15)
				)
				(justify left bottom mirror)
			)
		)
		(fp_text user "${REFERENCE}"
			(at -0.72 -3.4 45)
			(layer "B.Fab")
			(effects
				(font
					(size 0.7 0.7)
					(thickness 0.15)
				)
				(justify left bottom mirror)
			)
		)
		(pad "" smd roundrect
			(at -0.349 0.002 225)
			(size 0.318 0.36)
			(layers "B.Paste")
			(roundrect_rratio 0.25)
		)
		(pad "" smd roundrect
			(at 0.341 0.002 225)
			(size 0.318 0.36)
			(layers "B.Paste")
			(roundrect_rratio 0.25)
		)
		(pad "1" smd roundrect
			(at -0.321 0.002 225)
			(size 0.46 0.4)
			(layers "B.Cu" "B.Mask")
			(roundrect_rratio 0.25)
			(net 1 "GND")
			(pintype "passive")
		)
		(pad "2" smd roundrect
			(at 0.32 0.002 225)
			(size 0.46 0.4)
			(layers "B.Cu" "B.Mask")
			(roundrect_rratio 0.25)
			(net 2 "+3V3")
			(pintype "passive")
		)
	)
	(footprint "antmicro-footprints:C_0402_1005Metric"
		(layer "B.Cu")
		(at 90.56 72.11 90)
		(descr "Capacitor SMD 0402")
		(tags "capacitor SMD 0402")
		(property "Reference" "C57"
			(at -1.03 -0.63 90)
			(layer "B.SilkS")
			(effects
				(font
					(size 0.65 0.65)
					(thickness 0.15)
				)
				(justify right bottom mirror)
			)
		)
		(property "Value" "C_1u_0402"
			(at 0 -1.4 90)
			(layer "B.Fab")
			(hide yes)
			(effects
				(font
					(size 0.7 0.7)
					(thickness 0.15)
				)
				(justify right bottom mirror)
			)
		)
		(property "Datasheet" "https://product.tdk.com/en/search/capacitor/ceramic/mlcc/info?part_no=C1005X6S1A105K050BC"
			(at 0 0 90)
			(layer "F.Fab")
			(hide yes)
			(effects
				(font
					(size 1.27 1.27)
					(thickness 0.15)
				)
			)
		)
		(property "Description" "SMD Multilayer Ceramic Capacitor, 1 µF, 10 V, 0402 [1005 Metric], ± 10%, X6S, C"
			(at 0 0 90)
			(layer "F.Fab")
			(hide yes)
			(effects
				(font
					(size 1.27 1.27)
					(thickness 0.15)
				)
			)
		)
		(property "Author" "Antmicro"
			(at 162.67 -18.45 0)
			(layer "B.Fab")
			(hide yes)
			(effects
				(font
					(size 1 1)
					(thickness 0.15)
				)
				(justify mirror)
			)
		)
		(property "Dielectric" ""
			(at 162.67 -18.45 0)
			(layer "B.Fab")
			(hide yes)
			(effects
				(font
					(size 1 1)
					(thickness 0.15)
				)
				(justify mirror)
			)
		)
		(property "License" "Apache-2.0"
			(at 162.67 -18.45 0)
			(layer "B.Fab")
			(hide yes)
			(effects
				(font
					(size 1 1)
					(thickness 0.15)
				)
				(justify mirror)
			)
		)
		(property "MPN" "C1005X6S1A105K050BC"
			(at 162.67 -18.45 0)
			(layer "B.Fab")
			(hide yes)
			(effects
				(font
					(size 1 1)
					(thickness 0.15)
				)
				(justify mirror)
			)
		)
		(property "Manufacturer" "TDK"
			(at 162.67 -18.45 0)
			(layer "B.Fab")
			(hide yes)
			(effects
				(font
					(size 1 1)
					(thickness 0.15)
				)
				(justify mirror)
			)
		)
		(property "Val" "1u"
			(at 162.67 -18.45 0)
			(layer "B.Fab")
			(hide yes)
			(effects
				(font
					(size 1 1)
					(thickness 0.15)
				)
				(justify mirror)
			)
		)
		(property "Voltage" ""
			(at 162.67 -18.45 0)
			(layer "B.Fab")
			(hide yes)
			(effects
				(font
					(size 1 1)
					(thickness 0.15)
				)
				(justify mirror)
			)
		)
		(sheetname "/SDI/")
		(sheetfile "sdi.kicad_sch")
		(attr smd)
		(fp_rect
			(start -0.925 0.47)
			(end 0.925 -0.47)
			(stroke
				(width 0.05)
				(type default)
			)
			(fill no)
			(layer "B.CrtYd")
		)
		(fp_line
			(start 0.504 -0.248)
			(end -0.494 -0.248)
			(stroke
				(width 0.15)
				(type solid)
			)
			(layer "B.Fab")
		)
		(fp_line
			(start -0.494 -0.248)
			(end -0.494 0.25)
			(stroke
				(width 0.15)
				(type solid)
			)
			(layer "B.Fab")
		)
		(fp_line
			(start 0.504 0.25)
			(end 0.504 -0.248)
			(stroke
				(width 0.15)
				(type solid)
			)
			(layer "B.Fab")
		)
		(fp_line
			(start -0.494 0.25)
			(end 0.504 0.25)
			(stroke
				(width 0.15)
				(type solid)
			)
			(layer "B.Fab")
		)
		(fp_text user "License: Apache-2.0"
			(at -0.939 -5.799 270)
			(layer "B.Fab")
			(effects
				(font
					(size 0.7 0.7)
					(thickness 0.15)
				)
				(justify left bottom mirror)
			)
		)
		(fp_text user "Author: Antmicro"
			(at -0.939 -3.399 270)
			(layer "B.Fab")
			(effects
				(font
					(size 0.7 0.7)
					(thickness 0.15)
				)
				(justify left bottom mirror)
			)
		)
		(fp_text user "${REFERENCE}"
			(at -0.939 -4.599 270)
			(layer "B.Fab")
			(effects
				(font
					(size 0.7 0.7)
					(thickness 0.15)
				)
				(justify left bottom mirror)
			)
		)
		(pad "1" smd roundrect
			(at -0.48 0 90)
			(size 0.59 0.64)
			(layers "B.Cu" "B.Mask" "B.Paste")
			(roundrect_rratio 0.25)
			(net 242 "Net-(U15B-VBG)")
			(pintype "passive")
		)
		(pad "2" smd roundrect
			(at 0.48 0 90)
			(size 0.59 0.64)
			(layers "B.Cu" "B.Mask" "B.Paste")
			(roundrect_rratio 0.25)
			(net 1 "GND")
			(pintype "passive")
		)
	)
	(footprint "antmicro-footprints:C_0402_1005Metric"
		(layer "B.Cu")
		(at 136.58 59.2 -90)
		(descr "Capacitor SMD 0402")
		(tags "capacitor SMD 0402")
		(property "Reference" "C3"
			(at -0.66 0.7 90)
			(layer "B.SilkS")
			(effects
				(font
					(size 0.65 0.65)
					(thickness 0.15)
				)
				(justify left bottom mirror)
			)
		)
		(property "Value" "C_100n_0402"
			(at 0 -1.4 90)
			(layer "B.Fab")
			(hide yes)
			(effects
				(font
					(size 0.7 0.7)
					(thickness 0.15)
				)
				(justify left bottom mirror)
			)
		)
		(property "Datasheet" "https://www.murata.com/products/productdetail?partno=GRM155R61H104KE14%23"
			(at 0 0 270)
			(layer "F.Fab")
			(hide yes)
			(effects
				(font
					(size 1.27 1.27)
					(thickness 0.15)
				)
			)
		)
		(property "Description" "SMD Multilayer Ceramic Capacitor, 0.1 µF, 50 V, 0402 [1005 Metric], ± 10%, X5R, GRM Series"
			(at 0 0 270)
			(layer "F.Fab")
			(hide yes)
			(effects
				(font
					(size 1.27 1.27)
					(thickness 0.15)
				)
			)
		)
		(property "Author" "Antmicro"
			(at 77.38 195.78 0)
			(layer "B.Fab")
			(hide yes)
			(effects
				(font
					(size 1 1)
					(thickness 0.15)
				)
				(justify mirror)
			)
		)
		(property "Dielectric" "X5R"
			(at 77.38 195.78 0)
			(layer "B.Fab")
			(hide yes)
			(effects
				(font
					(size 1 1)
					(thickness 0.15)
				)
				(justify mirror)
			)
		)
		(property "License" "Apache-2.0"
			(at 77.38 195.78 0)
			(layer "B.Fab")
			(hide yes)
			(effects
				(font
					(size 1 1)
					(thickness 0.15)
				)
				(justify mirror)
			)
		)
		(property "MPN" "GRM155R61H104KE14D"
			(at 77.38 195.78 0)
			(layer "B.Fab")
			(hide yes)
			(effects
				(font
					(size 1 1)
					(thickness 0.15)
				)
				(justify mirror)
			)
		)
		(property "Manufacturer" "Murata"
			(at 77.38 195.78 0)
			(layer "B.Fab")
			(hide yes)
			(effects
				(font
					(size 1 1)
					(thickness 0.15)
				)
				(justify mirror)
			)
		)
		(property "Val" "100n"
			(at 77.38 195.78 0)
			(layer "B.Fab")
			(hide yes)
			(effects
				(font
					(size 1 1)
					(thickness 0.15)
				)
				(justify mirror)
			)
		)
		(property "Voltage" "50V"
			(at 77.38 195.78 0)
			(layer "B.Fab")
			(hide yes)
			(effects
				(font
					(size 1 1)
					(thickness 0.15)
				)
				(justify mirror)
			)
		)
		(sheetname "/Power Supply/")
		(sheetfile "supply.kicad_sch")
		(attr smd)
		(fp_rect
			(start -0.925 0.47)
			(end 0.925 -0.47)
			(stroke
				(width 0.05)
				(type default)
			)
			(fill no)
			(layer "B.CrtYd")
		)
		(fp_line
			(start -0.494 0.25)
			(end 0.504 0.25)
			(stroke
				(width 0.15)
				(type solid)
			)
			(layer "B.Fab")
		)
		(fp_line
			(start 0.504 0.25)
			(end 0.504 -0.248)
			(stroke
				(width 0.15)
				(type solid)
			)
			(layer "B.Fab")
		)
		(fp_line
			(start -0.494 -0.248)
			(end -0.494 0.25)
			(stroke
				(width 0.15)
				(type solid)
			)
			(layer "B.Fab")
		)
		(fp_line
			(start 0.504 -0.248)
			(end -0.494 -0.248)
			(stroke
				(width 0.15)
				(type solid)
			)
			(layer "B.Fab")
		)
		(fp_text user "Author: Antmicro"
			(at -0.939 -3.399 90)
			(layer "B.Fab")
			(effects
				(font
					(size 0.7 0.7)
					(thickness 0.15)
				)
				(justify left bottom mirror)
			)
		)
		(fp_text user "License: Apache-2.0"
			(at -0.939 -5.799 90)
			(layer "B.Fab")
			(effects
				(font
					(size 0.7 0.7)
					(thickness 0.15)
				)
				(justify left bottom mirror)
			)
		)
		(fp_text user "${REFERENCE}"
			(at -0.939 -4.599 90)
			(layer "B.Fab")
			(effects
				(font
					(size 0.7 0.7)
					(thickness 0.15)
				)
				(justify left bottom mirror)
			)
		)
		(pad "1" smd roundrect
			(at -0.48 0 270)
			(size 0.59 0.64)
			(layers "B.Cu" "B.Mask" "B.Paste")
			(roundrect_rratio 0.25)
			(net 30 "Net-(U1-REF)")
			(pintype "passive")
		)
		(pad "2" smd roundrect
			(at 0.48 0 270)
			(size 0.59 0.64)
			(layers "B.Cu" "B.Mask" "B.Paste")
			(roundrect_rratio 0.25)
			(net 1 "GND")
			(pintype "passive")
		)
	)
	(footprint "antmicro-footprints:C_0201"
		(layer "B.Cu")
		(at 133.3 84.4 -135)
		(descr "Capacitor SMD 0201")
		(tags "capacitor SMD 0201")
		(property "Reference" "C37"
			(at -1.053589 -1.393 45)
			(layer "B.SilkS")
			(effects
				(font
					(size 0.65 0.65)
					(thickness 0.15)
				)
				(justify left bottom mirror)
			)
		)
		(property "Value" "C_100n_0201"
			(at 0 -1.399999 45)
			(layer "B.Fab")
			(hide yes)
			(effects
				(font
					(size 0.7 0.7)
					(thickness 0.15)
				)
				(justify left bottom mirror)
			)
		)
		(property "Datasheet" "https://www.yageo.com/en/Chart/Download/pdf/CC0201KRX6S5BB104"
			(at 0 0 225)
			(layer "F.Fab")
			(hide yes)
			(effects
				(font
					(size 1.27 1.27)
					(thickness 0.15)
				)
			)
		)
		(property "Description" "SMD Multilayer Ceramic Capacitor, 0.1 µF, 6.3 V, 0201 [0603 Metric], ± 10%, X6S, CC Series"
			(at 0 0 225)
			(layer "F.Fab")
			(hide yes)
			(effects
				(font
					(size 1.27 1.27)
					(thickness 0.15)
				)
			)
		)
		(property "Author" "Antmicro"
			(at 167.877522 238.337146 0)
			(layer "B.Fab")
			(hide yes)
			(effects
				(font
					(size 1 1)
					(thickness 0.15)
				)
				(justify mirror)
			)
		)
		(property "Dielectric" ""
			(at 167.877522 238.337146 0)
			(layer "B.Fab")
			(hide yes)
			(effects
				(font
					(size 1 1)
					(thickness 0.15)
				)
				(justify mirror)
			)
		)
		(property "License" "Apache-2.0"
			(at 167.877522 238.337146 0)
			(layer "B.Fab")
			(hide yes)
			(effects
				(font
					(size 1 1)
					(thickness 0.15)
				)
				(justify mirror)
			)
		)
		(property "MPN" "CC0201KRX6S5BB104"
			(at 167.877522 238.337146 0)
			(layer "B.Fab")
			(hide yes)
			(effects
				(font
					(size 1 1)
					(thickness 0.15)
				)
				(justify mirror)
			)
		)
		(property "Manufacturer" "YAGEO"
			(at 167.877522 238.337146 0)
			(layer "B.Fab")
			(hide yes)
			(effects
				(font
					(size 1 1)
					(thickness 0.15)
				)
				(justify mirror)
			)
		)
		(property "Val" "100n"
			(at 167.877522 238.337146 0)
			(layer "B.Fab")
			(hide yes)
			(effects
				(font
					(size 1 1)
					(thickness 0.15)
				)
				(justify mirror)
			)
		)
		(property "Voltage" ""
			(at 167.877522 238.337146 0)
			(layer "B.Fab")
			(hide yes)
			(effects
				(font
					(size 1 1)
					(thickness 0.15)
				)
				(justify mirror)
			)
		)
		(property "Public" "False"
			(at 0 0 225)
			(unlocked yes)
			(layer "B.Fab")
			(hide yes)
			(effects
				(font
					(size 1 1)
					(thickness 0.15)
				)
				(justify mirror)
			)
		)
		(sheetname "/DDR3/")
		(sheetfile "ddr3.kicad_sch")
		(attr smd)
		(fp_poly
			(pts
				(xy -0.7 0.35) (xy 0.7 0.35) (xy 0.7 -0.35) (xy -0.7 -0.35)
			)
			(stroke
				(width 0.05)
				(type default)
			)
			(fill no)
			(layer "B.CrtYd")
		)
		(fp_poly
			(pts
				(xy 0.3 -0.15) (xy -0.301 -0.15) (xy -0.301 0.149) (xy 0.3 0.149)
			)
			(stroke
				(width 0.15)
				(type solid)
			)
			(fill no)
			(layer "B.Fab")
		)
		(fp_text user "Author: Antmicro"
			(at -0.72 -5.400001 45)
			(layer "B.Fab")
			(effects
				(font
					(size 0.7 0.7)
					(thickness 0.15)
				)
				(justify left bottom mirror)
			)
		)
		(fp_text user "License: Apache-2.0"
			(at -0.72 -4.4 45)
			(layer "B.Fab")
			(effects
				(font
					(size 0.7 0.7)
					(thickness 0.15)
				)
				(justify left bottom mirror)
			)
		)
		(fp_text user "${REFERENCE}"
			(at -0.72 -3.4 45)
			(layer "B.Fab")
			(effects
				(font
					(size 0.7 0.7)
					(thickness 0.15)
				)
				(justify left bottom mirror)
			)
		)
		(pad "" smd roundrect
			(at -0.349 0.002 225)
			(size 0.318 0.36)
			(layers "B.Paste")
			(roundrect_rratio 0.25)
		)
		(pad "" smd roundrect
			(at 0.341 0.002 225)
			(size 0.318 0.36)
			(layers "B.Paste")
			(roundrect_rratio 0.25)
		)
		(pad "1" smd roundrect
			(at -0.321 0.002 225)
			(size 0.46 0.4)
			(layers "B.Cu" "B.Mask")
			(roundrect_rratio 0.25)
			(net 5 "Vref")
			(pintype "passive")
		)
		(pad "2" smd roundrect
			(at 0.32 0.002 225)
			(size 0.46 0.4)
			(layers "B.Cu" "B.Mask")
			(roundrect_rratio 0.25)
			(net 248 "+1V5")
			(pintype "passive")
		)
	)
	(footprint "antmicro-footprints:R_0201"
		(layer "B.Cu")
		(at 122.59 64.51 -90)
		(descr "Resistor SMD 0201")
		(tags "resistor SMD 0201")
		(property "Reference" "R43"
			(at -0.67 0.5 90)
			(layer "B.SilkS")
			(effects
				(font
					(size 0.65 0.65)
					(thickness 0.15)
				)
				(justify left bottom mirror)
			)
		)
		(property "Value" "R_100R_0201"
			(at 0 -1.25 90)
			(layer "B.Fab")
			(hide yes)
			(effects
				(font
					(size 0.7 0.7)
					(thickness 0.15)
				)
				(justify left bottom mirror)
			)
		)
		(property "Datasheet" "https://www.bourns.com/docs/product-datasheets/cr-a-as.pdf"
			(at 0 0 90)
			(layer "F.Fab")
			(hide yes)
			(effects
				(font
					(size 1.27 1.27)
					(thickness 0.15)
				)
			)
		)
		(property "Description" "SMD Chip Resistor, 100 ohm, ± 1%, 50 mW, 0201 [0603 Metric], Thick Film, Sulfur Resistant"
			(at 0 0 90)
			(layer "F.Fab")
			(hide yes)
			(effects
				(font
					(size 1.27 1.27)
					(thickness 0.15)
				)
			)
		)
		(property "Author" "Antmicro"
			(at 58.08 187.1 0)
			(layer "B.Fab")
			(hide yes)
			(effects
				(font
					(size 1 1)
					(thickness 0.15)
				)
				(justify mirror)
			)
		)
		(property "License" "Apache-2.0"
			(at 58.08 187.1 0)
			(layer "B.Fab")
			(hide yes)
			(effects
				(font
					(size 1 1)
					(thickness 0.15)
				)
				(justify mirror)
			)
		)
		(property "MPN" "CR0201AFW-1000GAS"
			(at 58.08 187.1 0)
			(layer "B.Fab")
			(hide yes)
			(effects
				(font
					(size 1 1)
					(thickness 0.15)
				)
				(justify mirror)
			)
		)
		(property "Manufacturer" "Bourns"
			(at 58.08 187.1 0)
			(layer "B.Fab")
			(hide yes)
			(effects
				(font
					(size 1 1)
					(thickness 0.15)
				)
				(justify mirror)
			)
		)
		(property "Tolerance" "1%"
			(at 58.08 187.1 0)
			(layer "B.Fab")
			(hide yes)
			(effects
				(font
					(size 1 1)
					(thickness 0.15)
				)
				(justify mirror)
			)
		)
		(property "Val" "100R"
			(at 58.08 187.1 0)
			(layer "B.Fab")
			(hide yes)
			(effects
				(font
					(size 1 1)
					(thickness 0.15)
				)
				(justify mirror)
			)
		)
		(sheetname "/DDR3/")
		(sheetfile "ddr3.kicad_sch")
		(attr smd)
		(fp_rect
			(start -0.7 0.35)
			(end 0.7 -0.35)
			(stroke
				(width 0.05)
				(type default)
			)
			(fill no)
			(layer "B.CrtYd")
		)
		(fp_rect
			(start -0.3 0.15)
			(end 0.298 -0.148)
			(stroke
				(width 0.15)
				(type solid)
			)
			(fill no)
			(layer "B.Fab")
		)
		(fp_text user "License: Apache-2.0"
			(at -0.71 -4.25 90)
			(layer "B.Fab")
			(effects
				(font
					(size 0.7 0.7)
					(thickness 0.15)
				)
				(justify left bottom mirror)
			)
		)
		(fp_text user "Author: Antmicro"
			(at -0.71 -5.25 90)
			(layer "B.Fab")
			(effects
				(font
					(size 0.7 0.7)
					(thickness 0.15)
				)
				(justify left bottom mirror)
			)
		)
		(fp_text user "${REFERENCE}"
			(at -0.71 -3.25 90)
			(layer "B.Fab")
			(effects
				(font
					(size 0.7 0.7)
					(thickness 0.15)
				)
				(justify left bottom mirror)
			)
		)
		(pad "" smd roundrect
			(at -0.346 0 270)
			(size 0.318 0.36)
			(layers "B.Paste")
			(roundrect_rratio 0.25)
		)
		(pad "" smd roundrect
			(at 0.344 0 270)
			(size 0.318 0.36)
			(layers "B.Paste")
			(roundrect_rratio 0.25)
		)
		(pad "1" smd roundrect
			(at -0.32 0 270)
			(size 0.46 0.4)
			(layers "B.Cu" "B.Mask")
			(roundrect_rratio 0.25)
			(net 142 "/DDR3/DDR3_CK_N")
			(pintype "passive")
		)
		(pad "2" smd roundrect
			(at 0.32 0 270)
			(size 0.46 0.4)
			(layers "B.Cu" "B.Mask")
			(roundrect_rratio 0.25)
			(net 143 "/DDR3/DDR3_CK_P")
			(pintype "passive")
		)
	)
	(footprint "antmicro-footprints:C_0402_1005Metric"
		(layer "B.Cu")
		(at 144.2 81.5 90)
		(descr "Capacitor SMD 0402")
		(tags "capacitor SMD 0402")
		(property "Reference" "C117"
			(at 0.96 0.33 90)
			(layer "B.SilkS")
			(effects
				(font
					(size 0.65 0.65)
					(thickness 0.15)
				)
				(justify right bottom mirror)
			)
		)
		(property "Value" "C_47p_0402"
			(at 0 -1.4 90)
			(layer "B.Fab")
			(hide yes)
			(effects
				(font
					(size 0.7 0.7)
					(thickness 0.15)
				)
				(justify right bottom mirror)
			)
		)
		(property "Datasheet" "https://www.kemet.com/en/us/capacitors/product/C0402C470J5GACTU.html"
			(at 0 0 90)
			(layer "F.Fab")
			(hide yes)
			(effects
				(font
					(size 1.27 1.27)
					(thickness 0.15)
				)
			)
		)
		(property "Description" "SMD Multilayer Ceramic Capacitor, 47 pF, 50 V, 0402 [1005 Metric], ± 5%, C0G / NP0, C Series KEMET"
			(at 0 0 90)
			(layer "F.Fab")
			(hide yes)
			(effects
				(font
					(size 1.27 1.27)
					(thickness 0.15)
				)
			)
		)
		(property "Author" "Antmicro"
			(at 225.7 -62.7 0)
			(layer "B.Fab")
			(hide yes)
			(effects
				(font
					(size 1 1)
					(thickness 0.15)
				)
				(justify mirror)
			)
		)
		(property "Dielectric" "C0G"
			(at 225.7 -62.7 0)
			(layer "B.Fab")
			(hide yes)
			(effects
				(font
					(size 1 1)
					(thickness 0.15)
				)
				(justify mirror)
			)
		)
		(property "License" "Apache-2.0"
			(at 225.7 -62.7 0)
			(layer "B.Fab")
			(hide yes)
			(effects
				(font
					(size 1 1)
					(thickness 0.15)
				)
				(justify mirror)
			)
		)
		(property "MPN" "C0402C470J5GACTU"
			(at 225.7 -62.7 0)
			(layer "B.Fab")
			(hide yes)
			(effects
				(font
					(size 1 1)
					(thickness 0.15)
				)
				(justify mirror)
			)
		)
		(property "Manufacturer" "KEMET"
			(at 225.7 -62.7 0)
			(layer "B.Fab")
			(hide yes)
			(effects
				(font
					(size 1 1)
					(thickness 0.15)
				)
				(justify mirror)
			)
		)
		(property "Val" "47p"
			(at 225.7 -62.7 0)
			(layer "B.Fab")
			(hide yes)
			(effects
				(font
					(size 1 1)
					(thickness 0.15)
				)
				(justify mirror)
			)
		)
		(property "Voltage" ""
			(at 225.7 -62.7 0)
			(layer "B.Fab")
			(hide yes)
			(effects
				(font
					(size 1 1)
					(thickness 0.15)
				)
				(justify mirror)
			)
		)
		(sheetname "/Peripherals/")
		(sheetfile "peripherals.kicad_sch")
		(attr smd)
		(fp_rect
			(start -0.925 0.47)
			(end 0.925 -0.47)
			(stroke
				(width 0.05)
				(type default)
			)
			(fill no)
			(layer "B.CrtYd")
		)
		(fp_line
			(start 0.504 -0.248)
			(end -0.494 -0.248)
			(stroke
				(width 0.15)
				(type solid)
			)
			(layer "B.Fab")
		)
		(fp_line
			(start -0.494 -0.248)
			(end -0.494 0.25)
			(stroke
				(width 0.15)
				(type solid)
			)
			(layer "B.Fab")
		)
		(fp_line
			(start 0.504 0.25)
			(end 0.504 -0.248)
			(stroke
				(width 0.15)
				(type solid)
			)
			(layer "B.Fab")
		)
		(fp_line
			(start -0.494 0.25)
			(end 0.504 0.25)
			(stroke
				(width 0.15)
				(type solid)
			)
			(layer "B.Fab")
		)
		(fp_text user "Author: Antmicro"
			(at -0.939 -3.399 270)
			(layer "B.Fab")
			(effects
				(font
					(size 0.7 0.7)
					(thickness 0.15)
				)
				(justify left bottom mirror)
			)
		)
		(fp_text user "${REFERENCE}"
			(at -0.939 -4.599 270)
			(layer "B.Fab")
			(effects
				(font
					(size 0.7 0.7)
					(thickness 0.15)
				)
				(justify left bottom mirror)
			)
		)
		(fp_text user "License: Apache-2.0"
			(at -0.939 -5.799 270)
			(layer "B.Fab")
			(effects
				(font
					(size 0.7 0.7)
					(thickness 0.15)
				)
				(justify left bottom mirror)
			)
		)
		(pad "1" smd roundrect
			(at -0.48 0 90)
			(size 0.59 0.64)
			(layers "B.Cu" "B.Mask" "B.Paste")
			(roundrect_rratio 0.25)
			(net 1 "GND")
			(pintype "passive")
		)
		(pad "2" smd roundrect
			(at 0.48 0 90)
			(size 0.59 0.64)
			(layers "B.Cu" "B.Mask" "B.Paste")
			(roundrect_rratio 0.25)
			(net 359 "/Peripherals/USB_DP")
			(pintype "passive")
		)
	)
	(footprint "antmicro-footprints:R_0402_1005Metric"
		(layer "B.Cu")
		(at 139.23 59.2 -90)
		(descr "Resistor SMD 0402")
		(tags "resistor SMD 0402")
		(property "Reference" "R7"
			(at -0.76 -1.3 90)
			(layer "B.SilkS")
			(effects
				(font
					(size 0.65 0.65)
					(thickness 0.15)
				)
				(justify left bottom mirror)
			)
		)
		(property "Value" "R_22R_0402"
			(at 0 -1.4 90)
			(layer "B.Fab")
			(hide yes)
			(effects
				(font
					(size 0.7 0.7)
					(thickness 0.15)
				)
				(justify left bottom mirror)
			)
		)
		(property "Datasheet" "https://www.bourns.com/docs/product-datasheets/cr.pdf"
			(at 0 0 270)
			(layer "F.Fab")
			(hide yes)
			(effects
				(font
					(size 1.27 1.27)
					(thickness 0.15)
				)
			)
		)
		(property "Description" "SMD Chip Resistor, 22 ohm, ± 1%, 62.5 mW, 0402 [1005 Metric], Thick Film, General Purpose"
			(at 0 0 270)
			(layer "F.Fab")
			(hide yes)
			(effects
				(font
					(size 1.27 1.27)
					(thickness 0.15)
				)
			)
		)
		(property "Author" "Antmicro"
			(at 80.03 198.43 0)
			(layer "B.Fab")
			(hide yes)
			(effects
				(font
					(size 1 1)
					(thickness 0.15)
				)
				(justify mirror)
			)
		)
		(property "License" "Apache-2.0"
			(at 80.03 198.43 0)
			(layer "B.Fab")
			(hide yes)
			(effects
				(font
					(size 1 1)
					(thickness 0.15)
				)
				(justify mirror)
			)
		)
		(property "MPN" "CR0402-FX-22R0GLF"
			(at 80.03 198.43 0)
			(layer "B.Fab")
			(hide yes)
			(effects
				(font
					(size 1 1)
					(thickness 0.15)
				)
				(justify mirror)
			)
		)
		(property "Manufacturer" "Bourns"
			(at 80.03 198.43 0)
			(layer "B.Fab")
			(hide yes)
			(effects
				(font
					(size 1 1)
					(thickness 0.15)
				)
				(justify mirror)
			)
		)
		(property "Tolerance" "1%"
			(at 80.03 198.43 0)
			(layer "B.Fab")
			(hide yes)
			(effects
				(font
					(size 1 1)
					(thickness 0.15)
				)
				(justify mirror)
			)
		)
		(property "Val" "22R"
			(at 80.03 198.43 0)
			(layer "B.Fab")
			(hide yes)
			(effects
				(font
					(size 1 1)
					(thickness 0.15)
				)
				(justify mirror)
			)
		)
		(sheetname "/Power Supply/")
		(sheetfile "supply.kicad_sch")
		(attr smd)
		(fp_rect
			(start -0.925 0.47)
			(end 0.925 -0.47)
			(stroke
				(width 0.05)
				(type default)
			)
			(fill no)
			(layer "B.CrtYd")
		)
		(fp_rect
			(start -0.5 0.25)
			(end 0.5 -0.25)
			(stroke
				(width 0.15)
				(type solid)
			)
			(fill no)
			(layer "B.Fab")
		)
		(fp_text user "${REFERENCE}"
			(at -0.95 -3.168 90)
			(layer "B.Fab")
			(effects
				(font
					(size 0.7 0.7)
					(thickness 0.15)
				)
				(justify left bottom mirror)
			)
		)
		(fp_text user "Author: Antmicro"
			(at -0.95 -4.169 90)
			(layer "B.Fab")
			(effects
				(font
					(size 0.7 0.7)
					(thickness 0.15)
				)
				(justify left bottom mirror)
			)
		)
		(fp_text user "License: Apache-2.0"
			(at -0.95 -5.169 90)
			(layer "B.Fab")
			(effects
				(font
					(size 0.7 0.7)
					(thickness 0.15)
				)
				(justify left bottom mirror)
			)
		)
		(pad "1" smd roundrect
			(at -0.48 0 270)
			(size 0.59 0.64)
			(layers "B.Cu" "B.Mask" "B.Paste")
			(roundrect_rratio 0.25)
			(net 30 "Net-(U1-REF)")
			(pintype "passive")
		)
		(pad "2" smd roundrect
			(at 0.48 0 270)
			(size 0.59 0.64)
			(layers "B.Cu" "B.Mask" "B.Paste")
			(roundrect_rratio 0.25)
			(net 248 "+1V5")
			(pintype "passive")
		)
	)
	(footprint "antmicro-footprints:C_0201"
		(layer "B.Cu")
		(at 124.7 88.7 -90)
		(descr "Capacitor SMD 0201")
		(tags "capacitor SMD 0201")
		(property "Reference" "C106"
			(at -14.095736 9.07 90)
			(layer "B.SilkS")
			(effects
				(font
					(size 0.65 0.65)
					(thickness 0.15)
				)
				(justify left bottom mirror)
			)
		)
		(property "Value" "C_100n_0201"
			(at 0 -1.4 90)
			(layer "B.Fab")
			(hide yes)
			(effects
				(font
					(size 0.7 0.7)
					(thickness 0.15)
				)
				(justify left bottom mirror)
			)
		)
		(property "Datasheet" "https://www.yageo.com/en/Chart/Download/pdf/CC0201KRX6S5BB104"
			(at 0 0 270)
			(layer "F.Fab")
			(hide yes)
			(effects
				(font
					(size 1.27 1.27)
					(thickness 0.15)
				)
			)
		)
		(property "Description" "SMD Multilayer Ceramic Capacitor, 0.1 µF, 6.3 V, 0201 [0603 Metric], ± 10%, X6S, CC Series"
			(at 0 0 270)
			(layer "F.Fab")
			(hide yes)
			(effects
				(font
					(size 1.27 1.27)
					(thickness 0.15)
				)
			)
		)
		(property "Author" "Antmicro"
			(at 36 213.4 0)
			(layer "B.Fab")
			(hide yes)
			(effects
				(font
					(size 1 1)
					(thickness 0.15)
				)
				(justify mirror)
			)
		)
		(property "Dielectric" ""
			(at 36 213.4 0)
			(layer "B.Fab")
			(hide yes)
			(effects
				(font
					(size 1 1)
					(thickness 0.15)
				)
				(justify mirror)
			)
		)
		(property "License" "Apache-2.0"
			(at 36 213.4 0)
			(layer "B.Fab")
			(hide yes)
			(effects
				(font
					(size 1 1)
					(thickness 0.15)
				)
				(justify mirror)
			)
		)
		(property "MPN" "CC0201KRX6S5BB104"
			(at 36 213.4 0)
			(layer "B.Fab")
			(hide yes)
			(effects
				(font
					(size 1 1)
					(thickness 0.15)
				)
				(justify mirror)
			)
		)
		(property "Manufacturer" "YAGEO"
			(at 36 213.4 0)
			(layer "B.Fab")
			(hide yes)
			(effects
				(font
					(size 1 1)
					(thickness 0.15)
				)
				(justify mirror)
			)
		)
		(property "Val" "100n"
			(at 36 213.4 0)
			(layer "B.Fab")
			(hide yes)
			(effects
				(font
					(size 1 1)
					(thickness 0.15)
				)
				(justify mirror)
			)
		)
		(property "Voltage" ""
			(at 36 213.4 0)
			(layer "B.Fab")
			(hide yes)
			(effects
				(font
					(size 1 1)
					(thickness 0.15)
				)
				(justify mirror)
			)
		)
		(property "Public" "False"
			(at 0 0 270)
			(unlocked yes)
			(layer "B.Fab")
			(hide yes)
			(effects
				(font
					(size 1 1)
					(thickness 0.15)
				)
				(justify mirror)
			)
		)
		(sheetname "/FPGA Power/")
		(sheetfile "FPGA_Power.kicad_sch")
		(attr smd)
		(fp_rect
			(start -0.7 0.35)
			(end 0.7 -0.35)
			(stroke
				(width 0.05)
				(type default)
			)
			(fill no)
			(layer "B.CrtYd")
		)
		(fp_rect
			(start 0.3 -0.15)
			(end -0.301 0.149)
			(stroke
				(width 0.15)
				(type solid)
			)
			(fill no)
			(layer "B.Fab")
		)
		(fp_text user "Author: Antmicro"
			(at -0.72 -5.4 90)
			(layer "B.Fab")
			(effects
				(font
					(size 0.7 0.7)
					(thickness 0.15)
				)
				(justify left bottom mirror)
			)
		)
		(fp_text user "License: Apache-2.0"
			(at -0.72 -4.4 90)
			(layer "B.Fab")
			(effects
				(font
					(size 0.7 0.7)
					(thickness 0.15)
				)
				(justify left bottom mirror)
			)
		)
		(fp_text user "${REFERENCE}"
			(at -0.72 -3.4 90)
			(layer "B.Fab")
			(effects
				(font
					(size 0.7 0.7)
					(thickness 0.15)
				)
				(justify left bottom mirror)
			)
		)
		(pad "" smd roundrect
			(at -0.349 0.002 270)
			(size 0.318 0.36)
			(layers "B.Paste")
			(roundrect_rratio 0.25)
		)
		(pad "" smd roundrect
			(at 0.341 0.002 270)
			(size 0.318 0.36)
			(layers "B.Paste")
			(roundrect_rratio 0.25)
		)
		(pad "1" smd roundrect
			(at -0.321 0.002 270)
			(size 0.46 0.4)
			(layers "B.Cu" "B.Mask")
			(roundrect_rratio 0.25)
			(net 1 "GND")
			(pintype "passive")
		)
		(pad "2" smd roundrect
			(at 0.32 0.002 270)
			(size 0.46 0.4)
			(layers "B.Cu" "B.Mask")
			(roundrect_rratio 0.25)
			(net 9 "/FPGA Power/VCC_AUX")
			(pintype "passive")
		)
	)
	(footprint "antmicro-footprints:TP_SMD_0.75mm"
		(layer "B.Cu")
		(at 96.94 88.2 90)
		(property "Reference" "TP32"
			(at 0.76 0.39 90)
			(layer "B.SilkS")
			(effects
				(font
					(size 0.65 0.65)
					(thickness 0.15)
				)
				(justify right bottom mirror)
			)
		)
		(property "Value" "TP_0.75mm_SMD"
			(at 0 -1.2 90)
			(layer "B.Fab")
			(hide yes)
			(effects
				(font
					(size 0.7 0.7)
					(thickness 0.15)
				)
				(justify right bottom mirror)
			)
		)
		(property "Description" "SMT test point"
			(at 0 0 90)
			(layer "F.Fab")
			(hide yes)
			(effects
				(font
					(size 1.27 1.27)
					(thickness 0.15)
				)
			)
		)
		(property "Author" "Antmicro"
			(at 185.14 -8.74 0)
			(layer "B.Fab")
			(hide yes)
			(effects
				(font
					(size 1 1)
					(thickness 0.15)
				)
				(justify mirror)
			)
		)
		(property "License" "Apache-2.0"
			(at 185.14 -8.74 0)
			(layer "B.Fab")
			(hide yes)
			(effects
				(font
					(size 1 1)
					(thickness 0.15)
				)
				(justify mirror)
			)
		)
		(property "MPN" ""
			(at 185.14 -8.74 0)
			(layer "B.Fab")
			(hide yes)
			(effects
				(font
					(size 1 1)
					(thickness 0.15)
				)
				(justify mirror)
			)
		)
		(property "Manufacturer" ""
			(at 185.14 -8.74 0)
			(layer "B.Fab")
			(hide yes)
			(effects
				(font
					(size 1 1)
					(thickness 0.15)
				)
				(justify mirror)
			)
		)
		(sheetname "/SDI/")
		(sheetfile "sdi.kicad_sch")
		(attr exclude_from_pos_files)
		(fp_circle
			(center 0 0)
			(end 0.475 0)
			(stroke
				(width 0.05)
				(type default)
			)
			(fill no)
			(layer "B.CrtYd")
		)
		(fp_text user "License: Apache-2.0"
			(at -0.4 -5.101 270)
			(layer "B.Fab")
			(effects
				(font
					(size 0.7 0.7)
					(thickness 0.15)
				)
				(justify left bottom mirror)
			)
		)
		(fp_text user "Author: Antmicro"
			(at -0.4 -3.901 270)
			(layer "B.Fab")
			(effects
				(font
					(size 0.7 0.7)
					(thickness 0.15)
				)
				(justify left bottom mirror)
			)
		)
		(fp_text user "${REFERENCE}"
			(at -0.4 -2.7 270)
			(layer "B.Fab")
			(effects
				(font
					(size 0.7 0.7)
					(thickness 0.15)
				)
				(justify left bottom mirror)
			)
		)
		(pad "1" smd circle
			(at 0 0 90)
			(size 0.75 0.75)
			(layers "B.Cu" "B.Mask")
			(net 178 "/SDI/~{CS_TMS}")
			(pinfunction "1")
			(pintype "passive")
		)
	)
	(footprint "antmicro-footprints:C_0402_1005Metric"
		(layer "B.Cu")
		(at 97.15 79.92 90)
		(descr "Capacitor SMD 0402")
		(tags "capacitor SMD 0402")
		(property "Reference" "C68"
			(at -1.02 1.28 90)
			(layer "B.SilkS")
			(effects
				(font
					(size 0.65 0.65)
					(thickness 0.15)
				)
				(justify right bottom mirror)
			)
		)
		(property "Value" "C_100n_0402"
			(at 0 -1.4 90)
			(layer "B.Fab")
			(hide yes)
			(effects
				(font
					(size 0.7 0.7)
					(thickness 0.15)
				)
				(justify right bottom mirror)
			)
		)
		(property "Datasheet" "https://www.murata.com/products/productdetail?partno=GRM155R61H104KE14%23"
			(at 0 0 90)
			(layer "F.Fab")
			(hide yes)
			(effects
				(font
					(size 1.27 1.27)
					(thickness 0.15)
				)
			)
		)
		(property "Description" "SMD Multilayer Ceramic Capacitor, 0.1 µF, 50 V, 0402 [1005 Metric], ± 10%, X5R, GRM Series"
			(at 0 0 90)
			(layer "F.Fab")
			(hide yes)
			(effects
				(font
					(size 1.27 1.27)
					(thickness 0.15)
				)
			)
		)
		(property "Author" "Antmicro"
			(at 177.07 -17.23 0)
			(layer "B.Fab")
			(hide yes)
			(effects
				(font
					(size 1 1)
					(thickness 0.15)
				)
				(justify mirror)
			)
		)
		(property "Dielectric" "X5R"
			(at 177.07 -17.23 0)
			(layer "B.Fab")
			(hide yes)
			(effects
				(font
					(size 1 1)
					(thickness 0.15)
				)
				(justify mirror)
			)
		)
		(property "License" "Apache-2.0"
			(at 177.07 -17.23 0)
			(layer "B.Fab")
			(hide yes)
			(effects
				(font
					(size 1 1)
					(thickness 0.15)
				)
				(justify mirror)
			)
		)
		(property "MPN" "GRM155R61H104KE14D"
			(at 177.07 -17.23 0)
			(layer "B.Fab")
			(hide yes)
			(effects
				(font
					(size 1 1)
					(thickness 0.15)
				)
				(justify mirror)
			)
		)
		(property "Manufacturer" "Murata"
			(at 177.07 -17.23 0)
			(layer "B.Fab")
			(hide yes)
			(effects
				(font
					(size 1 1)
					(thickness 0.15)
				)
				(justify mirror)
			)
		)
		(property "Val" "100n"
			(at 177.07 -17.23 0)
			(layer "B.Fab")
			(hide yes)
			(effects
				(font
					(size 1 1)
					(thickness 0.15)
				)
				(justify mirror)
			)
		)
		(property "Voltage" "50V"
			(at 177.07 -17.23 0)
			(layer "B.Fab")
			(hide yes)
			(effects
				(font
					(size 1 1)
					(thickness 0.15)
				)
				(justify mirror)
			)
		)
		(sheetname "/SDI/")
		(sheetfile "sdi.kicad_sch")
		(attr smd)
		(fp_rect
			(start -0.925 0.47)
			(end 0.925 -0.47)
			(stroke
				(width 0.05)
				(type default)
			)
			(fill no)
			(layer "B.CrtYd")
		)
		(fp_line
			(start 0.504 -0.248)
			(end -0.494 -0.248)
			(stroke
				(width 0.15)
				(type solid)
			)
			(layer "B.Fab")
		)
		(fp_line
			(start -0.494 -0.248)
			(end -0.494 0.25)
			(stroke
				(width 0.15)
				(type solid)
			)
			(layer "B.Fab")
		)
		(fp_line
			(start 0.504 0.25)
			(end 0.504 -0.248)
			(stroke
				(width 0.15)
				(type solid)
			)
			(layer "B.Fab")
		)
		(fp_line
			(start -0.494 0.25)
			(end 0.504 0.25)
			(stroke
				(width 0.15)
				(type solid)
			)
			(layer "B.Fab")
		)
		(fp_text user "${REFERENCE}"
			(at -0.939 -4.599 270)
			(layer "B.Fab")
			(effects
				(font
					(size 0.7 0.7)
					(thickness 0.15)
				)
				(justify left bottom mirror)
			)
		)
		(fp_text user "Author: Antmicro"
			(at -0.939 -3.399 270)
			(layer "B.Fab")
			(effects
				(font
					(size 0.7 0.7)
					(thickness 0.15)
				)
				(justify left bottom mirror)
			)
		)
		(fp_text user "License: Apache-2.0"
			(at -0.939 -5.799 270)
			(layer "B.Fab")
			(effects
				(font
					(size 0.7 0.7)
					(thickness 0.15)
				)
				(justify left bottom mirror)
			)
		)
		(pad "1" smd roundrect
			(at -0.48 0 90)
			(size 0.59 0.64)
			(layers "B.Cu" "B.Mask" "B.Paste")
			(roundrect_rratio 0.25)
			(net 1 "GND")
			(pintype "passive")
		)
		(pad "2" smd roundrect
			(at 0.48 0 90)
			(size 0.59 0.64)
			(layers "B.Cu" "B.Mask" "B.Paste")
			(roundrect_rratio 0.25)
			(net 3 "+1V2")
			(pintype "passive")
		)
	)
	(footprint "antmicro-footprints:R_0402_1005Metric"
		(layer "B.Cu")
		(at 120.37 63.42)
		(descr "Resistor SMD 0402")
		(tags "resistor SMD 0402")
		(property "Reference" "R47"
			(at 0.66 1.32 180)
			(layer "B.SilkS")
			(effects
				(font
					(size 0.65 0.65)
					(thickness 0.15)
				)
				(justify left bottom mirror)
			)
		)
		(property "Value" "R_240R_0402"
			(at 0 -1.4 180)
			(layer "B.Fab")
			(hide yes)
			(effects
				(font
					(size 0.7 0.7)
					(thickness 0.15)
				)
				(justify left bottom mirror)
			)
		)
		(property "Datasheet" "https://www.bourns.com/docs/product-datasheets/cr.pdf"
			(at 0 0 0)
			(layer "F.Fab")
			(hide yes)
			(effects
				(font
					(size 1.27 1.27)
					(thickness 0.15)
				)
			)
		)
		(property "Description" "SMD Chip Resistor, 240 ohm, ± 1%, 63 mW, 0402 [1005 Metric], Thick Film, General Purpose"
			(at 0 0 0)
			(layer "F.Fab")
			(hide yes)
			(effects
				(font
					(size 1.27 1.27)
					(thickness 0.15)
				)
			)
		)
		(property "Author" "Antmicro"
			(at 0 0 0)
			(layer "B.Fab")
			(hide yes)
			(effects
				(font
					(size 1 1)
					(thickness 0.15)
				)
				(justify mirror)
			)
		)
		(property "License" "Apache-2.0"
			(at 0 0 0)
			(layer "B.Fab")
			(hide yes)
			(effects
				(font
					(size 1 1)
					(thickness 0.15)
				)
				(justify mirror)
			)
		)
		(property "MPN" "CR0402-FX-2400GLF"
			(at 0 0 0)
			(layer "B.Fab")
			(hide yes)
			(effects
				(font
					(size 1 1)
					(thickness 0.15)
				)
				(justify mirror)
			)
		)
		(property "Manufacturer" "Bourns"
			(at 0 0 0)
			(layer "B.Fab")
			(hide yes)
			(effects
				(font
					(size 1 1)
					(thickness 0.15)
				)
				(justify mirror)
			)
		)
		(property "Tolerance" "1%"
			(at 0 0 0)
			(layer "B.Fab")
			(hide yes)
			(effects
				(font
					(size 1 1)
					(thickness 0.15)
				)
				(justify mirror)
			)
		)
		(property "Val" "240R"
			(at 0 0 0)
			(layer "B.Fab")
			(hide yes)
			(effects
				(font
					(size 1 1)
					(thickness 0.15)
				)
				(justify mirror)
			)
		)
		(sheetname "/DDR3/")
		(sheetfile "ddr3.kicad_sch")
		(attr smd)
		(fp_rect
			(start -0.925 0.47)
			(end 0.925 -0.47)
			(stroke
				(width 0.05)
				(type default)
			)
			(fill no)
			(layer "B.CrtYd")
		)
		(fp_rect
			(start -0.5 0.25)
			(end 0.5 -0.25)
			(stroke
				(width 0.15)
				(type solid)
			)
			(fill no)
			(layer "B.Fab")
		)
		(fp_text user "${REFERENCE}"
			(at -0.95 -3.168 180)
			(layer "B.Fab")
			(effects
				(font
					(size 0.7 0.7)
					(thickness 0.15)
				)
				(justify left bottom mirror)
			)
		)
		(fp_text user "License: Apache-2.0"
			(at -0.95 -5.169 180)
			(layer "B.Fab")
			(effects
				(font
					(size 0.7 0.7)
					(thickness 0.15)
				)
				(justify left bottom mirror)
			)
		)
		(fp_text user "Author: Antmicro"
			(at -0.95 -4.169 180)
			(layer "B.Fab")
			(effects
				(font
					(size 0.7 0.7)
					(thickness 0.15)
				)
				(justify left bottom mirror)
			)
		)
		(pad "1" smd roundrect
			(at -0.48 0)
			(size 0.59 0.64)
			(layers "B.Cu" "B.Mask" "B.Paste")
			(roundrect_rratio 0.25)
			(net 1 "GND")
			(pintype "passive")
		)
		(pad "2" smd roundrect
			(at 0.48 0)
			(size 0.59 0.64)
			(layers "B.Cu" "B.Mask" "B.Paste")
			(roundrect_rratio 0.25)
			(net 287 "Net-(U12A-ZQ)")
			(pintype "passive")
		)
	)
	(footprint "antmicro-footprints:C_0201"
		(layer "B.Cu")
		(at 127.45 90.24)
		(descr "Capacitor SMD 0201")
		(tags "capacitor SMD 0201")
		(property "Reference" "C99"
			(at -10.22 -12.235736 0)
			(layer "B.SilkS")
			(effects
				(font
					(size 0.65 0.65)
					(thickness 0.15)
				)
				(justify right bottom mirror)
			)
		)
		(property "Value" "C_100n_0201"
			(at 0 -1.4 0)
			(layer "B.Fab")
			(hide yes)
			(effects
				(font
					(size 0.7 0.7)
					(thickness 0.15)
				)
				(justify right bottom mirror)
			)
		)
		(property "Datasheet" "https://www.yageo.com/en/Chart/Download/pdf/CC0201KRX6S5BB104"
			(at 0 0 0)
			(layer "F.Fab")
			(hide yes)
			(effects
				(font
					(size 1.27 1.27)
					(thickness 0.15)
				)
			)
		)
		(property "Description" "SMD Multilayer Ceramic Capacitor, 0.1 µF, 6.3 V, 0201 [0603 Metric], ± 10%, X6S, CC Series"
			(at 0 0 0)
			(layer "F.Fab")
			(hide yes)
			(effects
				(font
					(size 1.27 1.27)
					(thickness 0.15)
				)
			)
		)
		(property "Author" "Antmicro"
			(at 0 0 0)
			(layer "B.Fab")
			(hide yes)
			(effects
				(font
					(size 1 1)
					(thickness 0.15)
				)
				(justify mirror)
			)
		)
		(property "Dielectric" ""
			(at 0 0 0)
			(layer "B.Fab")
			(hide yes)
			(effects
				(font
					(size 1 1)
					(thickness 0.15)
				)
				(justify mirror)
			)
		)
		(property "License" "Apache-2.0"
			(at 0 0 0)
			(layer "B.Fab")
			(hide yes)
			(effects
				(font
					(size 1 1)
					(thickness 0.15)
				)
				(justify mirror)
			)
		)
		(property "MPN" "CC0201KRX6S5BB104"
			(at 0 0 0)
			(layer "B.Fab")
			(hide yes)
			(effects
				(font
					(size 1 1)
					(thickness 0.15)
				)
				(justify mirror)
			)
		)
		(property "Manufacturer" "YAGEO"
			(at 0 0 0)
			(layer "B.Fab")
			(hide yes)
			(effects
				(font
					(size 1 1)
					(thickness 0.15)
				)
				(justify mirror)
			)
		)
		(property "Val" "100n"
			(at 0 0 0)
			(layer "B.Fab")
			(hide yes)
			(effects
				(font
					(size 1 1)
					(thickness 0.15)
				)
				(justify mirror)
			)
		)
		(property "Voltage" ""
			(at 0 0 0)
			(layer "B.Fab")
			(hide yes)
			(effects
				(font
					(size 1 1)
					(thickness 0.15)
				)
				(justify mirror)
			)
		)
		(property "Public" "False"
			(at 0 0 0)
			(unlocked yes)
			(layer "B.Fab")
			(hide yes)
			(effects
				(font
					(size 1 1)
					(thickness 0.15)
				)
				(justify mirror)
			)
		)
		(sheetname "/FPGA Power/")
		(sheetfile "FPGA_Power.kicad_sch")
		(attr smd)
		(fp_rect
			(start -0.7 0.35)
			(end 0.7 -0.35)
			(stroke
				(width 0.05)
				(type default)
			)
			(fill no)
			(layer "B.CrtYd")
		)
		(fp_rect
			(start 0.3 -0.15)
			(end -0.301 0.149)
			(stroke
				(width 0.15)
				(type solid)
			)
			(fill no)
			(layer "B.Fab")
		)
		(fp_text user "License: Apache-2.0"
			(at -0.72 -4.4 180)
			(layer "B.Fab")
			(effects
				(font
					(size 0.7 0.7)
					(thickness 0.15)
				)
				(justify left bottom mirror)
			)
		)
		(fp_text user "Author: Antmicro"
			(at -0.72 -5.4 180)
			(layer "B.Fab")
			(effects
				(font
					(size 0.7 0.7)
					(thickness 0.15)
				)
				(justify left bottom mirror)
			)
		)
		(fp_text user "${REFERENCE}"
			(at -0.72 -3.4 180)
			(layer "B.Fab")
			(effects
				(font
					(size 0.7 0.7)
					(thickness 0.15)
				)
				(justify left bottom mirror)
			)
		)
		(pad "" smd roundrect
			(at -0.349 0.002)
			(size 0.318 0.36)
			(layers "B.Paste")
			(roundrect_rratio 0.25)
		)
		(pad "" smd roundrect
			(at 0.341 0.002)
			(size 0.318 0.36)
			(layers "B.Paste")
			(roundrect_rratio 0.25)
		)
		(pad "1" smd roundrect
			(at -0.321 0.002)
			(size 0.46 0.4)
			(layers "B.Cu" "B.Mask")
			(roundrect_rratio 0.25)
			(net 1 "GND")
			(pintype "passive")
		)
		(pad "2" smd roundrect
			(at 0.32 0.002)
			(size 0.46 0.4)
			(layers "B.Cu" "B.Mask")
			(roundrect_rratio 0.25)
			(net 9 "/FPGA Power/VCC_AUX")
			(pintype "passive")
		)
	)
	(footprint "antmicro-footprints:C_0201"
		(layer "B.Cu")
		(at 129.1 87.9 180)
		(descr "Capacitor SMD 0201")
		(tags "capacitor SMD 0201")
		(property "Reference" "C105"
			(at 7.87 12.095736 0)
			(layer "B.SilkS")
			(effects
				(font
					(size 0.65 0.65)
					(thickness 0.15)
				)
				(justify left bottom mirror)
			)
		)
		(property "Value" "C_100n_0201"
			(at 0 -1.4 0)
			(layer "B.Fab")
			(hide yes)
			(effects
				(font
					(size 0.7 0.7)
					(thickness 0.15)
				)
				(justify left bottom mirror)
			)
		)
		(property "Datasheet" "https://www.yageo.com/en/Chart/Download/pdf/CC0201KRX6S5BB104"
			(at 0 0 180)
			(layer "F.Fab")
			(hide yes)
			(effects
				(font
					(size 1.27 1.27)
					(thickness 0.15)
				)
			)
		)
		(property "Description" "SMD Multilayer Ceramic Capacitor, 0.1 µF, 6.3 V, 0201 [0603 Metric], ± 10%, X6S, CC Series"
			(at 0 0 180)
			(layer "F.Fab")
			(hide yes)
			(effects
				(font
					(size 1.27 1.27)
					(thickness 0.15)
				)
			)
		)
		(property "Author" "Antmicro"
			(at 258.2 175.8 0)
			(layer "B.Fab")
			(hide yes)
			(effects
				(font
					(size 1 1)
					(thickness 0.15)
				)
				(justify mirror)
			)
		)
		(property "Dielectric" ""
			(at 258.2 175.8 0)
			(layer "B.Fab")
			(hide yes)
			(effects
				(font
					(size 1 1)
					(thickness 0.15)
				)
				(justify mirror)
			)
		)
		(property "License" "Apache-2.0"
			(at 258.2 175.8 0)
			(layer "B.Fab")
			(hide yes)
			(effects
				(font
					(size 1 1)
					(thickness 0.15)
				)
				(justify mirror)
			)
		)
		(property "MPN" "CC0201KRX6S5BB104"
			(at 258.2 175.8 0)
			(layer "B.Fab")
			(hide yes)
			(effects
				(font
					(size 1 1)
					(thickness 0.15)
				)
				(justify mirror)
			)
		)
		(property "Manufacturer" "YAGEO"
			(at 258.2 175.8 0)
			(layer "B.Fab")
			(hide yes)
			(effects
				(font
					(size 1 1)
					(thickness 0.15)
				)
				(justify mirror)
			)
		)
		(property "Val" "100n"
			(at 258.2 175.8 0)
			(layer "B.Fab")
			(hide yes)
			(effects
				(font
					(size 1 1)
					(thickness 0.15)
				)
				(justify mirror)
			)
		)
		(property "Voltage" ""
			(at 258.2 175.8 0)
			(layer "B.Fab")
			(hide yes)
			(effects
				(font
					(size 1 1)
					(thickness 0.15)
				)
				(justify mirror)
			)
		)
		(property "Public" "False"
			(at 0 0 180)
			(unlocked yes)
			(layer "B.Fab")
			(hide yes)
			(effects
				(font
					(size 1 1)
					(thickness 0.15)
				)
				(justify mirror)
			)
		)
		(sheetname "/FPGA Power/")
		(sheetfile "FPGA_Power.kicad_sch")
		(attr smd)
		(fp_rect
			(start -0.7 0.35)
			(end 0.7 -0.35)
			(stroke
				(width 0.05)
				(type default)
			)
			(fill no)
			(layer "B.CrtYd")
		)
		(fp_rect
			(start 0.3 -0.15)
			(end -0.301 0.149)
			(stroke
				(width 0.15)
				(type solid)
			)
			(fill no)
			(layer "B.Fab")
		)
		(fp_text user "Author: Antmicro"
			(at -0.72 -5.4 0)
			(layer "B.Fab")
			(effects
				(font
					(size 0.7 0.7)
					(thickness 0.15)
				)
				(justify left bottom mirror)
			)
		)
		(fp_text user "${REFERENCE}"
			(at -0.72 -3.4 0)
			(layer "B.Fab")
			(effects
				(font
					(size 0.7 0.7)
					(thickness 0.15)
				)
				(justify left bottom mirror)
			)
		)
		(fp_text user "License: Apache-2.0"
			(at -0.72 -4.4 0)
			(layer "B.Fab")
			(effects
				(font
					(size 0.7 0.7)
					(thickness 0.15)
				)
				(justify left bottom mirror)
			)
		)
		(pad "" smd roundrect
			(at -0.349 0.002 180)
			(size 0.318 0.36)
			(layers "B.Paste")
			(roundrect_rratio 0.25)
		)
		(pad "" smd roundrect
			(at 0.341 0.002 180)
			(size 0.318 0.36)
			(layers "B.Paste")
			(roundrect_rratio 0.25)
		)
		(pad "1" smd roundrect
			(at -0.321 0.002 180)
			(size 0.46 0.4)
			(layers "B.Cu" "B.Mask")
			(roundrect_rratio 0.25)
			(net 1 "GND")
			(pintype "passive")
		)
		(pad "2" smd roundrect
			(at 0.32 0.002 180)
			(size 0.46 0.4)
			(layers "B.Cu" "B.Mask")
			(roundrect_rratio 0.25)
			(net 9 "/FPGA Power/VCC_AUX")
			(pintype "passive")
		)
	)
	(footprint "antmicro-footprints:R_0402_1005Metric"
		(layer "B.Cu")
		(at 103.19 96.8 -90)
		(descr "Resistor SMD 0402")
		(tags "resistor SMD 0402")
		(property "Reference" "R69"
			(at 0.94 -0.34 90)
			(layer "B.SilkS")
			(effects
				(font
					(size 0.65 0.65)
					(thickness 0.15)
				)
				(justify left bottom mirror)
			)
		)
		(property "Value" "R_0R_0402"
			(at 0 -1.4 90)
			(layer "B.Fab")
			(hide yes)
			(effects
				(font
					(size 0.7 0.7)
					(thickness 0.15)
				)
				(justify left bottom mirror)
			)
		)
		(property "Datasheet" "https://industrial.panasonic.com/cdbs/www-data/pdf/RDA0000/AOA0000C301.pdf"
			(at 0 0 270)
			(layer "F.Fab")
			(hide yes)
			(effects
				(font
					(size 1.27 1.27)
					(thickness 0.15)
				)
			)
		)
		(property "Description" "SMD Chip Resistor, Jumper, 0 ohm, 100 mW, 0402 [1005 Metric], Thick Film, General Purpose"
			(at 0 0 270)
			(layer "F.Fab")
			(hide yes)
			(effects
				(font
					(size 1.27 1.27)
					(thickness 0.15)
				)
			)
		)
		(property "Author" "Antmicro"
			(at 6.39 199.99 0)
			(layer "B.Fab")
			(hide yes)
			(effects
				(font
					(size 1 1)
					(thickness 0.15)
				)
				(justify mirror)
			)
		)
		(property "Current" "1A"
			(at 6.39 199.99 0)
			(layer "B.Fab")
			(hide yes)
			(effects
				(font
					(size 1 1)
					(thickness 0.15)
				)
				(justify mirror)
			)
		)
		(property "License" "Apache-2.0"
			(at 6.39 199.99 0)
			(layer "B.Fab")
			(hide yes)
			(effects
				(font
					(size 1 1)
					(thickness 0.15)
				)
				(justify mirror)
			)
		)
		(property "MPN" "ERJ2GE0R00X"
			(at 6.39 199.99 0)
			(layer "B.Fab")
			(hide yes)
			(effects
				(font
					(size 1 1)
					(thickness 0.15)
				)
				(justify mirror)
			)
		)
		(property "Manufacturer" "Panasonic"
			(at 6.39 199.99 0)
			(layer "B.Fab")
			(hide yes)
			(effects
				(font
					(size 1 1)
					(thickness 0.15)
				)
				(justify mirror)
			)
		)
		(property "Tolerance" "~"
			(at 6.39 199.99 0)
			(layer "B.Fab")
			(hide yes)
			(effects
				(font
					(size 1 1)
					(thickness 0.15)
				)
				(justify mirror)
			)
		)
		(property "Val" "0R"
			(at 6.39 199.99 0)
			(layer "B.Fab")
			(hide yes)
			(effects
				(font
					(size 1 1)
					(thickness 0.15)
				)
				(justify mirror)
			)
		)
		(sheetname "/FPGA/")
		(sheetfile "fpga.kicad_sch")
		(attr smd)
		(fp_rect
			(start -0.925 0.47)
			(end 0.925 -0.47)
			(stroke
				(width 0.05)
				(type default)
			)
			(fill no)
			(layer "B.CrtYd")
		)
		(fp_rect
			(start -0.5 0.25)
			(end 0.5 -0.25)
			(stroke
				(width 0.15)
				(type solid)
			)
			(fill no)
			(layer "B.Fab")
		)
		(fp_text user "${REFERENCE}"
			(at -0.95 -3.168 90)
			(layer "B.Fab")
			(effects
				(font
					(size 0.7 0.7)
					(thickness 0.15)
				)
				(justify left bottom mirror)
			)
		)
		(fp_text user "Author: Antmicro"
			(at -0.95 -4.169 90)
			(layer "B.Fab")
			(effects
				(font
					(size 0.7 0.7)
					(thickness 0.15)
				)
				(justify left bottom mirror)
			)
		)
		(fp_text user "License: Apache-2.0"
			(at -0.95 -5.169 90)
			(layer "B.Fab")
			(effects
				(font
					(size 0.7 0.7)
					(thickness 0.15)
				)
				(justify left bottom mirror)
			)
		)
		(pad "1" smd roundrect
			(at -0.48 0 270)
			(size 0.59 0.64)
			(layers "B.Cu" "B.Mask" "B.Paste")
			(roundrect_rratio 0.25)
			(net 300 "Net-(U18-SI{slash}IO0)")
			(pintype "passive")
		)
		(pad "2" smd roundrect
			(at 0.48 0 270)
			(size 0.59 0.64)
			(layers "B.Cu" "B.Mask" "B.Paste")
			(roundrect_rratio 0.25)
			(net 37 "/FPGA/SPI_DQ0_MOSI")
			(pintype "passive")
		)
	)
	(footprint "antmicro-footprints:SOT-23-6"
		(layer "B.Cu")
		(at 158.54 72.35 -90)
		(property "Reference" "U4"
			(at -1.71 -2.09 180)
			(layer "B.SilkS")
			(effects
				(font
					(size 0.65 0.65)
					(thickness 0.15)
				)
				(justify left bottom mirror)
			)
		)
		(property "Value" "DIO7553ST6"
			(at -1.75 -2.75 90)
			(layer "B.Fab")
			(hide yes)
			(effects
				(font
					(size 0.7 0.7)
					(thickness 0.15)
				)
				(justify left bottom mirror)
			)
		)
		(property "Datasheet" "https://www.mouser.com/datasheet/2/802/7e5c577022fb784effcb3cdb25b437c0-1815562.pdf"
			(at 0 0 270)
			(layer "F.Fab")
			(hide yes)
			(effects
				(font
					(size 1.27 1.27)
					(thickness 0.15)
				)
			)
		)
		(property "Description" "Power switch"
			(at 0 0 270)
			(layer "F.Fab")
			(hide yes)
			(effects
				(font
					(size 1.27 1.27)
					(thickness 0.15)
				)
			)
		)
		(property "Author" "Antmicro"
			(at 86.19 230.89 0)
			(layer "B.Fab")
			(hide yes)
			(effects
				(font
					(size 1 1)
					(thickness 0.15)
				)
				(justify mirror)
			)
		)
		(property "License" "Apache-2.0"
			(at 86.19 230.89 0)
			(layer "B.Fab")
			(hide yes)
			(effects
				(font
					(size 1 1)
					(thickness 0.15)
				)
				(justify mirror)
			)
		)
		(property "MPN" "DIO7553ST6"
			(at 86.19 230.89 0)
			(layer "B.Fab")
			(hide yes)
			(effects
				(font
					(size 1 1)
					(thickness 0.15)
				)
				(justify mirror)
			)
		)
		(property "Manufacturer" "DIOO Microcircuits"
			(at 86.19 230.89 0)
			(layer "B.Fab")
			(hide yes)
			(effects
				(font
					(size 1 1)
					(thickness 0.15)
				)
				(justify mirror)
			)
		)
		(sheetname "/Power Supply/")
		(sheetfile "supply.kicad_sch")
		(attr smd)
		(fp_line
			(start -1.45 0.757)
			(end -1.45 0.457)
			(stroke
				(width 0.12)
				(type solid)
			)
			(layer "B.SilkS")
		)
		(fp_line
			(start -1.3 0.757)
			(end -1.45 0.757)
			(stroke
				(width 0.12)
				(type solid)
			)
			(layer "B.SilkS")
		)
		(fp_line
			(start 1.3 0.757)
			(end 1.45 0.757)
			(stroke
				(width 0.12)
				(type solid)
			)
			(layer "B.SilkS")
		)
		(fp_line
			(start 1.45 0.757)
			(end 1.45 0.457)
			(stroke
				(width 0.12)
				(type solid)
			)
			(layer "B.SilkS")
		)
		(fp_line
			(start -1.45 -0.643)
			(end -1.45 -0.343)
			(stroke
				(width 0.12)
				(type solid)
			)
			(layer "B.SilkS")
		)
		(fp_line
			(start 1.3 -0.643)
			(end 1.45 -0.643)
			(stroke
				(width 0.12)
				(type solid)
			)
			(layer "B.SilkS")
		)
		(fp_line
			(start 1.45 -0.643)
			(end 1.45 -0.343)
			(stroke
				(width 0.12)
				(type solid)
			)
			(layer "B.SilkS")
		)
		(fp_rect
			(start -1.55 1.85)
			(end 1.55 -1.75)
			(stroke
				(width 0.05)
				(type solid)
			)
			(fill no)
			(layer "B.CrtYd")
		)
		(fp_line
			(start -1.5 0.757)
			(end 1.5 0.757)
			(stroke
				(width 0.1)
				(type solid)
			)
			(layer "B.Fab")
		)
		(fp_line
			(start 1.5 0.757)
			(end 1.5 -0.643)
			(stroke
				(width 0.1)
				(type solid)
			)
			(layer "B.Fab")
		)
		(fp_line
			(start -1.5 -0.643)
			(end -1.5 0.757)
			(stroke
				(width 0.1)
				(type solid)
			)
			(layer "B.Fab")
		)
		(fp_line
			(start 1.5 -0.643)
			(end -1.5 -0.643)
			(stroke
				(width 0.1)
				(type solid)
			)
			(layer "B.Fab")
		)
		(fp_text user "."
			(at -1.4 -1.2 90)
			(layer "B.SilkS")
			(effects
				(font
					(size 1 1)
					(thickness 0.15)
				)
				(justify mirror)
			)
		)
		(fp_text user "Author: Antmicro"
			(at -1.829 -5.25 90)
			(layer "B.Fab")
			(effects
				(font
					(size 0.7 0.7)
					(thickness 0.15)
				)
				(justify left bottom mirror)
			)
		)
		(fp_text user "${REFERENCE}"
			(at -1.75 -4 90)
			(layer "B.Fab")
			(effects
				(font
					(size 0.7 0.7)
					(thickness 0.15)
				)
				(justify left bottom mirror)
			)
		)
		(fp_text user "License: Apache-2.0"
			(at -1.75 -6.5 90)
			(layer "B.Fab")
			(effects
				(font
					(size 0.7 0.7)
					(thickness 0.15)
				)
				(justify left bottom mirror)
			)
		)
		(pad "1" smd roundrect
			(at -0.954 -1.1 270)
			(size 0.55 1)
			(layers "B.Cu" "B.Mask" "B.Paste")
			(roundrect_rratio 0.15)
			(net 329 "/Power Supply/FFC2_5V_1")
			(pinfunction "IN")
			(pintype "power_in")
		)
		(pad "2" smd roundrect
			(at -0.003 -1.1 270)
			(size 0.55 1)
			(layers "B.Cu" "B.Mask" "B.Paste")
			(roundrect_rratio 0.15)
			(net 1 "GND")
			(pinfunction "GND")
			(pintype "power_in")
		)
		(pad "3" smd roundrect
			(at 0.947 -1.1 270)
			(size 0.55 1)
			(layers "B.Cu" "B.Mask" "B.Paste")
			(roundrect_rratio 0.15)
			(net 259 "Net-(Q1-D)")
			(pinfunction "EN")
			(pintype "input")
		)
		(pad "4" smd roundrect
			(at 0.947 1.214 270)
			(size 0.55 1)
			(layers "B.Cu" "B.Mask" "B.Paste")
			(roundrect_rratio 0.15)
			(net 305 "/Power Supply/~{FAULT}")
			(pinfunction "~{FAULT}")
			(pintype "output")
		)
		(pad "5" smd roundrect
			(at -0.003 1.214 270)
			(size 0.55 1)
			(layers "B.Cu" "B.Mask" "B.Paste")
			(roundrect_rratio 0.15)
			(net 349 "Net-(U4-ILIM)")
			(pinfunction "ILIM")
			(pintype "passive")
		)
		(pad "6" smd roundrect
			(at -0.954 1.214 270)
			(size 0.55 1)
			(layers "B.Cu" "B.Mask" "B.Paste")
			(roundrect_rratio 0.15)
			(net 304 "/Power Supply/5V_I")
			(pinfunction "OUT")
			(pintype "power_out")
		)
	)
	(footprint "antmicro-footprints:C_0402_1005Metric"
		(layer "B.Cu")
		(at 153.03 98.35 90)
		(descr "Capacitor SMD 0402")
		(tags "capacitor SMD 0402")
		(property "Reference" "C1"
			(at 0.91 0.4 90)
			(layer "B.SilkS")
			(effects
				(font
					(size 0.65 0.65)
					(thickness 0.15)
				)
				(justify right bottom mirror)
			)
		)
		(property "Value" "C_100n_0402"
			(at 0 -1.4 90)
			(layer "B.Fab")
			(hide yes)
			(effects
				(font
					(size 0.7 0.7)
					(thickness 0.15)
				)
				(justify right bottom mirror)
			)
		)
		(property "Datasheet" "https://www.murata.com/products/productdetail?partno=GRM155R61H104KE14%23"
			(at 0 0 90)
			(layer "F.Fab")
			(hide yes)
			(effects
				(font
					(size 1.27 1.27)
					(thickness 0.15)
				)
			)
		)
		(property "Description" "SMD Multilayer Ceramic Capacitor, 0.1 µF, 50 V, 0402 [1005 Metric], ± 10%, X5R, GRM Series"
			(at 0 0 90)
			(layer "F.Fab")
			(hide yes)
			(effects
				(font
					(size 1.27 1.27)
					(thickness 0.15)
				)
			)
		)
		(property "Author" "Antmicro"
			(at 251.38 -54.68 0)
			(layer "B.Fab")
			(hide yes)
			(effects
				(font
					(size 1 1)
					(thickness 0.15)
				)
				(justify mirror)
			)
		)
		(property "Dielectric" "X5R"
			(at 251.38 -54.68 0)
			(layer "B.Fab")
			(hide yes)
			(effects
				(font
					(size 1 1)
					(thickness 0.15)
				)
				(justify mirror)
			)
		)
		(property "License" "Apache-2.0"
			(at 251.38 -54.68 0)
			(layer "B.Fab")
			(hide yes)
			(effects
				(font
					(size 1 1)
					(thickness 0.15)
				)
				(justify mirror)
			)
		)
		(property "MPN" "GRM155R61H104KE14D"
			(at 251.38 -54.68 0)
			(layer "B.Fab")
			(hide yes)
			(effects
				(font
					(size 1 1)
					(thickness 0.15)
				)
				(justify mirror)
			)
		)
		(property "Manufacturer" "Murata"
			(at 251.38 -54.68 0)
			(layer "B.Fab")
			(hide yes)
			(effects
				(font
					(size 1 1)
					(thickness 0.15)
				)
				(justify mirror)
			)
		)
		(property "Val" "100n"
			(at 251.38 -54.68 0)
			(layer "B.Fab")
			(hide yes)
			(effects
				(font
					(size 1 1)
					(thickness 0.15)
				)
				(justify mirror)
			)
		)
		(property "Voltage" "50V"
			(at 251.38 -54.68 0)
			(layer "B.Fab")
			(hide yes)
			(effects
				(font
					(size 1 1)
					(thickness 0.15)
				)
				(justify mirror)
			)
		)
		(sheetname "/Power Supply/")
		(sheetfile "supply.kicad_sch")
		(attr smd)
		(fp_rect
			(start -0.925 0.47)
			(end 0.925 -0.47)
			(stroke
				(width 0.05)
				(type default)
			)
			(fill no)
			(layer "B.CrtYd")
		)
		(fp_line
			(start 0.504 -0.248)
			(end -0.494 -0.248)
			(stroke
				(width 0.15)
				(type solid)
			)
			(layer "B.Fab")
		)
		(fp_line
			(start -0.494 -0.248)
			(end -0.494 0.25)
			(stroke
				(width 0.15)
				(type solid)
			)
			(layer "B.Fab")
		)
		(fp_line
			(start 0.504 0.25)
			(end 0.504 -0.248)
			(stroke
				(width 0.15)
				(type solid)
			)
			(layer "B.Fab")
		)
		(fp_line
			(start -0.494 0.25)
			(end 0.504 0.25)
			(stroke
				(width 0.15)
				(type solid)
			)
			(layer "B.Fab")
		)
		(fp_text user "Author: Antmicro"
			(at -0.939 -3.399 270)
			(layer "B.Fab")
			(effects
				(font
					(size 0.7 0.7)
					(thickness 0.15)
				)
				(justify left bottom mirror)
			)
		)
		(fp_text user "${REFERENCE}"
			(at -0.939 -4.599 270)
			(layer "B.Fab")
			(effects
				(font
					(size 0.7 0.7)
					(thickness 0.15)
				)
				(justify left bottom mirror)
			)
		)
		(fp_text user "License: Apache-2.0"
			(at -0.939 -5.799 270)
			(layer "B.Fab")
			(effects
				(font
					(size 0.7 0.7)
					(thickness 0.15)
				)
				(justify left bottom mirror)
			)
		)
		(pad "1" smd roundrect
			(at -0.48 0 90)
			(size 0.59 0.64)
			(layers "B.Cu" "B.Mask" "B.Paste")
			(roundrect_rratio 0.25)
			(net 1 "GND")
			(pintype "passive")
		)
		(pad "2" smd roundrect
			(at 0.48 0 90)
			(size 0.59 0.64)
			(layers "B.Cu" "B.Mask" "B.Paste")
			(roundrect_rratio 0.25)
			(net 14 "+5V")
			(pintype "passive")
		)
	)
	(footprint "antmicro-footprints:C_0402_1005Metric"
		(layer "B.Cu")
		(at 120.51 70.12 90)
		(descr "Capacitor SMD 0402")
		(tags "capacitor SMD 0402")
		(property "Reference" "C48"
			(at -0.92 1.42 90)
			(layer "B.SilkS")
			(effects
				(font
					(size 0.65 0.65)
					(thickness 0.15)
				)
				(justify right bottom mirror)
			)
		)
		(property "Value" "C_100n_0402"
			(at 0 -1.4 90)
			(layer "B.Fab")
			(hide yes)
			(effects
				(font
					(size 0.7 0.7)
					(thickness 0.15)
				)
				(justify right bottom mirror)
			)
		)
		(property "Datasheet" "https://www.murata.com/products/productdetail?partno=GRM155R61H104KE14%23"
			(at 0 0 90)
			(layer "F.Fab")
			(hide yes)
			(effects
				(font
					(size 1.27 1.27)
					(thickness 0.15)
				)
			)
		)
		(property "Description" "SMD Multilayer Ceramic Capacitor, 0.1 µF, 50 V, 0402 [1005 Metric], ± 10%, X5R, GRM Series"
			(at 0 0 90)
			(layer "F.Fab")
			(hide yes)
			(effects
				(font
					(size 1.27 1.27)
					(thickness 0.15)
				)
			)
		)
		(property "Author" "Antmicro"
			(at 190.63 -50.39 0)
			(layer "B.Fab")
			(hide yes)
			(effects
				(font
					(size 1 1)
					(thickness 0.15)
				)
				(justify mirror)
			)
		)
		(property "Dielectric" "X5R"
			(at 190.63 -50.39 0)
			(layer "B.Fab")
			(hide yes)
			(effects
				(font
					(size 1 1)
					(thickness 0.15)
				)
				(justify mirror)
			)
		)
		(property "License" "Apache-2.0"
			(at 190.63 -50.39 0)
			(layer "B.Fab")
			(hide yes)
			(effects
				(font
					(size 1 1)
					(thickness 0.15)
				)
				(justify mirror)
			)
		)
		(property "MPN" "GRM155R61H104KE14D"
			(at 190.63 -50.39 0)
			(layer "B.Fab")
			(hide yes)
			(effects
				(font
					(size 1 1)
					(thickness 0.15)
				)
				(justify mirror)
			)
		)
		(property "Manufacturer" "Murata"
			(at 190.63 -50.39 0)
			(layer "B.Fab")
			(hide yes)
			(effects
				(font
					(size 1 1)
					(thickness 0.15)
				)
				(justify mirror)
			)
		)
		(property "Val" "100n"
			(at 190.63 -50.39 0)
			(layer "B.Fab")
			(hide yes)
			(effects
				(font
					(size 1 1)
					(thickness 0.15)
				)
				(justify mirror)
			)
		)
		(property "Voltage" "50V"
			(at 190.63 -50.39 0)
			(layer "B.Fab")
			(hide yes)
			(effects
				(font
					(size 1 1)
					(thickness 0.15)
				)
				(justify mirror)
			)
		)
		(sheetname "/DDR3/")
		(sheetfile "ddr3.kicad_sch")
		(attr smd)
		(fp_rect
			(start -0.925 0.47)
			(end 0.925 -0.47)
			(stroke
				(width 0.05)
				(type default)
			)
			(fill no)
			(layer "B.CrtYd")
		)
		(fp_line
			(start 0.504 -0.248)
			(end -0.494 -0.248)
			(stroke
				(width 0.15)
				(type solid)
			)
			(layer "B.Fab")
		)
		(fp_line
			(start -0.494 -0.248)
			(end -0.494 0.25)
			(stroke
				(width 0.15)
				(type solid)
			)
			(layer "B.Fab")
		)
		(fp_line
			(start 0.504 0.25)
			(end 0.504 -0.248)
			(stroke
				(width 0.15)
				(type solid)
			)
			(layer "B.Fab")
		)
		(fp_line
			(start -0.494 0.25)
			(end 0.504 0.25)
			(stroke
				(width 0.15)
				(type solid)
			)
			(layer "B.Fab")
		)
		(fp_text user "${REFERENCE}"
			(at -0.939 -4.599 270)
			(layer "B.Fab")
			(effects
				(font
					(size 0.7 0.7)
					(thickness 0.15)
				)
				(justify left bottom mirror)
			)
		)
		(fp_text user "Author: Antmicro"
			(at -0.939 -3.399 270)
			(layer "B.Fab")
			(effects
				(font
					(size 0.7 0.7)
					(thickness 0.15)
				)
				(justify left bottom mirror)
			)
		)
		(fp_text user "License: Apache-2.0"
			(at -0.939 -5.799 270)
			(layer "B.Fab")
			(effects
				(font
					(size 0.7 0.7)
					(thickness 0.15)
				)
				(justify left bottom mirror)
			)
		)
		(pad "1" smd roundrect
			(at -0.48 0 90)
			(size 0.59 0.64)
			(layers "B.Cu" "B.Mask" "B.Paste")
			(roundrect_rratio 0.25)
			(net 1 "GND")
			(pintype "passive")
		)
		(pad "2" smd roundrect
			(at 0.48 0 90)
			(size 0.59 0.64)
			(layers "B.Cu" "B.Mask" "B.Paste")
			(roundrect_rratio 0.25)
			(net 248 "+1V5")
			(pintype "passive")
		)
	)
	(footprint "antmicro-footprints:TP_SMD_0.75mm"
		(layer "B.Cu")
		(at 99.19 88.95 90)
		(property "Reference" "TP33"
			(at -0.59 0.34 90)
			(layer "B.SilkS")
			(effects
				(font
					(size 0.65 0.65)
					(thickness 0.15)
				)
				(justify left bottom mirror)
			)
		)
		(property "Value" "TP_0.75mm_SMD"
			(at 0 -1.2 90)
			(layer "B.Fab")
			(hide yes)
			(effects
				(font
					(size 0.7 0.7)
					(thickness 0.15)
				)
				(justify right bottom mirror)
			)
		)
		(property "Description" "SMT test point"
			(at 0 0 90)
			(layer "F.Fab")
			(hide yes)
			(effects
				(font
					(size 1.27 1.27)
					(thickness 0.15)
				)
			)
		)
		(property "Author" "Antmicro"
			(at 188.14 -10.24 0)
			(layer "B.Fab")
			(hide yes)
			(effects
				(font
					(size 1 1)
					(thickness 0.15)
				)
				(justify mirror)
			)
		)
		(property "License" "Apache-2.0"
			(at 188.14 -10.24 0)
			(layer "B.Fab")
			(hide yes)
			(effects
				(font
					(size 1 1)
					(thickness 0.15)
				)
				(justify mirror)
			)
		)
		(property "MPN" ""
			(at 188.14 -10.24 0)
			(layer "B.Fab")
			(hide yes)
			(effects
				(font
					(size 1 1)
					(thickness 0.15)
				)
				(justify mirror)
			)
		)
		(property "Manufacturer" ""
			(at 188.14 -10.24 0)
			(layer "B.Fab")
			(hide yes)
			(effects
				(font
					(size 1 1)
					(thickness 0.15)
				)
				(justify mirror)
			)
		)
		(sheetname "/SDI/")
		(sheetfile "sdi.kicad_sch")
		(attr exclude_from_pos_files)
		(fp_circle
			(center 0 0)
			(end 0.475 0)
			(stroke
				(width 0.05)
				(type default)
			)
			(fill no)
			(layer "B.CrtYd")
		)
		(fp_text user "Author: Antmicro"
			(at -0.4 -3.901 270)
			(layer "B.Fab")
			(effects
				(font
					(size 0.7 0.7)
					(thickness 0.15)
				)
				(justify left bottom mirror)
			)
		)
		(fp_text user "License: Apache-2.0"
			(at -0.4 -5.101 270)
			(layer "B.Fab")
			(effects
				(font
					(size 0.7 0.7)
					(thickness 0.15)
				)
				(justify left bottom mirror)
			)
		)
		(fp_text user "${REFERENCE}"
			(at -0.4 -2.7 270)
			(layer "B.Fab")
			(effects
				(font
					(size 0.7 0.7)
					(thickness 0.15)
				)
				(justify left bottom mirror)
			)
		)
		(pad "1" smd circle
			(at 0 0 90)
			(size 0.75 0.75)
			(layers "B.Cu" "B.Mask")
			(net 199 "/SDI/IOPROC_EN{slash}~{DIS}")
			(pinfunction "1")
			(pintype "passive")
		)
	)
	(footprint "antmicro-footprints:C_0603_1608Metric"
		(layer "B.Cu")
		(at 130.2 62.15 90)
		(descr "Capacitor SMD 0603")
		(tags "capacitor 0603")
		(property "Reference" "C7"
			(at -2.69 0.4 90)
			(layer "B.SilkS")
			(effects
				(font
					(size 0.65 0.65)
					(thickness 0.15)
				)
				(justify right bottom mirror)
			)
		)
		(property "Value" "C_22u_0603"
			(at 0 -1.6 90)
			(layer "B.Fab")
			(hide yes)
			(effects
				(font
					(size 0.7 0.7)
					(thickness 0.15)
				)
				(justify right bottom mirror)
			)
		)
		(property "Datasheet" "https://www.murata.com/products/productdetail?partno=GRM188R60J226MEA0%23"
			(at 0 0 90)
			(layer "F.Fab")
			(hide yes)
			(effects
				(font
					(size 1.27 1.27)
					(thickness 0.15)
				)
			)
		)
		(property "Description" "SMD Multilayer Ceramic Capacitor, 22 µF, 6.3 V, 0603 [1608 Metric], ± 20%, X5R, GRM Series"
			(at 0 0 90)
			(layer "F.Fab")
			(hide yes)
			(effects
				(font
					(size 1.27 1.27)
					(thickness 0.15)
				)
			)
		)
		(property "Author" "Antmicro"
			(at 192.38 -68.08 0)
			(layer "B.Fab")
			(hide yes)
			(effects
				(font
					(size 1 1)
					(thickness 0.15)
				)
				(justify mirror)
			)
		)
		(property "Dielectric" ""
			(at 192.38 -68.08 0)
			(layer "B.Fab")
			(hide yes)
			(effects
				(font
					(size 1 1)
					(thickness 0.15)
				)
				(justify mirror)
			)
		)
		(property "License" "Apache-2.0"
			(at 192.38 -68.08 0)
			(layer "B.Fab")
			(hide yes)
			(effects
				(font
					(size 1 1)
					(thickness 0.15)
				)
				(justify mirror)
			)
		)
		(property "MPN" "GRM188R60J226MEA0D"
			(at 192.38 -68.08 0)
			(layer "B.Fab")
			(hide yes)
			(effects
				(font
					(size 1 1)
					(thickness 0.15)
				)
				(justify mirror)
			)
		)
		(property "Manufacturer" "Murata"
			(at 192.38 -68.08 0)
			(layer "B.Fab")
			(hide yes)
			(effects
				(font
					(size 1 1)
					(thickness 0.15)
				)
				(justify mirror)
			)
		)
		(property "Val" "22u"
			(at 192.38 -68.08 0)
			(layer "B.Fab")
			(hide yes)
			(effects
				(font
					(size 1 1)
					(thickness 0.15)
				)
				(justify mirror)
			)
		)
		(property "Voltage" ""
			(at 192.38 -68.08 0)
			(layer "B.Fab")
			(hide yes)
			(effects
				(font
					(size 1 1)
					(thickness 0.15)
				)
				(justify mirror)
			)
		)
		(sheetname "/Power Supply/")
		(sheetfile "supply.kicad_sch")
		(attr smd)
		(fp_line
			(start -0.15 -0.4)
			(end 0.15 -0.4)
			(stroke
				(width 0.15)
				(type solid)
			)
			(layer "B.SilkS")
		)
		(fp_line
			(start -0.15 0.4)
			(end 0.15 0.4)
			(stroke
				(width 0.15)
				(type solid)
			)
			(layer "B.SilkS")
		)
		(fp_rect
			(start -1.25 0.65)
			(end 1.25 -0.65)
			(stroke
				(width 0.05)
				(type solid)
			)
			(fill no)
			(layer "B.CrtYd")
		)
		(fp_rect
			(start -0.8 0.4)
			(end 0.8 -0.4)
			(stroke
				(width 0.15)
				(type solid)
			)
			(fill no)
			(layer "B.Fab")
		)
		(fp_text user "${REFERENCE}"
			(at -1.682 -3.895 270)
			(layer "B.Fab")
			(effects
				(font
					(size 0.7 0.7)
					(thickness 0.15)
				)
				(justify left bottom mirror)
			)
		)
		(fp_text user "License: Apache-2.0"
			(at -1.682 -5.895 270)
			(layer "B.Fab")
			(effects
				(font
					(size 0.7 0.7)
					(thickness 0.15)
				)
				(justify left bottom mirror)
			)
		)
		(fp_text user "Author: Antmicro"
			(at -1.682 -4.894 270)
			(layer "B.Fab")
			(effects
				(font
					(size 0.7 0.7)
					(thickness 0.15)
				)
				(justify left bottom mirror)
			)
		)
		(pad "1" smd roundrect
			(at -0.7 0 90)
			(size 0.8 1)
			(layers "B.Cu" "B.Mask" "B.Paste")
			(roundrect_rratio 0.2)
			(net 1 "GND")
			(pintype "passive")
		)
		(pad "2" smd roundrect
			(at 0.7 0 90)
			(size 0.8 1)
			(layers "B.Cu" "B.Mask" "B.Paste")
			(roundrect_rratio 0.2)
			(net 6 "Vtt")
			(pintype "passive")
		)
	)
	(footprint "antmicro-footprints:C_0201"
		(layer "B.Cu")
		(at 129.9 94.7 -135)
		(descr "Capacitor SMD 0201")
		(tags "capacitor SMD 0201")
		(property "Reference" "C97"
			(at -3.553732 15.249278 45)
			(layer "B.SilkS")
			(effects
				(font
					(size 0.65 0.65)
					(thickness 0.15)
				)
				(justify left bottom mirror)
			)
		)
		(property "Value" "C_100n_0201"
			(at 0 -1.399999 45)
			(layer "B.Fab")
			(hide yes)
			(effects
				(font
					(size 0.7 0.7)
					(thickness 0.15)
				)
				(justify left bottom mirror)
			)
		)
		(property "Datasheet" "https://www.yageo.com/en/Chart/Download/pdf/CC0201KRX6S5BB104"
			(at 0 0 225)
			(layer "F.Fab")
			(hide yes)
			(effects
				(font
					(size 1.27 1.27)
					(thickness 0.15)
				)
			)
		)
		(property "Description" "SMD Multilayer Ceramic Capacitor, 0.1 µF, 6.3 V, 0201 [0603 Metric], ± 10%, X6S, CC Series"
			(at 0 0 225)
			(layer "F.Fab")
			(hide yes)
			(effects
				(font
					(size 1.27 1.27)
					(thickness 0.15)
				)
			)
		)
		(property "Author" "Antmicro"
			(at 154.790159 253.516183 0)
			(layer "B.Fab")
			(hide yes)
			(effects
				(font
					(size 1 1)
					(thickness 0.15)
				)
				(justify mirror)
			)
		)
		(property "Dielectric" ""
			(at 154.790159 253.516183 0)
			(layer "B.Fab")
			(hide yes)
			(effects
				(font
					(size 1 1)
					(thickness 0.15)
				)
				(justify mirror)
			)
		)
		(property "License" "Apache-2.0"
			(at 154.790159 253.516183 0)
			(layer "B.Fab")
			(hide yes)
			(effects
				(font
					(size 1 1)
					(thickness 0.15)
				)
				(justify mirror)
			)
		)
		(property "MPN" "CC0201KRX6S5BB104"
			(at 154.790159 253.516183 0)
			(layer "B.Fab")
			(hide yes)
			(effects
				(font
					(size 1 1)
					(thickness 0.15)
				)
				(justify mirror)
			)
		)
		(property "Manufacturer" "YAGEO"
			(at 154.790159 253.516183 0)
			(layer "B.Fab")
			(hide yes)
			(effects
				(font
					(size 1 1)
					(thickness 0.15)
				)
				(justify mirror)
			)
		)
		(property "Val" "100n"
			(at 154.790159 253.516183 0)
			(layer "B.Fab")
			(hide yes)
			(effects
				(font
					(size 1 1)
					(thickness 0.15)
				)
				(justify mirror)
			)
		)
		(property "Voltage" ""
			(at 154.790159 253.516183 0)
			(layer "B.Fab")
			(hide yes)
			(effects
				(font
					(size 1 1)
					(thickness 0.15)
				)
				(justify mirror)
			)
		)
		(property "Public" "False"
			(at 0 0 225)
			(unlocked yes)
			(layer "B.Fab")
			(hide yes)
			(effects
				(font
					(size 1 1)
					(thickness 0.15)
				)
				(justify mirror)
			)
		)
		(sheetname "/FPGA Power/")
		(sheetfile "FPGA_Power.kicad_sch")
		(attr smd)
		(fp_poly
			(pts
				(xy -0.7 0.35) (xy 0.7 0.35) (xy 0.7 -0.35) (xy -0.7 -0.35)
			)
			(stroke
				(width 0.05)
				(type default)
			)
			(fill no)
			(layer "B.CrtYd")
		)
		(fp_poly
			(pts
				(xy 0.3 -0.15) (xy -0.301 -0.15) (xy -0.301 0.149) (xy 0.3 0.149)
			)
			(stroke
				(width 0.15)
				(type solid)
			)
			(fill no)
			(layer "B.Fab")
		)
		(fp_text user "License: Apache-2.0"
			(at -0.72 -4.4 45)
			(layer "B.Fab")
			(effects
				(font
					(size 0.7 0.7)
					(thickness 0.15)
				)
				(justify left bottom mirror)
			)
		)
		(fp_text user "${REFERENCE}"
			(at -0.72 -3.4 45)
			(layer "B.Fab")
			(effects
				(font
					(size 0.7 0.7)
					(thickness 0.15)
				)
				(justify left bottom mirror)
			)
		)
		(fp_text user "Author: Antmicro"
			(at -0.72 -5.400001 45)
			(layer "B.Fab")
			(effects
				(font
					(size 0.7 0.7)
					(thickness 0.15)
				)
				(justify left bottom mirror)
			)
		)
		(pad "" smd roundrect
			(at -0.349 0.002 225)
			(size 0.318 0.36)
			(layers "B.Paste")
			(roundrect_rratio 0.25)
		)
		(pad "" smd roundrect
			(at 0.341 0.002 225)
			(size 0.318 0.36)
			(layers "B.Paste")
			(roundrect_rratio 0.25)
		)
		(pad "1" smd roundrect
			(at -0.321 0.002 225)
			(size 0.46 0.4)
			(layers "B.Cu" "B.Mask")
			(roundrect_rratio 0.25)
			(net 1 "GND")
			(pintype "passive")
		)
		(pad "2" smd roundrect
			(at 0.32 0.002 225)
			(size 0.46 0.4)
			(layers "B.Cu" "B.Mask")
			(roundrect_rratio 0.25)
			(net 13 "/FPGA Power/VCC_PLLDPHY")
			(pintype "passive")
		)
	)
	(footprint "antmicro-footprints:C_0201"
		(layer "B.Cu")
		(at 131.1 92.3 -90)
		(descr "Capacitor SMD 0201")
		(tags "capacitor SMD 0201")
		(property "Reference" "C102"
			(at -13.945736 9.07 90)
			(layer "B.SilkS")
			(effects
				(font
					(size 0.65 0.65)
					(thickness 0.15)
				)
				(justify left bottom mirror)
			)
		)
		(property "Value" "C_100n_0201"
			(at 0 -1.4 90)
			(layer "B.Fab")
			(hide yes)
			(effects
				(font
					(size 0.7 0.7)
					(thickness 0.15)
				)
				(justify left bottom mirror)
			)
		)
		(property "Datasheet" "https://www.yageo.com/en/Chart/Download/pdf/CC0201KRX6S5BB104"
			(at 0 0 270)
			(layer "F.Fab")
			(hide yes)
			(effects
				(font
					(size 1.27 1.27)
					(thickness 0.15)
				)
			)
		)
		(property "Description" "SMD Multilayer Ceramic Capacitor, 0.1 µF, 6.3 V, 0201 [0603 Metric], ± 10%, X6S, CC Series"
			(at 0 0 270)
			(layer "F.Fab")
			(hide yes)
			(effects
				(font
					(size 1.27 1.27)
					(thickness 0.15)
				)
			)
		)
		(property "Author" "Antmicro"
			(at 38.8 223.4 0)
			(layer "B.Fab")
			(hide yes)
			(effects
				(font
					(size 1 1)
					(thickness 0.15)
				)
				(justify mirror)
			)
		)
		(property "Dielectric" ""
			(at 38.8 223.4 0)
			(layer "B.Fab")
			(hide yes)
			(effects
				(font
					(size 1 1)
					(thickness 0.15)
				)
				(justify mirror)
			)
		)
		(property "License" "Apache-2.0"
			(at 38.8 223.4 0)
			(layer "B.Fab")
			(hide yes)
			(effects
				(font
					(size 1 1)
					(thickness 0.15)
				)
				(justify mirror)
			)
		)
		(property "MPN" "CC0201KRX6S5BB104"
			(at 38.8 223.4 0)
			(layer "B.Fab")
			(hide yes)
			(effects
				(font
					(size 1 1)
					(thickness 0.15)
				)
				(justify mirror)
			)
		)
		(property "Manufacturer" "YAGEO"
			(at 38.8 223.4 0)
			(layer "B.Fab")
			(hide yes)
			(effects
				(font
					(size 1 1)
					(thickness 0.15)
				)
				(justify mirror)
			)
		)
		(property "Val" "100n"
			(at 38.8 223.4 0)
			(layer "B.Fab")
			(hide yes)
			(effects
				(font
					(size 1 1)
					(thickness 0.15)
				)
				(justify mirror)
			)
		)
		(property "Voltage" ""
			(at 38.8 223.4 0)
			(layer "B.Fab")
			(hide yes)
			(effects
				(font
					(size 1 1)
					(thickness 0.15)
				)
				(justify mirror)
			)
		)
		(property "Public" "False"
			(at 0 0 270)
			(unlocked yes)
			(layer "B.Fab")
			(hide yes)
			(effects
				(font
					(size 1 1)
					(thickness 0.15)
				)
				(justify mirror)
			)
		)
		(sheetname "/FPGA Power/")
		(sheetfile "FPGA_Power.kicad_sch")
		(attr smd)
		(fp_rect
			(start -0.7 0.35)
			(end 0.7 -0.35)
			(stroke
				(width 0.05)
				(type default)
			)
			(fill no)
			(layer "B.CrtYd")
		)
		(fp_rect
			(start 0.3 -0.15)
			(end -0.301 0.149)
			(stroke
				(width 0.15)
				(type solid)
			)
			(fill no)
			(layer "B.Fab")
		)
		(fp_text user "Author: Antmicro"
			(at -0.72 -5.4 90)
			(layer "B.Fab")
			(effects
				(font
					(size 0.7 0.7)
					(thickness 0.15)
				)
				(justify left bottom mirror)
			)
		)
		(fp_text user "${REFERENCE}"
			(at -0.72 -3.4 90)
			(layer "B.Fab")
			(effects
				(font
					(size 0.7 0.7)
					(thickness 0.15)
				)
				(justify left bottom mirror)
			)
		)
		(fp_text user "License: Apache-2.0"
			(at -0.72 -4.4 90)
			(layer "B.Fab")
			(effects
				(font
					(size 0.7 0.7)
					(thickness 0.15)
				)
				(justify left bottom mirror)
			)
		)
		(pad "" smd roundrect
			(at -0.349 0.002 270)
			(size 0.318 0.36)
			(layers "B.Paste")
			(roundrect_rratio 0.25)
		)
		(pad "" smd roundrect
			(at 0.341 0.002 270)
			(size 0.318 0.36)
			(layers "B.Paste")
			(roundrect_rratio 0.25)
		)
		(pad "1" smd roundrect
			(at -0.321 0.002 270)
			(size 0.46 0.4)
			(layers "B.Cu" "B.Mask")
			(roundrect_rratio 0.25)
			(net 1 "GND")
			(pintype "passive")
		)
		(pad "2" smd roundrect
			(at 0.32 0.002 270)
			(size 0.46 0.4)
			(layers "B.Cu" "B.Mask")
			(roundrect_rratio 0.25)
			(net 12 "/FPGA Power/VCC_ADPHY")
			(pintype "passive")
		)
	)
	(footprint "antmicro-footprints:R_0402_1005Metric"
		(layer "B.Cu")
		(at 152.23 60.25 -90)
		(descr "Resistor SMD 0402")
		(tags "resistor SMD 0402")
		(property "Reference" "R8"
			(at -0.91 -1.3 90)
			(layer "B.SilkS")
			(effects
				(font
					(size 0.65 0.65)
					(thickness 0.15)
				)
				(justify left bottom mirror)
			)
		)
		(property "Value" "R_5k1_0402"
			(at 0 -1.4 90)
			(layer "B.Fab")
			(hide yes)
			(effects
				(font
					(size 0.7 0.7)
					(thickness 0.15)
				)
				(justify left bottom mirror)
			)
		)
		(property "Datasheet" "https://www.bourns.com/docs/product-datasheets/cr.pdf"
			(at 0 0 270)
			(layer "F.Fab")
			(hide yes)
			(effects
				(font
					(size 1.27 1.27)
					(thickness 0.15)
				)
			)
		)
		(property "Description" "SMD Chip Resistor, 5.1 kohm, ± 1%, 63 mW, 0402 [1005 Metric], Thick Film, General Purpose"
			(at 0 0 270)
			(layer "F.Fab")
			(hide yes)
			(effects
				(font
					(size 1.27 1.27)
					(thickness 0.15)
				)
			)
		)
		(property "Author" "Antmicro"
			(at 91.98 212.48 0)
			(layer "B.Fab")
			(hide yes)
			(effects
				(font
					(size 1 1)
					(thickness 0.15)
				)
				(justify mirror)
			)
		)
		(property "License" "Apache-2.0"
			(at 91.98 212.48 0)
			(layer "B.Fab")
			(hide yes)
			(effects
				(font
					(size 1 1)
					(thickness 0.15)
				)
				(justify mirror)
			)
		)
		(property "MPN" "CR0402-FX-5101GLF"
			(at 91.98 212.48 0)
			(layer "B.Fab")
			(hide yes)
			(effects
				(font
					(size 1 1)
					(thickness 0.15)
				)
				(justify mirror)
			)
		)
		(property "Manufacturer" "Bourns"
			(at 91.98 212.48 0)
			(layer "B.Fab")
			(hide yes)
			(effects
				(font
					(size 1 1)
					(thickness 0.15)
				)
				(justify mirror)
			)
		)
		(property "Tolerance" "1%"
			(at 91.98 212.48 0)
			(layer "B.Fab")
			(hide yes)
			(effects
				(font
					(size 1 1)
					(thickness 0.15)
				)
				(justify mirror)
			)
		)
		(property "Val" "5k1"
			(at 91.98 212.48 0)
			(layer "B.Fab")
			(hide yes)
			(effects
				(font
					(size 1 1)
					(thickness 0.15)
				)
				(justify mirror)
			)
		)
		(sheetname "/Peripherals/")
		(sheetfile "peripherals.kicad_sch")
		(attr smd)
		(fp_rect
			(start -0.925 0.47)
			(end 0.925 -0.47)
			(stroke
				(width 0.05)
				(type default)
			)
			(fill no)
			(layer "B.CrtYd")
		)
		(fp_rect
			(start -0.5 0.25)
			(end 0.5 -0.25)
			(stroke
				(width 0.15)
				(type solid)
			)
			(fill no)
			(layer "B.Fab")
		)
		(fp_text user "${REFERENCE}"
			(at -0.95 -3.168 90)
			(layer "B.Fab")
			(effects
				(font
					(size 0.7 0.7)
					(thickness 0.15)
				)
				(justify left bottom mirror)
			)
		)
		(fp_text user "License: Apache-2.0"
			(at -0.95 -5.169 90)
			(layer "B.Fab")
			(effects
				(font
					(size 0.7 0.7)
					(thickness 0.15)
				)
				(justify left bottom mirror)
			)
		)
		(fp_text user "Author: Antmicro"
			(at -0.95 -4.169 90)
			(layer "B.Fab")
			(effects
				(font
					(size 0.7 0.7)
					(thickness 0.15)
				)
				(justify left bottom mirror)
			)
		)
		(pad "1" smd roundrect
			(at -0.48 0 270)
			(size 0.59 0.64)
			(layers "B.Cu" "B.Mask" "B.Paste")
			(roundrect_rratio 0.25)
			(net 1 "GND")
			(pintype "passive")
		)
		(pad "2" smd roundrect
			(at 0.48 0 270)
			(size 0.59 0.64)
			(layers "B.Cu" "B.Mask" "B.Paste")
			(roundrect_rratio 0.25)
			(net 350 "Net-(J1-CC_{2})")
			(pintype "passive")
		)
	)
	(footprint "antmicro-footprints:C_0603_1608Metric"
		(layer "B.Cu")
		(at 132.48 97.73)
		(descr "Capacitor SMD 0603")
		(tags "capacitor 0603")
		(property "Reference" "C91"
			(at -3.2 0.69 0)
			(layer "B.SilkS")
			(effects
				(font
					(size 0.65 0.65)
					(thickness 0.15)
				)
				(justify right bottom mirror)
			)
		)
		(property "Value" "C_10u_0603"
			(at 0 -1.6 0)
			(layer "B.Fab")
			(hide yes)
			(effects
				(font
					(size 0.7 0.7)
					(thickness 0.15)
				)
				(justify right bottom mirror)
			)
		)
		(property "Datasheet" "https://www.murata.com/products/productdetail?partno=GRM188R61A106KE69%23"
			(at 0 0 0)
			(layer "F.Fab")
			(hide yes)
			(effects
				(font
					(size 1.27 1.27)
					(thickness 0.15)
				)
			)
		)
		(property "Description" "SMD Multilayer Ceramic Capacitor, 10 µF, 10 V, 0603 [1608 Metric], ± 10%, X5R, GRM Series"
			(at 0 0 0)
			(layer "F.Fab")
			(hide yes)
			(effects
				(font
					(size 1.27 1.27)
					(thickness 0.15)
				)
			)
		)
		(property "Author" "Antmicro"
			(at 0 0 0)
			(layer "B.Fab")
			(hide yes)
			(effects
				(font
					(size 1 1)
					(thickness 0.15)
				)
				(justify mirror)
			)
		)
		(property "License" "Apache-2.0"
			(at 0 0 0)
			(layer "B.Fab")
			(hide yes)
			(effects
				(font
					(size 1 1)
					(thickness 0.15)
				)
				(justify mirror)
			)
		)
		(property "MPN" "GRM188R61A106KE69D"
			(at 0 0 0)
			(layer "B.Fab")
			(hide yes)
			(effects
				(font
					(size 1 1)
					(thickness 0.15)
				)
				(justify mirror)
			)
		)
		(property "Manufacturer" "Murata"
			(at 0 0 0)
			(layer "B.Fab")
			(hide yes)
			(effects
				(font
					(size 1 1)
					(thickness 0.15)
				)
				(justify mirror)
			)
		)
		(property "Val" "10u"
			(at 0 0 0)
			(layer "B.Fab")
			(hide yes)
			(effects
				(font
					(size 1 1)
					(thickness 0.15)
				)
				(justify mirror)
			)
		)
		(property "Voltage" ""
			(at 0 0 0)
			(layer "B.Fab")
			(hide yes)
			(effects
				(font
					(size 1 1)
					(thickness 0.15)
				)
				(justify mirror)
			)
		)
		(property "Dielectric" "template_dielectric"
			(at 0 0 0)
			(unlocked yes)
			(layer "B.Fab")
			(hide yes)
			(effects
				(font
					(size 1 1)
					(thickness 0.15)
				)
				(justify mirror)
			)
		)
		(sheetname "/FPGA Power/")
		(sheetfile "FPGA_Power.kicad_sch")
		(attr smd)
		(fp_line
			(start -0.15 -0.4)
			(end 0.15 -0.4)
			(stroke
				(width 0.15)
				(type solid)
			)
			(layer "B.SilkS")
		)
		(fp_line
			(start -0.15 0.4)
			(end 0.15 0.4)
			(stroke
				(width 0.15)
				(type solid)
			)
			(layer "B.SilkS")
		)
		(fp_rect
			(start -1.25 0.65)
			(end 1.25 -0.65)
			(stroke
				(width 0.05)
				(type solid)
			)
			(fill no)
			(layer "B.CrtYd")
		)
		(fp_rect
			(start -0.8 0.4)
			(end 0.8 -0.4)
			(stroke
				(width 0.15)
				(type solid)
			)
			(fill no)
			(layer "B.Fab")
		)
		(fp_text user "License: Apache-2.0"
			(at -1.682 -5.895 180)
			(layer "B.Fab")
			(effects
				(font
					(size 0.7 0.7)
					(thickness 0.15)
				)
				(justify left bottom mirror)
			)
		)
		(fp_text user "${REFERENCE}"
			(at -1.682 -3.895 180)
			(layer "B.Fab")
			(effects
				(font
					(size 0.7 0.7)
					(thickness 0.15)
				)
				(justify left bottom mirror)
			)
		)
		(fp_text user "Author: Antmicro"
			(at -1.682 -4.894 180)
			(layer "B.Fab")
			(effects
				(font
					(size 0.7 0.7)
					(thickness 0.15)
				)
				(justify left bottom mirror)
			)
		)
		(pad "1" smd roundrect
			(at -0.7 0)
			(size 0.8 1)
			(layers "B.Cu" "B.Mask" "B.Paste")
			(roundrect_rratio 0.2)
			(net 1 "GND")
			(pintype "passive")
		)
		(pad "2" smd roundrect
			(at 0.7 0)
			(size 0.8 1)
			(layers "B.Cu" "B.Mask" "B.Paste")
			(roundrect_rratio 0.2)
			(net 13 "/FPGA Power/VCC_PLLDPHY")
			(pintype "passive")
		)
	)
	(footprint "antmicro-footprints:TP_SMD_0.75mm"
		(layer "B.Cu")
		(at 98.44 88.2 90)
		(property "Reference" "TP29"
			(at 0.76 0.39 90)
			(layer "B.SilkS")
			(effects
				(font
					(size 0.65 0.65)
					(thickness 0.15)
				)
				(justify right bottom mirror)
			)
		)
		(property "Value" "TP_0.75mm_SMD"
			(at 0 -1.2 90)
			(layer "B.Fab")
			(hide yes)
			(effects
				(font
					(size 0.7 0.7)
					(thickness 0.15)
				)
				(justify right bottom mirror)
			)
		)
		(property "Description" "SMT test point"
			(at 0 0 90)
			(layer "F.Fab")
			(hide yes)
			(effects
				(font
					(size 1.27 1.27)
					(thickness 0.15)
				)
			)
		)
		(property "Author" "Antmicro"
			(at 186.64 -10.24 0)
			(layer "B.Fab")
			(hide yes)
			(effects
				(font
					(size 1 1)
					(thickness 0.15)
				)
				(justify mirror)
			)
		)
		(property "License" "Apache-2.0"
			(at 186.64 -10.24 0)
			(layer "B.Fab")
			(hide yes)
			(effects
				(font
					(size 1 1)
					(thickness 0.15)
				)
				(justify mirror)
			)
		)
		(property "MPN" ""
			(at 186.64 -10.24 0)
			(layer "B.Fab")
			(hide yes)
			(effects
				(font
					(size 1 1)
					(thickness 0.15)
				)
				(justify mirror)
			)
		)
		(property "Manufacturer" ""
			(at 186.64 -10.24 0)
			(layer "B.Fab")
			(hide yes)
			(effects
				(font
					(size 1 1)
					(thickness 0.15)
				)
				(justify mirror)
			)
		)
		(sheetname "/SDI/")
		(sheetfile "sdi.kicad_sch")
		(attr exclude_from_pos_files)
		(fp_circle
			(center 0 0)
			(end 0.475 0)
			(stroke
				(width 0.05)
				(type default)
			)
			(fill no)
			(layer "B.CrtYd")
		)
		(fp_text user "Author: Antmicro"
			(at -0.4 -3.901 270)
			(layer "B.Fab")
			(effects
				(font
					(size 0.7 0.7)
					(thickness 0.15)
				)
				(justify left bottom mirror)
			)
		)
		(fp_text user "License: Apache-2.0"
			(at -0.4 -5.101 270)
			(layer "B.Fab")
			(effects
				(font
					(size 0.7 0.7)
					(thickness 0.15)
				)
				(justify left bottom mirror)
			)
		)
		(fp_text user "${REFERENCE}"
			(at -0.4 -2.7 270)
			(layer "B.Fab")
			(effects
				(font
					(size 0.7 0.7)
					(thickness 0.15)
				)
				(justify left bottom mirror)
			)
		)
		(pad "1" smd circle
			(at 0 0 90)
			(size 0.75 0.75)
			(layers "B.Cu" "B.Mask")
			(net 201 "/SDI/~{SMPTE_BYPASS}")
			(pinfunction "1")
			(pintype "passive")
		)
	)
	(footprint "antmicro-footprints:FB_0603_1608Metric"
		(layer "B.Cu")
		(at 137.48 91.68)
		(property "Reference" "FB2"
			(at 1.05 1.46 180)
			(layer "B.SilkS")
			(effects
				(font
					(size 0.65 0.65)
					(thickness 0.15)
				)
				(justify left bottom mirror)
			)
		)
		(property "Value" "FB_120Z_2A_0603"
			(at 0 -1.5 180)
			(layer "B.Fab")
			(hide yes)
			(effects
				(font
					(size 0.7 0.7)
					(thickness 0.15)
				)
				(justify left bottom mirror)
			)
		)
		(property "Datasheet" "https://www.murata.com/en-us/products/productdata/8796738650142/ENFA0003.pdf"
			(at 0 0 0)
			(layer "F.Fab")
			(hide yes)
			(effects
				(font
					(size 1.27 1.27)
					(thickness 0.15)
				)
			)
		)
		(property "Description" "Ferrite Bead, 0603 [1608 Metric], 120 ohm, 2 A, BLM18P, 0.05 ohm, ± 25%, DC power line"
			(at 0 0 0)
			(layer "F.Fab")
			(hide yes)
			(effects
				(font
					(size 1.27 1.27)
					(thickness 0.15)
				)
			)
		)
		(property "Author" "Antmicro"
			(at 0 0 0)
			(layer "B.Fab")
			(hide yes)
			(effects
				(font
					(size 1 1)
					(thickness 0.15)
				)
				(justify mirror)
			)
		)
		(property "License" "Apache-2.0"
			(at 0 0 0)
			(layer "B.Fab")
			(hide yes)
			(effects
				(font
					(size 1 1)
					(thickness 0.15)
				)
				(justify mirror)
			)
		)
		(property "MPN" "BLM18PG121SN1D"
			(at 0 0 0)
			(layer "B.Fab")
			(hide yes)
			(effects
				(font
					(size 1 1)
					(thickness 0.15)
				)
				(justify mirror)
			)
		)
		(property "Manufacturer" "Murata"
			(at 0 0 0)
			(layer "B.Fab")
			(hide yes)
			(effects
				(font
					(size 1 1)
					(thickness 0.15)
				)
				(justify mirror)
			)
		)
		(property "Val" "120Z/2A"
			(at 0 0 0)
			(unlocked yes)
			(layer "B.Fab")
			(hide yes)
			(effects
				(font
					(size 1 1)
					(thickness 0.15)
				)
				(justify mirror)
			)
		)
		(property "Current" ""
			(at 0 0 0)
			(unlocked yes)
			(layer "B.Fab")
			(hide yes)
			(effects
				(font
					(size 1 1)
					(thickness 0.15)
				)
				(justify mirror)
			)
		)
		(sheetname "/FPGA Power/")
		(sheetfile "FPGA_Power.kicad_sch")
		(attr smd)
		(fp_line
			(start -0.15 -0.4)
			(end 0.15 -0.4)
			(stroke
				(width 0.15)
				(type solid)
			)
			(layer "B.SilkS")
		)
		(fp_line
			(start -0.15 0.4)
			(end 0.15 0.4)
			(stroke
				(width 0.15)
				(type solid)
			)
			(layer "B.SilkS")
		)
		(fp_rect
			(start -1.25 0.65)
			(end 1.25 -0.65)
			(stroke
				(width 0.05)
				(type solid)
			)
			(fill no)
			(layer "B.CrtYd")
		)
		(fp_line
			(start -0.803 -0.406)
			(end -0.803 0.408)
			(stroke
				(width 0.15)
				(type solid)
			)
			(layer "B.Fab")
		)
		(fp_line
			(start 0.8 -0.406)
			(end -0.803 -0.406)
			(stroke
				(width 0.15)
				(type solid)
			)
			(layer "B.Fab")
		)
		(fp_line
			(start 0.8 0.408)
			(end -0.803 0.408)
			(stroke
				(width 0.15)
				(type solid)
			)
			(layer "B.Fab")
		)
		(fp_line
			(start 0.8 0.408)
			(end 0.8 -0.406)
			(stroke
				(width 0.15)
				(type solid)
			)
			(layer "B.Fab")
		)
		(fp_text user "${REFERENCE}"
			(at -1.653 -4.6 180)
			(layer "B.Fab")
			(effects
				(font
					(size 0.7 0.7)
					(thickness 0.15)
				)
				(justify left bottom mirror)
			)
		)
		(fp_text user "License: Apache-2.0"
			(at -1.653 -5.9 180)
			(layer "B.Fab")
			(effects
				(font
					(size 0.7 0.7)
					(thickness 0.15)
				)
				(justify left bottom mirror)
			)
		)
		(fp_text user "Author: Antmicro"
			(at -1.653 -3.162 180)
			(layer "B.Fab")
			(effects
				(font
					(size 0.7 0.7)
					(thickness 0.15)
				)
				(justify left bottom mirror)
			)
		)
		(pad "1" smd roundrect
			(at -0.7 0)
			(size 0.8 1)
			(layers "B.Cu" "B.Mask" "B.Paste")
			(roundrect_rratio 0.2)
			(net 10 "/FPGA Power/VCC_AUXA")
			(pintype "passive")
		)
		(pad "2" smd roundrect
			(at 0.7 0)
			(size 0.8 1)
			(layers "B.Cu" "B.Mask" "B.Paste")
			(roundrect_rratio 0.2)
			(net 50 "+1V8")
			(pintype "passive")
		)
	)
	(footprint "antmicro-footprints:R_0402_1005Metric"
		(layer "B.Cu")
		(at 155.89 72.9 90)
		(descr "Resistor SMD 0402")
		(tags "resistor SMD 0402")
		(property "Reference" "R98"
			(at 0.96 -0.66 270)
			(layer "B.SilkS")
			(effects
				(font
					(size 0.65 0.65)
					(thickness 0.15)
				)
				(justify left bottom mirror)
			)
		)
		(property "Value" "R_10k_0402"
			(at 0 -1.4 270)
			(layer "B.Fab")
			(hide yes)
			(effects
				(font
					(size 0.7 0.7)
					(thickness 0.15)
				)
				(justify left bottom mirror)
			)
		)
		(property "Datasheet" "https://www.bourns.com/docs/product-datasheets/cr.pdf"
			(at 0 0 90)
			(layer "F.Fab")
			(hide yes)
			(effects
				(font
					(size 1.27 1.27)
					(thickness 0.15)
				)
			)
		)
		(property "Description" "SMD Chip Resistor, 10 kohm, ± 1%, 62.5 mW, 0402 [1005 Metric], Thick Film, General Purpose"
			(at 0 0 90)
			(layer "F.Fab")
			(hide yes)
			(effects
				(font
					(size 1.27 1.27)
					(thickness 0.15)
				)
			)
		)
		(property "Author" "Antmicro"
			(at 228.79 -82.99 0)
			(layer "B.Fab")
			(hide yes)
			(effects
				(font
					(size 1 1)
					(thickness 0.15)
				)
				(justify mirror)
			)
		)
		(property "License" "Apache-2.0"
			(at 228.79 -82.99 0)
			(layer "B.Fab")
			(hide yes)
			(effects
				(font
					(size 1 1)
					(thickness 0.15)
				)
				(justify mirror)
			)
		)
		(property "MPN" "CR0402-FX-1002GLF"
			(at 228.79 -82.99 0)
			(layer "B.Fab")
			(hide yes)
			(effects
				(font
					(size 1 1)
					(thickness 0.15)
				)
				(justify mirror)
			)
		)
		(property "Manufacturer" "Bourns"
			(at 228.79 -82.99 0)
			(layer "B.Fab")
			(hide yes)
			(effects
				(font
					(size 1 1)
					(thickness 0.15)
				)
				(justify mirror)
			)
		)
		(property "Tolerance" "1%"
			(at 228.79 -82.99 0)
			(layer "B.Fab")
			(hide yes)
			(effects
				(font
					(size 1 1)
					(thickness 0.15)
				)
				(justify mirror)
			)
		)
		(property "Val" "10k"
			(at 228.79 -82.99 0)
			(layer "B.Fab")
			(hide yes)
			(effects
				(font
					(size 1 1)
					(thickness 0.15)
				)
				(justify mirror)
			)
		)
		(sheetname "/Power Supply/")
		(sheetfile "supply.kicad_sch")
		(attr smd)
		(fp_rect
			(start -0.925 0.47)
			(end 0.925 -0.47)
			(stroke
				(width 0.05)
				(type default)
			)
			(fill no)
			(layer "B.CrtYd")
		)
		(fp_rect
			(start -0.5 0.25)
			(end 0.5 -0.25)
			(stroke
				(width 0.15)
				(type solid)
			)
			(fill no)
			(layer "B.Fab")
		)
		(fp_text user "Author: Antmicro"
			(at -0.95 -4.169 270)
			(layer "B.Fab")
			(effects
				(font
					(size 0.7 0.7)
					(thickness 0.15)
				)
				(justify left bottom mirror)
			)
		)
		(fp_text user "License: Apache-2.0"
			(at -0.95 -5.169 270)
			(layer "B.Fab")
			(effects
				(font
					(size 0.7 0.7)
					(thickness 0.15)
				)
				(justify left bottom mirror)
			)
		)
		(fp_text user "${REFERENCE}"
			(at -0.95 -3.168 270)
			(layer "B.Fab")
			(effects
				(font
					(size 0.7 0.7)
					(thickness 0.15)
				)
				(justify left bottom mirror)
			)
		)
		(pad "1" smd roundrect
			(at -0.48 0 90)
			(size 0.59 0.64)
			(layers "B.Cu" "B.Mask" "B.Paste")
			(roundrect_rratio 0.25)
			(net 1 "GND")
			(pintype "passive")
		)
		(pad "2" smd roundrect
			(at 0.48 0 90)
			(size 0.59 0.64)
			(layers "B.Cu" "B.Mask" "B.Paste")
			(roundrect_rratio 0.25)
			(net 349 "Net-(U4-ILIM)")
			(pintype "passive")
		)
	)
	(gr_line
		(start 175.03 124.15)
		(end 175.03 56.15)
		(stroke
			(width 0.12)
			(type solid)
		)
		(layer "Edge.Cuts")
	)
	(gr_line
		(start 76.03 125.15)
		(end 174.03 125.15)
		(stroke
			(width 0.12)
			(type solid)
		)
		(layer "Edge.Cuts")
	)
	(gr_arc
		(start 174.03 55.15)
		(mid 174.737107 55.442893)
		(end 175.03 56.15)
		(stroke
			(width 0.12)
			(type solid)
		)
		(layer "Edge.Cuts")
	)
	(gr_arc
		(start 76.03 125.15)
		(mid 75.322893 124.857107)
		(end 75.03 124.15)
		(stroke
			(width 0.12)
			(type solid)
		)
		(layer "Edge.Cuts")
	)
	(gr_arc
		(start 175.03 124.15)
		(mid 174.737107 124.857107)
		(end 174.03 125.15)
		(stroke
			(width 0.12)
			(type solid)
		)
		(layer "Edge.Cuts")
	)
	(gr_line
		(start 75.03 56.15)
		(end 75.03 124.15)
		(stroke
			(width 0.12)
			(type solid)
		)
		(layer "Edge.Cuts")
	)
	(gr_arc
		(start 75.03 56.15)
		(mid 75.322893 55.442893)
		(end 76.03 55.15)
		(stroke
			(width 0.12)
			(type solid)
		)
		(layer "Edge.Cuts")
	)
	(gr_line
		(start 174.03 55.15)
		(end 76.03 55.15)
		(stroke
			(width 0.12)
			(type solid)
		)
		(layer "Edge.Cuts")
	)
	(gr_text "SDI-MIPI Video Converter\nRev. 1.1.4 10/2023"
		(at 94.28 64.4 0)
		(layer "F.Cu")
		(effects
			(font
				(size 0.8 0.8)
				(thickness 0.125)
			)
			(justify left)
		)
	)
	(segment
		(start 129.085 62.37)
		(end 129.48 62.765)
		(width 0.3)
		(layer "F.Cu")
		(net 1)
	)
	(segment
		(start 132.7 83.9)
		(end 132.3 84.3)
		(width 0.3)
		(layer "F.Cu")
		(net 1)
	)
	(segment
		(start 94.1 77.4)
		(end 94.6 77.9)
		(width 0.5)
		(layer "F.Cu")
		(net 1)
	)
	(segment
		(start 105.61 74.15)
		(end 108.75 74.15)
		(width 0.15)
		(layer "F.Cu")
		(net 1)
	)
	(segment
		(start 167.03 87.35)
		(end 166.63 87.35)
		(width 0.2)
		(layer "F.Cu")
		(net 1)
	)
	(segment
		(start 105.61 74.15)
		(end 103.78 74.15)
		(width 0.15)
		(layer "F.Cu")
		(net 1)
	)
	(segment
		(start 90.975 105.525)
		(end 91.615 105.525)
		(width 0.3)
		(layer "F.Cu")
		(net 1)
	)
	(segment
		(start 124.7 95.1)
		(end 125.1 95.5)
		(width 0.3)
		(layer "F.Cu")
		(net 1)
	)
	(segment
		(start 170.105 114.345)
		(end 170.09 114.33)
		(width 0.3)
		(layer "F.Cu")
		(net 1)
	)
	(segment
		(start 125.9 96.3)
		(end 125.9 97.01)
		(width 0.1)
		(layer "F.Cu")
		(net 1)
	)
	(segment
		(start 121.18 120.125)
		(end 121.18 121.15)
		(width 0.3)
		(layer "F.Cu")
		(net 1)
	)
	(segment
		(start 157.03 89.35)
		(end 155.98 89.35)
		(width 0.15)
		(layer "F.Cu")
		(net 1)
	)
	(segment
		(start 162.83 120.95)
		(end 162.81 120.97)
		(width 0.3)
		(layer "F.Cu")
		(net 1)
	)
	(segment
		(start 109.6 97)
		(end 109.000419 97.599581)
		(width 0.15)
		(layer "F.Cu")
		(net 1)
	)
	(segment
		(start 130.3 89.5)
		(end 130.7 89.9)
		(width 0.3)
		(layer "F.Cu")
		(net 1)
	)
	(segment
		(start 163.39 81.15)
		(end 163.39 80.2)
		(width 0.3)
		(layer "F.Cu")
		(net 1)
	)
	(segment
		(start 165.785 59.15)
		(end 166.39 59.15)
		(width 0.3)
		(layer "F.Cu")
		(net 1)
	)
	(segment
		(start 163.59 76.6)
		(end 162.39 76.6)
		(width 0.3)
		(layer "F.Cu")
		(net 1)
	)
	(segment
		(start 169.435 85.945)
		(end 169.43 85.95)
		(width 0.2)
		(layer "F.Cu")
		(net 1)
	)
	(segment
		(start 125.9 95.5)
		(end 126.3 95.9)
		(width 0.3)
		(layer "F.Cu")
		(net 1)
	)
	(segment
		(start 126.7 85.1)
		(end 126.3 84.7)
		(width 0.3)
		(layer "F.Cu")
		(net 1)
	)
	(segment
		(start 160.25 123.3)
		(end 160.9 123.3)
		(width 0.15)
		(layer "F.Cu")
		(net 1)
	)
	(segment
		(start 162.5 94.97)
		(end 162.5 95.8)
		(width 0.2)
		(layer "F.Cu")
		(net 1)
	)
	(segment
		(start 83.7 110.78)
		(end 83.69 110.79)
		(width 0.3)
		(layer "F.Cu")
		(net 1)
	)
	(segment
		(start 96.81 89.13)
		(end 96.96 88.98)
		(width 0.15)
		(layer "F.Cu")
		(net 1)
	)
	(segment
		(start 125.9 96.3)
		(end 125.9 96.9)
		(width 0.3)
		(layer "F.Cu")
		(net 1)
	)
	(segment
		(start 120.450023 70.5545)
		(end 121.0455 70.5545)
		(width 0.3)
		(layer "F.Cu")
		(net 1)
	)
	(segment
		(start 173.38 81.7)
		(end 173.38 80.95)
		(width 0.2)
		(layer "F.Cu")
		(net 1)
	)
	(segment
		(start 170.635 106.895)
		(end 170.64 106.9)
		(width 0.3)
		(layer "F.Cu")
		(net 1)
	)
	(segment
		(start 169.6 108.395)
		(end 170.645 108.395)
		(width 0.3)
		(layer "F.Cu")
		(net 1)
	)
	(segment
		(start 126.3 95.9)
		(end 126.7 95.5)
		(width 0.3)
		(layer "F.Cu")
		(net 1)
	)
	(segment
		(start 122.3 89.5)
		(end 122.315979 89.5)
		(width 0.1)
		(layer "F.Cu")
		(net 1)
	)
	(segment
		(start 110.73 120.49)
		(end 110.72 120.48)
		(width 0.3)
		(layer "F.Cu")
		(net 1)
	)
	(segment
		(start 169.6 99.395)
		(end 170.635 99.395)
		(width 0.3)
		(layer "F.Cu")
		(net 1)
	)
	(segment
		(start 129.5 87.1)
		(end 129.5 87.12)
		(width 0.3)
		(layer "F.Cu")
		(net 1)
	)
	(segment
		(start 121.18 121.15)
		(end 121.12751 121.20249)
		(width 0.3)
		(layer "F.Cu")
		(net 1)
	)
	(segment
		(start 127.46 68.14)
		(end 127.96 68.14)
		(width 0.3)
		(layer "F.Cu")
		(net 1)
	)
	(segment
		(start 121.5 86.3)
		(end 121.9 86.7)
		(width 0.3)
		(layer "F.Cu")
		(net 1)
	)
	(segment
		(start 125.5 90.3)
		(end 125.9 89.9)
		(width 0.3)
		(layer "F.Cu")
		(net 1)
	)
	(segment
		(start 121.06 62.54)
		(end 120.66 62.54)
		(width 0.3)
		(layer "F.Cu")
		(net 1)
	)
	(segment
		(start 121.5 94.3)
		(end 121.9 93.9)
		(width 0.3)
		(layer "F.Cu")
		(net 1)
	)
	(segment
		(start 119.68 120.125)
		(end 119.68 121.12)
		(width 0.3)
		(layer "F.Cu")
		(net 1)
	)
	(segment
		(start 147.7 123.8)
		(end 147.7 120.8)
		(width 0.15)
		(layer "F.Cu")
		(net 1)
	)
	(segment
		(start 161.38 86.65)
		(end 159.03 86.65)
		(width 0.3)
		(layer "F.Cu")
		(net 1)
	)
	(segment
		(start 173.405 69.35)
		(end 172.34 69.35)
		(width 0.3)
		(layer "F.Cu")
		(net 1)
	)
	(segment
		(start 165.53 88.1)
		(end 166.98 88.1)
		(width 0.2)
		(layer "F.Cu")
		(net 1)
	)
	(segment
		(start 120.7 89.5)
		(end 121.1 89.1)
		(width 0.3)
		(layer "F.Cu")
		(net 1)
	)
	(segment
		(start 173.38 82.55)
		(end 173.38 81.7)
		(width 0.2)
		(layer "F.Cu")
		(net 1)
	)
	(segment
		(start 91.8 68.06)
		(end 91.78 68.04)
		(width 0.3)
		(layer "F.Cu")
		(net 1)
	)
	(segment
		(start 120.8295 97.13749)
		(end 121.1 96.86699)
		(width 0.3)
		(layer "F.Cu")
		(net 1)
	)
	(segment
		(start 91.8 68.715)
		(end 91.8 68.06)
		(width 0.3)
		(layer "F.Cu")
		(net 1)
	)
	(segment
		(start 130.7 93.9)
		(end 131.1 94.3)
		(width 0.3)
		(layer "F.Cu")
		(net 1)
	)
	(segment
		(start 126.3 87.9)
		(end 126.7 87.5)
		(width 0.3)
		(layer "F.Cu")
		(net 1)
	)
	(segment
		(start 122.161665 65.299464)
		(end 122.161665 65.241665)
		(width 0.3)
		(layer "F.Cu")
		(net 1)
	)
	(segment
		(start 126.3 84.7)
		(end 125.9 85.1)
		(width 0.3)
		(layer "F.Cu")
		(net 1)
	)
	(segment
		(start 116.68 120.125)
		(end 116.68 121.11)
		(width 0.3)
		(layer "F.Cu")
		(net 1)
	)
	(segment
		(start 123.9 87.1)
		(end 124.3 86.7)
		(width 0.3)
		(layer "F.Cu")
		(net 1)
	)
	(segment
		(start 160.69 80.1)
		(end 161.18 80.1)
		(width 0.3)
		(layer "F.Cu")
		(net 1)
	)
	(segment
		(start 129.5 87.12)
		(end 129.12 87.5)
		(width 0.3)
		(layer "F.Cu")
		(net 1)
	)
	(segment
		(start 92.1 77.4)
		(end 92.6 77.9)
		(width 0.5)
		(layer "F.Cu")
		(net 1)
	)
	(segment
		(start 139.13 120.01)
		(end 139.14 120)
		(width 0.3)
		(layer "F.Cu")
		(net 1)
	)
	(segment
		(start 121.5 89.5)
		(end 121.9 89.1)
		(width 0.3)
		(layer "F.Cu")
		(net 1)
	)
	(segment
		(start 169.53 73.65)
		(end 170.74 73.65)
		(width 0.3)
		(layer "F.Cu")
		(net 1)
	)
	(segment
		(start 103.75 90.6955)
		(end 103.75 92.14)
		(width 0.3)
		(layer "F.Cu")
		(net 1)
	)
	(segment
		(start 120.3 84.3)
		(end 119.8295 83.8295)
		(width 0.3)
		(layer "F.Cu")
		(net 1)
	)
	(segment
		(start 127.5 93.1)
		(end 127.1 92.7)
		(width 0.3)
		(layer "F.Cu")
		(net 1)
	)
	(segment
		(start 121.9 85.9)
		(end 122.3 86.3)
		(width 0.3)
		(layer "F.Cu")
		(net 1)
	)
	(segment
		(start 82.035 107.635)
		(end 82.01 107.61)
		(width 0.3)
		(layer "F.Cu")
		(net 1)
	)
	(segment
		(start 125.4995 95.1)
		(end 125.5 95.1)
		(width 0.3)
		(layer "F.Cu")
		(net 1)
	)
	(segment
		(start 92.1 79.4)
		(end 92.6 79.9)
		(width 0.5)
		(layer "F.Cu")
		(net 1)
	)
	(segment
		(start 88 78.385)
		(end 87.315 78.385)
		(width 0.3)
		(layer "F.Cu")
		(net 1)
	)
	(segment
		(start 127.5 86.71)
		(end 127.89 87.1)
		(width 0.3)
		(layer "F.Cu")
		(net 1)
	)
	(segment
		(start 137.49 110)
		(end 137.19 109.7)
		(width 0.5)
		(layer "F.Cu")
		(net 1)
	)
	(segment
		(start 111.79 103)
		(end 111.79 103.4)
		(width 0.3)
		(layer "F.Cu")
		(net 1)
	)
	(segment
		(start 147.7 120.8)
		(end 147.75 120.75)
		(width 0.15)
		(layer "F.Cu")
		(net 1)
	)
	(segment
		(start 160.9 123.3)
		(end 160.91 123.31)
		(width 0.15)
		(layer "F.Cu")
		(net 1)
	)
	(segment
		(start 110.73 122.225)
		(end 110.73 120.49)
		(width 0.3)
		(layer "F.Cu")
		(net 1)
	)
	(segment
		(start 172.24 74.95)
		(end 172.19 75)
		(width 0.3)
		(layer "F.Cu")
		(net 1)
	)
	(segment
		(start 138.845 56.855)
		(end 139.53 56.855)
		(width 0.3)
		(layer "F.Cu")
		(net 1)
	)
	(segment
		(start 142.05 120.8)
		(end 142.05 122.65)
		(width 0.15)
		(layer "F.Cu")
		(net 1)
	)
	(segment
		(start 126.7 93.1)
		(end 127.1 92.7)
		(width 0.3)
		(layer "F.Cu")
		(net 1)
	)
	(segment
		(start 101.42 85.6)
		(end 101.77 85.6)
		(width 0.15)
		(layer "F.Cu")
		(net 1)
	)
	(segment
		(start 132.72 91.85)
		(end 132.72 91.9005)
		(width 0.3)
		(layer "F.Cu")
		(net 1)
	)
	(segment
		(start 99.1 79.4)
		(end 99.6 79.9)
		(width 0.5)
		(layer "F.Cu")
		(net 1)
	)
	(segment
		(start 127.9 87.056224)
		(end 127.543776 86.7)
		(width 0.1)
		(layer "F.Cu")
		(net 1)
	)
	(segment
		(start 125.599946 111.642026)
		(end 125.425535 111.642026)
		(width 0.15)
		(layer "F.Cu")
		(net 1)
	)
	(segment
		(start 125.4995 95.0995)
		(end 125.1 94.7)
		(width 0.3)
		(layer "F.Cu")
		(net 1)
	)
	(segment
		(start 128.39 62.54)
		(end 128.56 62.37)
		(width 0.3)
		(layer "F.Cu")
		(net 1)
	)
	(segment
		(start 125.9 87.5)
		(end 126.3 87.9)
		(width 0.3)
		(layer "F.Cu")
		(net 1)
	)
	(segment
		(start 160.95 119)
		(end 160.97 118.98)
		(width 0.15)
		(layer "F.Cu")
		(net 1)
	)
	(segment
		(start 119.9 87.9)
		(end 119.9 87.97)
		(width 0.1)
		(layer "F.Cu")
		(net 1)
	)
	(segment
		(start 125.1 85.9)
		(end 125.5 85.5)
		(width 0.3)
		(layer "F.Cu")
		(net 1)
	)
	(segment
		(start 121.9 86.7)
		(end 122.7 85.9)
		(width 0.3)
		(layer "F.Cu")
		(net 1)
	)
	(segment
		(start 101 119.99)
		(end 100.99 119.98)
		(width 0.3)
		(layer "F.Cu")
		(net 1)
	)
	(segment
		(start 121.46 67.74)
		(end 121.86 68.14)
		(width 0.3)
		(layer "F.Cu")
		(net 1)
	)
	(segment
		(start 137.19 109.7)
		(end 137.905 109.7)
		(width 0.5)
		(layer "F.Cu")
		(net 1)
	)
	(segment
		(start 157.59 82.7)
		(end 156.550274 82.7)
		(width 0.3)
		(layer "F.Cu")
		(net 1)
	)
	(segment
		(start 99.73 121.9875)
		(end 99.73 120.03)
		(width 0.3)
		(layer "F.Cu")
		(net 1)
	)
	(segment
		(start 110.4 94.6)
		(end 110.4 94)
		(width 0.15)
		(layer "F.Cu")
		(net 1)
	)
	(segment
		(start 119.68 121.12)
		(end 119.69 121.13)
		(width 0.3)
		(layer "F.Cu")
		(net 1)
	)
	(segment
		(start 101.8655 102.775)
		(end 101.84 102.7495)
		(width 0.15)
		(layer "F.Cu")
		(net 1)
	)
	(segment
		(start 106.005 98.7)
		(end 105.4195 98.7)
		(width 0.3)
		(layer "F.Cu")
		(net 1)
	)
	(segment
		(start 165.63 119.9)
		(end 165.63 120.91)
		(width 0.3)
		(layer "F.Cu")
		(net 1)
	)
	(segment
		(start 162.43 86.15)
		(end 162.43 84.18)
		(width 0.3)
		(layer "F.Cu")
		(net 1)
	)
	(segment
		(start 167.03 86.85)
		(end 167.03 87.35)
		(width 0.2)
		(layer "F.Cu")
		(net 1)
	)
	(segment
		(start 122.315979 89.5)
		(end 122.7 89.115979)
		(width 0.1)
		(layer "F.Cu")
		(net 1)
	)
	(segment
		(start 125.5 95.9)
		(end 125.9 95.5)
		(width 0.3)
		(layer "F.Cu")
		(net 1)
	)
	(segment
		(start 92.1 76.4)
		(end 92.6 76.9)
		(width 0.5)
		(layer "F.Cu")
		(net 1)
	)
	(segment
		(start 97.1 74.4)
		(end 96.6 74.9)
		(width 0.1)
		(layer "F.Cu")
		(net 1)
	)
	(segment
		(start 126.3 94.3)
		(end 126.7 93.9)
		(width 0.3)
		(layer "F.Cu")
		(net 1)
	)
	(segment
		(start 83.7 110.135)
		(end 83.7 110.78)
		(width 0.3)
		(layer "F.Cu")
		(net 1)
	)
	(segment
		(start 125.1 95.5)
		(end 125.5 95.9)
		(width 0.3)
		(layer "F.Cu")
		(net 1)
	)
	(segment
		(start 125.4995 95.1)
		(end 125.4995 95.0995)
		(width 0.3)
		(layer "F.Cu")
		(net 1)
	)
	(segment
		(start 161.18 80.1)
		(end 161.28 80.2)
		(width 0.3)
		(layer "F.Cu")
		(net 1)
	)
	(segment
		(start 119.8295 83.8295)
		(end 119.82 83.8295)
		(width 0.3)
		(layer "F.Cu")
		(net 1)
	)
	(segment
		(start 124.467561 112.6)
		(end 124.08 112.6)
		(width 0.15)
		(layer "F.Cu")
		(net 1)
	)
	(segment
		(start 109.5 93)
		(end 109.505317 93)
		(width 0.15)
		(layer "F.Cu")
		(net 1)
	)
	(segment
		(start 128.06 59.34)
		(end 127.46 59.34)
		(width 0.3)
		(layer "F.Cu")
		(net 1)
	)
	(segment
		(start 126.7 87.5)
		(end 127.1 87.1)
		(width 0.3)
		(layer "F.Cu")
		(net 1)
	)
	(segment
		(start 97.1 81.4)
		(end 96.6 80.9)
		(width 0.5)
		(layer "F.Cu")
		(net 1)
	)
	(segment
		(start 118.18 120.125)
		(end 118.18 121.11)
		(width 0.3)
		(layer "F.Cu")
		(net 1)
	)
	(segment
		(start 155.98 89.35)
		(end 155.949935 89.319935)
		(width 0.15)
		(layer "F.Cu")
		(net 1)
	)
	(segment
		(start 125.9 90.7)
		(end 125.5 90.3)
		(width 0.3)
		(layer "F.Cu")
		(net 1)
	)
	(segment
		(start 94.1 79.4)
		(end 94.6 79.9)
		(width 0.5)
		(layer "F.Cu")
		(net 1)
	)
	(segment
		(start 127.0995 93.5)
		(end 127.1 93.5)
		(width 0.3)
		(layer "F.Cu")
		(net 1)
	)
	(segment
		(start 91.615 105.525)
		(end 91.83 105.74)
		(width 0.3)
		(layer "F.Cu")
		(net 1)
	)
	(segment
		(start 170.575 103.895)
		(end 170.59 103.91)
		(width 0.3)
		(layer "F.Cu")
		(net 1)
	)
	(segment
		(start 126.7 89.9)
		(end 127.1 89.5)
		(width 0.3)
		(layer "F.Cu")
		(net 1)
	)
	(segment
		(start 94.1 76.4)
		(end 94.6 76.9)
		(width 0.5)
		(layer "F.Cu")
		(net 1)
	)
	(segment
		(start 157.25 119)
		(end 156.77 119)
		(width 0.15)
		(layer "F.Cu")
		(net 1)
	)
	(segment
		(start 126.7 89.9)
		(end 126.3 90.3)
		(width 0.3)
		(layer "F.Cu")
		(net 1)
	)
	(segment
		(start 169.6 105.395)
		(end 170.635 105.395)
		(width 0.3)
		(layer "F.Cu")
		(net 1)
	)
	(segment
		(start 121.9 89.9)
		(end 122.7 89.1)
		(width 0.3)
		(layer "F.Cu")
		(net 1)
	)
	(segment
		(start 128.3 94.7)
		(end 128.7 95.1)
		(width 0.3)
		(layer "F.Cu")
		(net 1)
	)
	(segment
		(start 127.18 121.06)
		(end 127.21 121.09)
		(width 0.3)
		(layer "F.Cu")
		(net 1)
	)
	(segment
		(start 170.635 105.395)
		(end 170.67 105.36)
		(width 0.3)
		(layer "F.Cu")
		(net 1)
	)
	(segment
		(start 129.1 91.5)
		(end 129.5 91.9)
		(width 0.3)
		(layer "F.Cu")
		(net 1)
	)
	(segment
		(start 131.5 91.5)
		(end 131.9 91.9)
		(width 0.3)
		(layer "F.Cu")
		(net 1)
	)
	(segment
		(start 95.1 79.4)
		(end 95.6 79.9)
		(width 0.5)
		(layer "F.Cu")
		(net 1)
	)
	(segment
		(start 121.1 96.86699)
		(end 121.1 96.3)
		(width 0.3)
		(layer "F.Cu")
		(net 1)
	)
	(segment
		(start 131.060444 91.9)
		(end 130.7 92.260444)
		(width 0.3)
		(layer "F.Cu")
		(net 1)
	)
	(segment
		(start 126.3 91.1)
		(end 125.9 90.7)
		(width 0.3)
		(layer "F.Cu")
		(net 1)
	)
	(segment
		(start 125.9 89.9)
		(end 126.3 90.3)
		(width 0.3)
		(layer "F.Cu")
		(net 1)
	)
	(segment
		(start 127.96 66.54)
		(end 128.46 66.04)
		(width 0.3)
		(layer "F.Cu")
		(net 1)
	)
	(segment
		(start 127.0995 93.5)
		(end 127.0995 93.4995)
		(width 0.3)
		(layer "F.Cu")
		(net 1)
	)
	(segment
		(start 124.7 95.9)
		(end 125.1 95.5)
		(width 0.3)
		(layer "F.Cu")
		(net 1)
	)
	(segment
		(start 125.425535 111.642026)
		(end 124.467561 112.6)
		(width 0.15)
		(layer "F.Cu")
		(net 1)
	)
	(segment
		(start 86.505 105.525)
		(end 86.45 105.47)
		(width 0.3)
		(layer "F.Cu")
		(net 1)
	)
	(segment
		(start 95.1 76.4)
		(end 95.6 76.9)
		(width 0.5)
		(layer "F.Cu")
		(net 1)
	)
	(segment
		(start 101.77 85.6)
		(end 102.07 85.9)
		(width 0.15)
		(layer "F.Cu")
		(net 1)
	)
	(segment
		(start 120.7 89.5)
		(end 120.3 89.1)
		(width 0.3)
		(layer "F.Cu")
		(net 1)
	)
	(segment
		(start 113.275 89.285)
		(end 112.04 90.52)
		(width 0.15)
		(layer "F.Cu")
		(net 1)
	)
	(segment
		(start 122.3 89.515979)
		(end 121.915979 89.9)
		(width 0.1)
		(layer "F.Cu")
		(net 1)
	)
	(segment
		(start 132.4135 96.8)
		(end 132.3 96.6865)
		(width 0.3)
		(layer "F.Cu")
		(net 1)
	)
	(segment
		(start 159.25 124)
		(end 159.25 123)
		(width 0.15)
		(layer "F.Cu")
		(net 1)
	)
	(segment
		(start 170.645 108.395)
		(end 170.65 108.39)
		(width 0.3)
		(layer "F.Cu")
		(net 1)
	)
	(segment
		(start 122.161665 65.299464)
		(end 121.86 64.997799)
		(width 0.1)
		(layer "F.Cu")
		(net 1)
	)
	(segment
		(start 125.5 95.1)
		(end 125.9 94.7)
		(width 0.3)
		(layer "F.Cu")
		(net 1)
	)
	(segment
		(start 126.3 91.1)
		(end 126.7 91.5)
		(width 0.3)
		(layer "F.Cu")
		(net 1)
	)
	(segment
		(start 125.297046 106.26)
		(end 125.197046 106.16)
		(width 0.15)
		(layer "F.Cu")
		(net 1)
	)
	(segment
		(start 121.9 95.5)
		(end 121.9 96.9)
		(width 0.3)
		(layer "F.Cu")
		(net 1)
	)
	(segment
		(start 102.965 102.775)
		(end 101.8655 102.775)
		(width 0.15)
		(layer "F.Cu")
		(net 1)
	)
	(segment
		(start 120.76 71.64)
		(end 121.06 71.34)
		(width 0.3)
		(layer "F.Cu")
		(net 1)
	)
	(segment
		(start 132.37 91.5)
		(end 132.72 91.85)
		(width 0.3)
		(layer "F.Cu")
		(net 1)
	)
	(segment
		(start 111.175 104.385)
		(end 111.19 104.4)
		(width 0.3)
		(layer "F.Cu")
		(net 1)
	)
	(segment
		(start 102.07 85.9)
		(end 102.5 85.9)
		(width 0.15)
		(layer "F.Cu")
		(net 1)
	)
	(segment
		(start 161.28 80.2)
		(end 163.39 80.2)
		(width 0.3)
		(layer "F.Cu")
		(net 1)
	)
	(segment
		(start 111.275 100.4)
		(end 111.275 102.4)
		(width 0.3)
		(layer "F.Cu")
		(net 1)
	)
	(segment
		(start 132.3 96.6865)
		(end 132.3 96.3)
		(width 0.3)
		(layer "F.Cu")
		(net 1)
	)
	(segment
		(start 139.53 56.855)
		(end 139.4 56.725)
		(width 0.2)
		(layer "F.Cu")
		(net 1)
	)
	(segment
		(start 125.4995 95.1)
		(end 125.4995 95.1005)
		(width 0.3)
		(layer "F.Cu")
		(net 1)
	)
	(segment
		(start 126.66 68.14)
		(end 127.06 68.54)
		(width 0.3)
		(layer "F.Cu")
		(net 1)
	)
	(segment
		(start 92.1 80.4)
		(end 92.6 80.9)
		(width 0.5)
		(layer "F.Cu")
		(net 1)
	)
	(segment
		(start 82.7 107.635)
		(end 82.035 107.635)
		(width 0.3)
		(layer "F.Cu")
		(net 1)
	)
	(segment
		(start 165.675 59.04)
		(end 165.785 59.15)
		(width 0.3)
		(layer "F.Cu")
		(net 1)
	)
	(segment
		(start 121.1 87.5)
		(end 121.5 87.9)
		(width 0.3)
		(layer "F.Cu")
		(net 1)
	)
	(segment
		(start 155.325 123.825)
		(end 154.325 123.825)
		(width 0.15)
		(layer "F.Cu")
		(net 1)
	)
	(segment
		(start 127.18 120.125)
		(end 127.18 121.06)
		(width 0.3)
		(layer "F.Cu")
		(net 1)
	)
	(segment
		(start 103.54 121.9875)
		(end 103.54 120)
		(width 0.3)
		(layer "F.Cu")
		(net 1)
	)
	(segment
		(start 173.38 81.7)
		(end 172.68 81.7)
		(width 0.2)
		(layer "F.Cu")
		(net 1)
	)
	(segment
		(start 131.1 95.1)
		(end 130.7 94.7)
		(width 0.3)
		(layer "F.Cu")
		(net 1)
	)
	(segment
		(start 103.54 120)
		(end 103.53 119.99)
		(width 0.3)
		(layer "F.Cu")
		(net 1)
	)
	(segment
		(start 132.4135 96.4135)
		(end 132.4135 96.8)
		(width 0.1)
		(layer "F.Cu")
		(net 1)
	)
	(segment
		(start 120.3 96.3)
		(end 120.3 96.60799)
		(width 0.3)
		(layer "F.Cu")
		(net 1)
	)
	(segment
		(start 170.635 99.395)
		(end 170.64 99.39)
		(width 0.3)
		(layer "F.Cu")
		(net 1)
	)
	(segment
		(start 87.115 79.4)
		(end 86.5 79.4)
		(width 0.3)
		(layer "F.Cu")
		(net 1)
	)
	(segment
		(start 125.86 70.54)
		(end 126.26 70.94)
		(width 0.3)
		(layer "F.Cu")
		(net 1)
	)
	(segment
		(start 111.275 102.485)
		(end 111.79 103)
		(width 0.3)
		(layer "F.Cu")
		(net 1)
	)
	(segment
		(start 110.29 104.385)
		(end 111.175 104.385)
		(width 0.3)
		(layer "F.Cu")
		(net 1)
	)
	(segment
		(start 121.46 66.14)
		(end 121.86 66.54)
		(width 0.3)
		(layer "F.Cu")
		(net 1)
	)
	(segment
		(start 156.550274 82.7)
		(end 156.404019 82.846255)
		(width 0.3)
		(layer "F.Cu")
		(net 1)
	)
	(segment
		(start 93.78 74.72)
		(end 93.65 74.72)
		(width 0.5)
		(layer "F.Cu")
		(net 1)
	)
	(segment
		(start 162.79 71.05)
		(end 164.79 71.05)
		(width 0.3)
		(layer "F.Cu")
		(net 1)
	)
	(segment
		(start 123.5 92.2995)
		(end 123.9 91.8995)
		(width 0.3)
		(layer "F.Cu")
		(net 1)
	)
	(segment
		(start 122.7 96.3)
		(end 122.7 96.9)
		(width 0.3)
		(layer "F.Cu")
		(net 1)
	)
	(segment
		(start 128.56 62.37)
		(end 129.085 62.37)
		(width 0.3)
		(layer "F.Cu")
		(net 1)
	)
	(segment
		(start 121.06 60.94)
		(end 120.8945 60.94)
		(width 0.1)
		(layer "F.Cu")
		(net 1)
	)
	(segment
		(start 123.5 86.7)
		(end 123.9 87.1)
		(width 0.3)
		(layer "F.Cu")
		(net 1)
	)
	(segment
		(start 127.89 87.1)
		(end 127.9 87.1)
		(width 0.3)
		(layer "F.Cu")
		(net 1)
	)
	(segment
		(start 125.197046 106.16)
		(end 123.945 106.16)
		(width 0.15)
		(layer "F.Cu")
		(net 1)
	)
	(segment
		(start 99.73 120.03)
		(end 99.72 120.02)
		(width 0.3)
		(layer "F.Cu")
		(net 1)
	)
	(segment
		(start 127.46 62.54)
		(end 128.39 62.54)
		(width 0.3)
		(layer "F.Cu")
		(net 1)
	)
	(segment
		(start 119.9 87.9)
		(end 120.3 88.3)
		(width 0.3)
		(layer "F.Cu")
		(net 1)
	)
	(segment
		(start 93.1 77.4)
		(end 93.6 77.9)
		(width 0.5)
		(layer "F.Cu")
		(net 1)
	)
	(segment
		(start 171.45 85.945)
		(end 169.435 85.945)
		(width 0.2)
		(layer "F.Cu")
		(net 1)
	)
	(segment
		(start 142 120.75)
		(end 142.05 120.8)
		(width 0.15)
		(layer "F.Cu")
		(net 1)
	)
	(segment
		(start 169.6 97.895)
		(end 170.635 97.895)
		(width 0.3)
		(layer "F.Cu")
		(net 1)
	)
	(segment
		(start 93.1 76.4)
		(end 93.6 76.9)
		(width 0.5)
		(layer "F.Cu")
		(net 1)
	)
	(segment
		(start 121.1 88.3)
		(end 121.5 87.9)
		(width 0.3)
		(layer "F.Cu")
		(net 1)
	)
	(segment
		(start 171.7 114.345)
		(end 170.105 114.345)
		(width 0.3)
		(layer "F.Cu")
		(net 1)
	)
	(segment
		(start 138.49 56.5)
		(end 138.845 56.855)
		(width 0.3)
		(layer "F.Cu")
		(net 1)
	)
	(segment
		(start 125.1 96.9)
		(end 125.1 96.3)
		(width 0.3)
		(layer "F.Cu")
		(net 1)
	)
	(segment
		(start 169.6 106.895)
		(end 170.635 106.895)
		(width 0.3)
		(layer "F.Cu")
		(net 1)
	)
	(segment
		(start 162.83 119.9)
		(end 162.83 120.95)
		(width 0.3)
		(layer "F.Cu")
		(net 1)
	)
	(segment
		(start 122.7 88.3)
		(end 122.3 87.9)
		(width 0.3)
		(layer "F.Cu")
		(net 1)
	)
	(segment
		(start 127.1 87.1)
		(end 127.5 86.7)
		(width 0.3)
		(layer "F.Cu")
		(net 1)
	)
	(segment
		(start 170.74 73.65)
		(end 170.79 73.7)
		(width 0.3)
		(layer "F.Cu")
		(net 1)
	)
	(segment
		(start 95.1 78.4)
		(end 95.6 78.9)
		(width 0.5)
		(layer "F.Cu")
		(net 1)
	)
	(segment
		(start 172.34 69.35)
		(end 172.19 69.2)
		(width 0.3)
		(layer "F.Cu")
		(net 1)
	)
	(segment
		(start 122.3 89.5)
		(end 122.3 89.515979)
		(width 0.1)
		(layer "F.Cu")
		(net 1)
	)
	(segment
		(start 123.1 87.1)
		(end 123.5 86.7)
		(width 0.3)
		(layer "F.Cu")
		(net 1)
	)
	(segment
		(start 124.7 95.1)
		(end 125.1 94.7)
		(width 0.3)
		(layer "F.Cu")
		(net 1)
	)
	(segment
		(start 112.04 90.01)
		(end 111.18 89.15)
		(width 0.15)
		(layer "F.Cu")
		(net 1)
	)
	(segment
		(start 86.46 117.665)
		(end 86.46 115.58)
		(width 0.3)
		(layer "F.Cu")
		(net 1)
	)
	(segment
		(start 170.635 97.895)
		(end 170.65 97.91)
		(width 0.3)
		(layer "F.Cu")
		(net 1)
	)
	(segment
		(start 118.18 121.11)
		(end 118.21 121.14)
		(width 0.3)
		(layer "F.Cu")
		(net 1)
	)
	(segment
		(start 86.1 78.385)
		(end 86.1 79)
		(width 0.3)
		(layer "F.Cu")
		(net 1)
	)
	(segment
		(start 167.03 87.35)
		(end 167.03 88.05)
		(width 0.2)
		(layer "F.Cu")
		(net 1)
	)
	(segment
		(start 125.608496 111.633476)
		(end 125.599946 111.642026)
		(width 0.15)
		(layer "F.Cu")
		(net 1)
	)
	(segment
		(start 160.25 119)
		(end 160.95 119)
		(width 0.15)
		(layer "F.Cu")
		(net 1)
	)
	(segment
		(start 116.68 121.11)
		(end 116.71 121.14)
		(width 0.3)
		(layer "F.Cu")
		(net 1)
	)
	(segment
		(start 127.9 87.1)
		(end 127.9 87.056224)
		(width 0.1)
		(layer "F.Cu")
		(net 1)
	)
	(segment
		(start 121.5 89.5)
		(end 121.1 89.1)
		(width 0.3)
		(layer "F.Cu")
		(net 1)
	)
	(segment
		(start 87.025 105.525)
		(end 86.505 105.525)
		(width 0.3)
		(layer "F.Cu")
		(net 1)
	)
	(segment
		(start 121.9 96.3)
		(end 121.9 96.9)
		(width 0.1)
		(layer "F.Cu")
		(net 1)
	)
	(segment
		(start 125.68 121.03)
		(end 125.72 121.07)
		(width 0.3)
		(layer "F.Cu")
		(net 1)
	)
	(segment
		(start 86.5 79.4)
		(end 86.3 79.6)
		(width 0.3)
		(layer "F.Cu")
		(net 1)
	)
	(segment
		(start 127.0995 93.4995)
		(end 126.7 93.1)
		(width 0.3)
		(layer "F.Cu")
		(net 1)
	)
	(segment
		(start 156.77 119)
		(end 156.57 118.8)
		(width 0.15)
		(layer "F.Cu")
		(net 1)
	)
	(segment
		(start 154.325 123.825)
		(end 154.25 123.75)
		(width 0.15)
		(layer "F.Cu")
		(net 1)
	)
	(segment
		(start 166.63 87.35)
		(end 166.43 87.55)
		(width 0.2)
		(layer "F.Cu")
		(net 1)
	)
	(segment
		(start 121.9 95.5)
		(end 121.9 96.3)
		(width 0.1)
		(layer "F.Cu")
		(net 1)
	)
	(segment
		(start 166.43 87.55)
		(end 166.23 87.55)
		(width 0.2)
		(layer "F.Cu")
		(net 1)
	)
	(segment
		(start 121.5 89.5)
		(end 121.9 89.9)
		(width 0.3)
		(layer "F.Cu")
		(net 1)
	)
	(segment
		(start 120.56 67.34)
		(end 121.06 67.34)
		(width 0.3)
		(layer "F.Cu")
		(net 1)
	)
	(segment
		(start 159.4 91.15)
		(end 160.2 91.15)
		(width 0.3)
		(layer "F.Cu")
		(net 1)
	)
	(segment
		(start 173.44 77.8)
		(end 174.39 77.8)
		(width 0.15)
		(layer "F.Cu")
		(net 1)
	)
	(segment
		(start 115.8 89.285)
		(end 113.275 89.285)
		(width 0.15)
		(layer "F.Cu")
		(net 1)
	)
	(segment
		(start 120.3 96.60799)
		(end 120.8295 97.13749)
		(width 0.3)
		(layer "F.Cu")
		(net 1)
	)
	(segment
		(start 125.9 85.1)
		(end 125.5 85.5)
		(width 0.3)
		(layer "F.Cu")
		(net 1)
	)
	(segment
		(start 124.7 95.1)
		(end 124.3 94.7)
		(width 0.3)
		(layer "F.Cu")
		(net 1)
	)
	(segment
		(start 120.56 66.54)
		(end 121.06 66.54)
		(width 0.3)
		(layer "F.Cu")
		(net 1)
	)
	(segment
		(start 127.1 93.5)
		(end 127.5 93.1)
		(width 0.3)
		(layer "F.Cu")
		(net 1)
	)
	(segment
		(start 109.000419 97.599581)
		(end 109.000419 98.499581)
		(width 0.15)
		(layer "F.Cu")
		(net 1)
	)
	(segment
		(start 101.045 85.975)
		(end 101.42 85.6)
		(width 0.15)
		(layer "F.Cu")
		(net 1)
	)
	(segment
		(start 172.68 81.7)
		(end 172.63 81.75)
		(width 0.2)
		(layer "F.Cu")
		(net 1)
	)
	(segment
		(start 122.7 85.9)
		(end 122.3 86.3)
		(width 0.1)
		(layer "F.Cu")
		(net 1)
	)
	(segment
		(start 92.08 75.4)
		(end 91.63 75.85)
		(width 0.5)
		(layer "F.Cu")
		(net 1)
	)
	(segment
		(start 127.1 89.5)
		(end 127.5 89.9)
		(width 0.3)
		(layer "F.Cu")
		(net 1)
	)
	(segment
		(start 110.4 94)
		(end 109.5 93.1)
		(width 0.15)
		(layer "F.Cu")
		(net 1)
	)
	(segment
		(start 126.3 94.3)
		(end 125.9 94.7)
		(width 0.3)
		(layer "F.Cu")
		(net 1)
	)
	(segment
		(start 150.43 69.15)
		(end 150.83 69.55)
		(width 0.2)
		(layer "F.Cu")
		(net 1)
	)
	(segment
		(start 120.8945 60.94)
		(end 120.75 60.7955)
		(width 0.1)
		(layer "F.Cu")
		(net 1)
	)
	(segment
		(start 119.9 87.97)
		(end 120.23 88.3)
		(width 0.1)
		(layer "F.Cu")
		(net 1)
	)
	(segment
		(start 156.63 123.3)
		(end 156.61 123.28)
		(width 0.15)
		(layer "F.Cu")
		(net 1)
	)
	(segment
		(start 126.3 90.3)
		(end 126.7 90.7)
		(width 0.3)
		(layer "F.Cu")
		(net 1)
	)
	(segment
		(start 124.7 87.9)
		(end 124.3 87.5)
		(width 0.3)
		(layer "F.Cu")
		(net 1)
	)
	(segment
		(start 99.1 76.4)
		(end 98.6 76.9)
		(width 0.5)
		(layer "F.Cu")
		(net 1)
	)
	(segment
		(start 158.25 124.1)
		(end 158.25 123)
		(width 0.15)
		(layer "F.Cu")
		(net 1)
	)
	(segment
		(start 121.86 68.9395)
		(end 121.46 68.5395)
		(width 0.1)
		(layer "F.Cu")
		(net 1)
	)
	(segment
		(start 125.68 120.125)
		(end 125.68 121.03)
		(width 0.3)
		(layer "F.Cu")
		(net 1)
	)
	(segment
		(start 94.1 74.4)
		(end 93.78 74.72)
		(width 0.5)
		(layer "F.Cu")
		(net 1)
	)
	(segment
		(start 127.46 68.94)
		(end 127.96 68.94)
		(width 0.3)
		(layer "F.Cu")
		(net 1)
	)
	(segment
		(start 109.505317 93)
		(end 109.512099 92.993218)
		(width 0.15)
		(layer "F.Cu")
		(net 1)
	)
	(segment
		(start 93.1 78.4)
		(end 93.6 78.9)
		(width 0.5)
		(layer "F.Cu")
		(net 1)
	)
	(segment
		(start 101 121.9875)
		(end 101 119.99)
		(width 0.3)
		(layer "F.Cu")
		(net 1)
	)
	(segment
		(start 125.55 106.26)
		(end 125.297046 106.26)
		(width 0.15)
		(layer "F.Cu")
		(net 1)
	)
	(segment
		(start 131.1 91.9)
		(end 131.060444 91.9)
		(width 0.3)
		(layer "F.Cu")
		(net 1)
	)
	(segment
		(start 127.46 60.94)
		(end 127.96 60.94)
		(width 0.3)
		(layer "F.Cu")
		(net 1)
	)
	(segment
		(start 173.405 74.95)
		(end 172.24 74.95)
		(width 0.3)
		(layer "F.Cu")
		(net 1)
	)
	(segment
		(start 122.161665 65.241665)
		(end 121.86 64.94)
		(width 0.3)
		(layer "F.Cu")
		(net 1)
	)
	(segment
		(start 162.51 94.96)
		(end 162.5 94.97)
		(width 0.2)
		(layer "F.Cu")
		(net 1)
	)
	(segment
		(start 121.9 85.9)
		(end 121.5 85.5)
		(width 0.3)
		(layer "F.Cu")
		(net 1)
	)
	(segment
		(start 157.25 123.3)
		(end 156.63 123.3)
		(width 0.15)
		(layer "F.Cu")
		(net 1)
	)
	(segment
		(start 160.194093 88.07)
		(end 160.58 88.07)
		(width 0.3)
		(layer "F.Cu")
		(net 1)
	)
	(segment
		(start 127.46 70.54)
		(end 127.96 70.54)
		(width 0.3)
		(layer "F.Cu")
		(net 1)
	)
	(segment
		(start 86.46 115.58)
		(end 86.48 115.56)
		(width 0.3)
		(layer "F.Cu")
		(net 1)
	)
	(segment
		(start 126.66 64.94)
		(end 127.06 64.54)
		(width 0.3)
		(layer "F.Cu")
		(net 1)
	)
	(segment
		(start 96.195 89.13)
		(end 96.81 89.13)
		(width 0.15)
		(layer "F.Cu")
		(net 1)
	)
	(segment
		(start 139.13 121.975)
		(end 139.13 120.01)
		(width 0.3)
		(layer "F.Cu")
		(net 1)
	)
	(segment
		(start 109.5 93.1)
		(end 109.5 93)
		(width 0.15)
		(layer "F.Cu")
		(net 1)
	)
	(segment
		(start 133.345 112.15)
		(end 132.63 112.15)
		(width 0.15)
		(layer "F.Cu")
		(net 1)
	)
	(segment
		(start 169.6 103.895)
		(end 170.575 103.895)
		(width 0.3)
		(layer "F.Cu")
		(net 1)
	)
	(segment
		(start 102.9 75.03)
		(end 102.9 76.4)
		(width 0.15)
		(layer "F.Cu")
		(net 1)
	)
	(segment
		(start 125.4995 95.1005)
		(end 125.1 95.5)
		(width 0.3)
		(layer "F.Cu")
		(net 1)
	)
	(segment
		(start 125.5 91.1)
		(end 125.9 90.7)
		(width 0.3)
		(layer "F.Cu")
		(net 1)
	)
	(segment
		(start 149.84 69.15)
		(end 150.43 69.15)
		(width 0.2)
		(layer "F.Cu")
		(net 1)
	)
	(segment
		(start 121.9 86.7)
		(end 122.3 86.3)
		(width 0.1)
		(layer "F.Cu")
		(net 1)
	)
	(segment
		(start 161.93 86.65)
		(end 162.43 86.15)
		(width 0.3)
		(layer "F.Cu")
		(net 1)
	)
	(segment
		(start 139.4 56.725)
		(end 139.4 55.9292)
		(width 0.2)
		(layer "F.Cu")
		(net 1)
	)
	(segment
		(start 103.78 74.15)
		(end 102.9 75.03)
		(width 0.15)
		(layer "F.Cu")
		(net 1)
	)
	(segment
		(start 137.49 110.9)
		(end 137.49 110)
		(width 0.5)
		(layer "F.Cu")
		(net 1)
	)
	(segment
		(start 120.3 88.3)
		(end 120.7 87.9)
		(width 0.3)
		(layer "F.Cu")
		(net 1)
	)
	(segment
		(start 137.905 109.7)
		(end 138.005 109.6)
		(width 0.5)
		(layer "F.Cu")
		(net 1)
	)
	(segment
		(start 125.9 96.3)
		(end 126.7 96.3)
		(width 0.3)
		(layer "F.Cu")
		(net 1)
	)
	(segment
		(start 124.3 87.5)
		(end 123.9 87.1)
		(width 0.3)
		(layer "F.Cu")
		(net 1)
	)
	(segment
		(start 95.6 77.9)
		(end 95.1 77.4)
		(width 0.5)
		(layer "F.Cu")
		(net 1)
	)
	(segment
		(start 159.939093 87.815)
		(end 160.194093 88.07)
		(width 0.3)
		(layer "F.Cu")
		(net 1)
	)
	(segment
		(start 154.075 120)
		(end 154.75 120)
		(width 0.15)
		(layer "F.Cu")
		(net 1)
	)
	(segment
		(start 94.1 78.4)
		(end 94.6 78.9)
		(width 0.5)
		(layer "F.Cu")
		(net 1)
	)
	(segment
		(start 87.315 78.385)
		(end 87.2 78.5)
		(width 0.3)
		(layer "F.Cu")
		(net 1)
	)
	(segment
		(start 121.1 88.3)
		(end 120.7 87.9)
		(width 0.3)
		(layer "F.Cu")
		(net 1)
	)
	(segment
		(start 129.9 85.876763)
		(end 130.299998 85.476765)
		(width 0.3)
		(layer "F.Cu")
		(net 1)
	)
	(segment
		(start 126.7 90.7)
		(end 126.3 91.1)
		(width 0.3)
		(layer "F.Cu")
		(net 1)
	)
	(segment
		(start 120.66 59.34)
		(end 121.06 59.34)
		(width 0.3)
		(layer "F.Cu")
		(net 1)
	)
	(segment
		(start 161.38 86.65)
		(end 161.93 86.65)
		(width 0.3)
		(layer "F.Cu")
		(net 1)
	)
	(segment
		(start 127.46 66.54)
		(end 127.96 66.54)
		(width 0.3)
		(layer "F.Cu")
		(net 1)
	)
	(via
		(at 166.23 87.55)
		(size 0.45)
		(drill 0.2)
		(layers "F.Cu" "B.Cu")
		(remove_unused_layers yes)
		(keep_end_layers yes)
		(zone_layer_connections "In1.Cu" "In3.Cu" "In5.Cu")
		(net 1)
	)
	(via
		(at 95.6 76.9)
		(size 0.45)
		(drill 0.2)
		(layers "F.Cu" "B.Cu")
		(remove_unused_layers yes)
		(keep_end_layers yes)
		(zone_layer_connections "In1.Cu" "In3.Cu" "In5.Cu")
		(net 1)
	)
	(via
		(at 76.03 97.15)
		(size 0.45)
		(drill 0.2)
		(layers "F.Cu" "B.Cu")
		(remove_unused_layers yes)
		(keep_end_layers yes)
		(free yes)
		(zone_layer_connections "In1.Cu" "In3.Cu" "In5.Cu")
		(net 1)
	)
	(via
		(at 131.9 91.9)
		(size 0.45)
		(drill 0.2)
		(layers "F.Cu" "B.Cu")
		(remove_unused_layers yes)
		(keep_end_layers yes)
		(zone_layer_connections "In1.Cu" "In3.Cu" "In5.Cu")
		(net 1)
	)
	(via
		(at 159.69 59.35)
		(size 0.45)
		(drill 0.2)
		(layers "F.Cu" "B.Cu")
		(remove_unused_layers yes)
		(keep_end_layers yes)
		(free yes)
		(zone_layer_connections "In1.Cu" "In3.Cu" "In5.Cu")
		(net 1)
	)
	(via
		(at 174.39 77.8)
		(size 0.45)
		(drill 0.2)
		(layers "F.Cu" "B.Cu")
		(remove_unused_layers yes)
		(keep_end_layers yes)
		(zone_layer_connections "In1.Cu" "In3.Cu" "In5.Cu")
		(net 1)
	)
	(via
		(at 157.69 64.2)
		(size 0.45)
		(drill 0.2)
		(layers "F.Cu" "B.Cu")
		(remove_unused_layers yes)
		(keep_end_layers yes)
		(free yes)
		(zone_layer_connections "In1.Cu" "In3.Cu" "In5.Cu")
		(net 1)
	)
	(via
		(at 76.03 71.15)
		(size 0.45)
		(drill 0.2)
		(layers "F.Cu" "B.Cu")
		(remove_unused_layers yes)
		(keep_end_layers yes)
		(free yes)
		(zone_layer_connections "In3.Cu" "In5.Cu")
		(net 1)
	)
	(via
		(at 121.46 68.5395)
		(size 0.45)
		(drill 0.2)
		(layers "F.Cu" "B.Cu")
		(remove_unused_layers yes)
		(keep_end_layers yes)
		(zone_layer_connections "In1.Cu" "In3.Cu" "In5.Cu")
		(net 1)
	)
	(via
		(at 174.026373 91.149492)
		(size 0.45)
		(drill 0.2)
		(layers "F.Cu" "B.Cu")
		(remove_unused_layers yes)
		(keep_end_layers yes)
		(free yes)
		(zone_layer_connections "In1.Cu" "In3.Cu" "In5.Cu")
		(net 1)
	)
	(via
		(at 134.031146 94.9)
		(size 0.45)
		(drill 0.2)
		(layers "F.Cu" "B.Cu")
		(remove_unused_layers yes)
		(keep_end_layers yes)
		(free yes)
		(zone_layer_connections "In1.Cu" "In3.Cu" "In5.Cu")
		(net 1)
	)
	(via
		(at 76.035638 73.095202)
		(size 0.45)
		(drill 0.2)
		(layers "F.Cu" "B.Cu")
		(remove_unused_layers yes)
		(keep_end_layers yes)
		(free yes)
		(zone_layer_connections "In3.Cu" "In5.Cu")
		(net 1)
	)
	(via
		(at 98.147874 124.023057)
		(size 0.45)
		(drill 0.2)
		(layers "F.Cu" "B.Cu")
		(remove_unused_layers yes)
		(keep_end_layers yes)
		(free yes)
		(zone_layer_connections "In1.Cu" "In3.Cu" "In5.Cu")
		(net 1)
	)
	(via
		(at 130.101732 67.328268)
		(size 0.45)
		(drill 0.2)
		(layers "F.Cu" "B.Cu")
		(remove_unused_layers yes)
		(keep_end_layers yes)
		(free yes)
		(zone_layer_connections "In1.Cu" "In3.Cu" "In5.Cu")
		(net 1)
	)
	(via
		(at 102.4 81.23)
		(size 0.45)
		(drill 0.2)
		(layers "F.Cu" "B.Cu")
		(remove_unused_layers yes)
		(keep_end_layers yes)
		(free yes)
		(zone_layer_connections "In1.Cu" "In3.Cu" "In5.Cu")
		(net 1)
	)
	(via
		(at 101.299392 81.783368)
		(size 0.45)
		(drill 0.2)
		(layers "F.Cu" "B.Cu")
		(remove_unused_layers yes)
		(keep_end_layers yes)
		(free yes)
		(zone_layer_connections "In1.Cu" "In3.Cu" "In5.Cu")
		(net 1)
	)
	(via
		(at 75.995347 81.253956)
		(size 0.45)
		(drill 0.2)
		(layers "F.Cu" "B.Cu")
		(remove_unused_layers yes)
		(keep_end_layers yes)
		(free yes)
		(zone_layer_connections "In3.Cu" "In5.Cu")
		(net 1)
	)
	(via
		(at 123.094917 59.000628)
		(size 0.45)
		(drill 0.2)
		(layers "F.Cu" "B.Cu")
		(remove_unused_layers yes)
		(keep_end_layers yes)
		(free yes)
		(zone_layer_connections "In1.Cu" "In3.Cu" "In5.Cu")
		(net 1)
	)
	(via
		(at 76.03 85.15)
		(size 0.45)
		(drill 0.2)
		(layers "F.Cu" "B.Cu")
		(remove_unused_layers yes)
		(keep_end_layers yes)
		(free yes)
		(zone_layer_connections "In1.Cu" "In3.Cu" "In5.Cu")
		(net 1)
	)
	(via
		(at 122.7 96.9)
		(size 0.45)
		(drill 0.2)
		(layers "F.Cu" "B.Cu")
		(remove_unused_layers yes)
		(keep_end_layers yes)
		(zone_layer_connections "In1.Cu" "In3.Cu" "In5.Cu")
		(net 1)
	)
	(via
		(at 143.371113 81.377243)
		(size 0.45)
		(drill 0.2)
		(layers "F.Cu" "B.Cu")
		(remove_unused_layers yes)
		(keep_end_layers yes)
		(zone_layer_connections "In1.Cu" "In3.Cu" "In5.Cu")
		(net 1)
	)
	(via
		(at 135.03 122.15)
		(size 0.45)
		(drill 0.2)
		(layers "F.Cu" "B.Cu")
		(remove_unused_layers yes)
		(keep_end_layers yes)
		(free yes)
		(zone_layer_connections "In1.Cu" "In3.Cu" "In5.Cu")
		(net 1)
	)
	(via
		(at 97.03 66.15)
		(size 0.45)
		(drill 0.2)
		(layers "F.Cu" "B.Cu")
		(remove_unused_layers yes)
		(keep_end_layers yes)
		(free yes)
		(zone_layer_connections "In1.Cu" "In3.Cu" "In5.Cu")
		(net 1)
	)
	(via
		(at 92.03 108.15)
		(size 0.45)
		(drill 0.2)
		(layers "F.Cu" "B.Cu")
		(remove_unused_layers yes)
		(keep_end_layers yes)
		(free yes)
		(zone_layer_connections "In1.Cu" "In3.Cu" "In5.Cu")
		(net 1)
	)
	(via
		(at 143.83 66.4)
		(size 0.45)
		(drill 0.2)
		(layers "F.Cu" "B.Cu")
		(remove_unused_layers yes)
		(keep_end_layers yes)
		(free yes)
		(zone_layer_connections "In1.Cu" "In3.Cu" "In5.Cu")
		(net 1)
	)
	(via
		(at 127.0995 93.5)
		(size 0.45)
		(drill 0.2)
		(layers "F.Cu" "B.Cu")
		(remove_unused_layers yes)
		(keep_end_layers yes)
		(zone_layer_connections "In1.Cu" "In3.Cu" "In5.Cu")
		(net 1)
	)
	(via
		(at 111.18 89.15)
		(size 0.45)
		(drill 0.2)
		(layers "F.Cu" "B.Cu")
		(remove_unused_layers yes)
		(keep_end_layers yes)
		(zone_layer_connections "In1.Cu" "In3.Cu" "In5.Cu")
		(net 1)
	)
	(via
		(at 132.4135 96.8)
		(size 0.45)
		(drill 0.2)
		(layers "F.Cu" "B.Cu")
		(remove_unused_layers yes)
		(keep_end_layers yes)
		(zone_layer_connections "In1.Cu" "In3.Cu" "In5.Cu")
		(net 1)
	)
	(via
		(at 132.72 91.9005)
		(size 0.45)
		(drill 0.2)
		(layers "F.Cu" "B.Cu")
		(remove_unused_layers yes)
		(keep_end_layers yes)
		(zone_layer_connections "In1.Cu" "In3.Cu" "In5.Cu")
		(net 1)
	)
	(via
		(at 132.478479 62.810276)
		(size 0.45)
		(drill 0.2)
		(layers "F.Cu" "B.Cu")
		(remove_unused_layers yes)
		(keep_end_layers yes)
		(free yes)
		(zone_layer_connections "In1.Cu" "In3.Cu" "In5.Cu")
		(net 1)
	)
	(via
		(at 130.15 65.1645)
		(size 0.45)
		(drill 0.2)
		(layers "F.Cu" "B.Cu")
		(remove_unused_layers yes)
		(keep_end_layers yes)
		(free yes)
		(zone_layer_connections "In1.Cu" "In3.Cu" "In5.Cu")
		(net 1)
	)
	(via
		(at 138.49 69.6)
		(size 0.45)
		(drill 0.2)
		(layers "F.Cu" "B.Cu")
		(remove_unused_layers yes)
		(keep_end_layers yes)
		(free yes)
		(zone_layer_connections "In1.Cu" "In3.Cu" "In5.Cu")
		(net 1)
	)
	(via
		(at 146.14 65.5)
		(size 0.45)
		(drill 0.2)
		(layers "F.Cu" "B.Cu")
		(remove_unused_layers yes)
		(keep_end_layers yes)
		(free yes)
		(zone_layer_connections "In1.Cu" "In3.Cu" "In5.Cu")
		(net 1)
	)
	(via
		(at 129.56 71.48)
		(size 0.45)
		(drill 0.2)
		(layers "F.Cu" "B.Cu")
		(remove_unused_layers yes)
		(keep_end_layers yes)
		(free yes)
		(zone_layer_connections "In1.Cu" "In3.Cu" "In5.Cu")
		(net 1)
	)
	(via
		(at 156 113.745383)
		(size 0.45)
		(drill 0.2)
		(layers "F.Cu" "B.Cu")
		(remove_unused_layers yes)
		(keep_end_layers yes)
		(zone_layer_connections "In1.Cu" "In3.Cu" "In5.Cu")
		(net 1)
	)
	(via
		(at 94.03 66.15)
		(size 0.45)
		(drill 0.2)
		(layers "F.Cu" "B.Cu")
		(remove_unused_layers yes)
		(keep_end_layers yes)
		(free yes)
		(zone_layer_connections "In1.Cu" "In3.Cu" "In5.Cu")
		(net 1)
	)
	(via
		(at 92.6 76.9)
		(size 0.45)
		(drill 0.2)
		(layers "F.Cu" "B.Cu")
		(remove_unused_layers yes)
		(keep_end_layers yes)
		(zone_layer_connections "In1.Cu" "In3.Cu" "In5.Cu")
		(net 1)
	)
	(via
		(at 77.03 79.65)
		(size 0.45)
		(drill 0.2)
		(layers "F.Cu" "B.Cu")
		(remove_unused_layers yes)
		(keep_end_layers yes)
		(zone_layer_connections "In3.Cu" "In5.Cu")
		(net 1)
	)
	(via
		(at 76.03 118.15)
		(size 0.45)
		(drill 0.2)
		(layers "F.Cu" "B.Cu")
		(remove_unused_layers yes)
		(keep_end_layers yes)
		(free yes)
		(zone_layer_connections "In1.Cu" "In3.Cu" "In5.Cu")
		(net 1)
	)
	(via
		(at 138.89 117.4)
		(size 0.45)
		(drill 0.2)
		(layers "F.Cu" "B.Cu")
		(remove_unused_layers yes)
		(keep_end_layers yes)
		(free yes)
		(zone_layer_connections "In1.Cu" "In3.Cu" "In5.Cu")
		(net 1)
	)
	(via
		(at 158.59 65.1)
		(size 0.45)
		(drill 0.2)
		(layers "F.Cu" "B.Cu")
		(remove_unused_layers yes)
		(keep_end_layers yes)
		(free yes)
		(zone_layer_connections "In1.Cu" "In3.Cu" "In5.Cu")
		(net 1)
	)
	(via
		(at 96.03 101.15)
		(size 0.45)
		(drill 0.2)
		(layers "F.Cu" "B.Cu")
		(remove_unused_layers yes)
		(keep_end_layers yes)
		(free yes)
		(zone_layer_connections "In1.Cu" "In3.Cu" "In5.Cu")
		(net 1)
	)
	(via
		(at 76.03 78.15)
		(size 0.45)
		(drill 0.2)
		(layers "F.Cu" "B.Cu")
		(remove_unused_layers yes)
		(keep_end_layers yes)
		(free yes)
		(zone_layer_connections "In3.Cu" "In5.Cu")
		(net 1)
	)
	(via
		(at 102.83 70.31)
		(size 0.45)
		(drill 0.2)
		(layers "F.Cu" "B.Cu")
		(remove_unused_layers yes)
		(keep_end_layers yes)
		(free yes)
		(zone_layer_connections "In1.Cu" "In3.Cu" "In5.Cu")
		(net 1)
	)
	(via
		(at 134.62 62.47)
		(size 0.45)
		(drill 0.2)
		(layers "F.Cu" "B.Cu")
		(remove_unused_layers yes)
		(keep_end_layers yes)
		(free yes)
		(zone_layer_connections "In1.Cu" "In3.Cu" "In5.Cu")
		(net 1)
	)
	(via
		(at 101.03 73.97)
		(size 0.45)
		(drill 0.2)
		(layers "F.Cu" "B.Cu")
		(remove_unused_layers yes)
		(keep_end_layers yes)
		(free yes)
		(zone_layer_connections "In1.Cu" "In3.Cu" "In5.Cu")
		(net 1)
	)
	(via
		(at 147.435752 99.374249)
		(size 0.45)
		(drill 0.2)
		(layers "F.Cu" "B.Cu")
		(remove_unused_layers yes)
		(keep_end_layers yes)
		(zone_layer_connections "In1.Cu" "In3.Cu" "In5.Cu")
		(net 1)
	)
	(via
		(at 110.72 120.48)
		(size 0.45)
		(drill 0.2)
		(layers "F.Cu" "B.Cu")
		(remove_unused_layers yes)
		(keep_end_layers yes)
		(zone_layer_connections "In1.Cu" "In3.Cu" "In5.Cu")
		(net 1)
	)
	(via
		(at 131.1 95.1)
		(size 0.45)
		(drill 0.2)
		(layers "F.Cu" "B.Cu")
		(remove_unused_layers yes)
		(keep_end_layers yes)
		(zone_layer_connections "In1.Cu" "In3.Cu" "In5.Cu")
		(net 1)
	)
	(via
		(at 145 120)
		(size 0.45)
		(drill 0.2)
		(layers "F.Cu" "B.Cu")
		(remove_unused_layers yes)
		(keep_end_layers yes)
		(free yes)
		(zone_layer_connections "In1.Cu" "In3.Cu" "In5.Cu")
		(net 1)
	)
	(via
		(at 76.03 77.15)
		(size 0.45)
		(drill 0.2)
		(layers "F.Cu" "B.Cu")
		(remove_unused_layers yes)
		(keep_end_layers yes)
		(free yes)
		(zone_layer_connections "In3.Cu" "In5.Cu")
		(net 1)
	)
	(via
		(at 125.0055 71.8305)
		(size 0.45)
		(drill 0.2)
		(layers "F.Cu" "B.Cu")
		(remove_unused_layers yes)
		(keep_end_layers yes)
		(free yes)
		(zone_layer_connections "In1.Cu" "In3.Cu" "In5.Cu")
		(net 1)
	)
	(via
		(at 126.3 87.9)
		(size 0.45)
		(drill 0.2)
		(layers "F.Cu" "B.Cu")
		(remove_unused_layers yes)
		(keep_end_layers yes)
		(zone_layer_connections "In1.Cu" "In3.Cu" "In5.Cu")
		(net 1)
	)
	(via
		(at 153.03 56.15)
		(size 0.45)
		(drill 0.2)
		(layers "F.Cu" "B.Cu")
		(remove_unused_layers yes)
		(keep_end_layers yes)
		(free yes)
		(zone_layer_connections "In1.Cu" "In3.Cu" "In5.Cu")
		(net 1)
	)
	(via
		(at 156.980498 66.72)
		(size 0.45)
		(drill 0.2)
		(layers "F.Cu" "B.Cu")
		(remove_unused_layers yes)
		(keep_end_layers yes)
		(free yes)
		(zone_layer_connections "In1.Cu" "In3.Cu" "In5.Cu")
		(net 1)
	)
	(via
		(at 152.23 64.95)
		(size 0.45)
		(drill 0.2)
		(layers "F.Cu" "B.Cu")
		(remove_unused_layers yes)
		(keep_end_layers yes)
		(zone_layer_connections "In1.Cu" "In3.Cu" "In5.Cu")
		(net 1)
	)
	(via
		(at 91.03 66.15)
		(size 0.45)
		(drill 0.2)
		(layers "F.Cu" "B.Cu")
		(remove_unused_layers yes)
		(keep_end_layers yes)
		(free yes)
		(zone_layer_connections "In1.Cu" "In3.Cu" "In5.Cu")
		(net 1)
	)
	(via
		(at 144.23 101.85)
		(size 0.45)
		(drill 0.2)
		(layers "F.Cu" "B.Cu")
		(remove_unused_layers yes)
		(keep_end_layers yes)
		(zone_layer_connections "In1.Cu" "In3.Cu" "In5.Cu")
		(net 1)
	)
	(via
		(at 172.63 81.75)
		(size 0.45)
		(drill 0.2)
		(layers "F.Cu" "B.Cu")
		(remove_unused_layers yes)
		(keep_end_layers yes)
		(zone_layer_connections "In1.Cu" "In3.Cu" "In5.Cu")
		(net 1)
	)
	(via
		(at 148.13 76.05)
		(size 0.45)
		(drill 0.2)
		(layers "F.Cu" "B.Cu")
		(remove_unused_layers yes)
		(keep_end_layers yes)
		(free yes)
		(zone_layer_connections "In1.Cu" "In3.Cu" "In5.Cu")
		(net 1)
	)
	(via
		(at 137.23 76.85)
		(size 0.45)
		(drill 0.2)
		(layers "F.Cu" "B.Cu")
		(remove_unused_layers yes)
		(keep_end_layers yes)
		(free yes)
		(zone_layer_connections "In1.Cu" "In3.Cu" "In5.Cu")
		(net 1)
	)
	(via
		(at 133.12 105.54)
		(size 0.45)
		(drill 0.2)
		(layers "F.Cu" "B.Cu")
		(remove_unused_layers yes)
		(keep_end_layers yes)
		(free yes)
		(zone_layer_connections "In1.Cu" "In3.Cu" "In5.Cu")
		(net 1)
	)
	(via
		(at 119.03 124.15)
		(size 0.45)
		(drill 0.2)
		(layers "F.Cu" "B.Cu")
		(remove_unused_layers yes)
		(keep_end_layers yes)
		(free yes)
		(zone_layer_connections "In1.Cu" "In3.Cu" "In5.Cu")
		(net 1)
	)
	(via
		(at 170.65 108.39)
		(size 0.45)
		(drill 0.2)
		(layers "F.Cu" "B.Cu")
		(remove_unused_layers yes)
		(keep_end_layers yes)
		(zone_layer_connections "In1.Cu" "In3.Cu" "In5.Cu")
		(net 1)
	)
	(via
		(at 145.03 71.05)
		(size 0.45)
		(drill 0.2)
		(layers "F.Cu" "B.Cu")
		(remove_unused_layers yes)
		(keep_end_layers yes)
		(free yes)
		(zone_layer_connections "In1.Cu" "In3.Cu" "In5.Cu")
		(net 1)
	)
	(via
		(at 174.03 106.15)
		(size 0.45)
		(drill 0.2)
		(layers "F.Cu" "B.Cu")
		(remove_unused_layers yes)
		(keep_end_layers yes)
		(free yes)
		(zone_layer_connections "In1.Cu" "In3.Cu" "In5.Cu")
		(net 1)
	)
	(via
		(at 90.03 112.15)
		(size 0.45)
		(drill 0.2)
		(layers "F.Cu" "B.Cu")
		(remove_unused_layers yes)
		(keep_end_layers yes)
		(free yes)
		(zone_layer_connections "In1.Cu" "In3.Cu" "In5.Cu")
		(net 1)
	)
	(via
		(at 170.64 99.39)
		(size 0.45)
		(drill 0.2)
		(layers "F.Cu" "B.Cu")
		(remove_unused_layers yes)
		(keep_end_layers yes)
		(zone_layer_connections "In1.Cu" "In3.Cu" "In5.Cu")
		(net 1)
	)
	(via
		(at 127.96 70.54)
		(size 0.45)
		(drill 0.2)
		(layers "F.Cu" "B.Cu")
		(remove_unused_layers yes)
		(keep_end_layers yes)
		(zone_layer_connections "In1.Cu" "In3.Cu" "In5.Cu")
		(net 1)
	)
	(via
		(at 119.82 83.8295)
		(size 0.45)
		(drill 0.2)
		(layers "F.Cu" "B.Cu")
		(remove_unused_layers yes)
		(keep_end_layers yes)
		(zone_layer_connections "In1.Cu" "In3.Cu" "In5.Cu")
		(net 1)
	)
	(via
		(at 136.81 121.48)
		(size 0.45)
		(drill 0.2)
		(layers "F.Cu" "B.Cu")
		(remove_unused_layers yes)
		(keep_end_layers yes)
		(free yes)
		(zone_layer_connections "In1.Cu" "In3.Cu" "In5.Cu")
		(net 1)
	)
	(via
		(at 126.03 101.69)
		(size 0.45)
		(drill 0.2)
		(layers "F.Cu" "B.Cu")
		(remove_unused_layers yes)
		(keep_end_layers yes)
		(free yes)
		(zone_layer_connections "In1.Cu" "In3.Cu" "In5.Cu")
		(net 1)
	)
	(via
		(at 76.03 107.15)
		(size 0.45)
		(drill 0.2)
		(layers "F.Cu" "B.Cu")
		(remove_unused_layers yes)
		(keep_end_layers yes)
		(free yes)
		(zone_layer_connections "In3.Cu" "In5.Cu")
		(net 1)
	)
	(via
		(at 144.728712 85.247803)
		(size 0.45)
		(drill 0.2)
		(layers "F.Cu" "B.Cu")
		(remove_unused_layers yes)
		(keep_end_layers yes)
		(zone_layer_connections "In1.Cu" "In3.Cu" "In5.Cu")
		(net 1)
	)
	(via
		(at 149.83 64.05)
		(size 0.45)
		(drill 0.2)
		(layers "F.Cu" "B.Cu")
		(remove_unused_layers yes)
		(keep_end_layers yes)
		(free yes)
		(zone_layer_connections "In1.Cu" "In3.Cu" "In5.Cu")
		(net 1)
	)
	(via
		(at 153.9 114.57)
		(size 0.45)
		(drill 0.2)
		(layers "F.Cu" "B.Cu")
		(remove_unused_layers yes)
		(keep_end_layers yes)
		(zone_layer_connections "In1.Cu" "In3.Cu" "In5.Cu")
		(net 1)
	)
	(via
		(at 127.06 64.54)
		(size 0.45)
		(drill 0.2)
		(layers "F.Cu" "B.Cu")
		(remove_unused_layers yes)
		(keep_end_layers yes)
		(zone_layer_connections "In1.Cu" "In3.Cu" "In5.Cu")
		(net 1)
	)
	(via
		(at 174.03 109.15)
		(size 0.45)
		(drill 0.2)
		(layers "F.Cu" "B.Cu")
		(remove_unused_layers yes)
		(keep_end_layers yes)
		(free yes)
		(zone_layer_connections "In1.Cu" "In3.Cu" "In5.Cu")
		(net 1)
	)
	(via
		(at 97.1 70.6)
		(size 0.45)
		(drill 0.2)
		(layers "F.Cu" "B.Cu")
		(remove_unused_layers yes)
		(keep_end_layers yes)
		(zone_layer_connections "In1.Cu" "In3.Cu" "In5.Cu")
		(net 1)
	)
	(via
		(at 127.1 87.1)
		(size 0.45)
		(drill 0.2)
		(layers "F.Cu" "B.Cu")
		(remove_unused_layers yes)
		(keep_end_layers yes)
		(zone_layer_connections "In1.Cu" "In3.Cu" "In5.Cu")
		(net 1)
	)
	(via
		(at 157.69 66)
		(size 0.45)
		(drill 0.2)
		(layers "F.Cu" "B.Cu")
		(remove_unused_layers yes)
		(keep_end_layers yes)
		(free yes)
		(zone_layer_connections "In1.Cu" "In3.Cu" "In5.Cu")
		(net 1)
	)
	(via
		(at 102.28 69.4)
		(size 0.45)
		(drill 0.2)
		(layers "F.Cu" "B.Cu")
		(remove_unused_layers yes)
		(keep_end_layers yes)
		(free yes)
		(zone_layer_connections "In1.Cu" "In3.Cu" "In5.Cu")
		(net 1)
	)
	(via
		(at 166.54 108.44)
		(size 0.45)
		(drill 0.2)
		(layers "F.Cu" "B.Cu")
		(remove_unused_layers yes)
		(keep_end_layers yes)
		(free yes)
		(zone_layer_connections "In1.Cu" "In3.Cu" "In5.Cu")
		(net 1)
	)
	(via
		(at 154.25 123.75)
		(size 0.45)
		(drill 0.2)
		(layers "F.Cu" "B.Cu")
		(remove_unused_layers yes)
		(keep_end_layers yes)
		(zone_layer_connections "In1.Cu" "In3.Cu" "In5.Cu")
		(net 1)
	)
	(via
		(at 172.19 69.2)
		(size 0.45)
		(drill 0.2)
		(layers "F.Cu" "B.Cu")
		(remove_unused_layers yes)
		(keep_end_layers yes)
		(zone_layer_connections "In1.Cu" "In3.Cu" "In5.Cu")
		(net 1)
	)
	(via
		(at 99.09 90.31)
		(size 0.45)
		(drill 0.2)
		(layers "F.Cu" "B.Cu")
		(remove_unused_layers yes)
		(keep_end_layers yes)
		(free yes)
		(zone_layer_connections "In1.Cu" "In3.Cu" "In5.Cu")
		(net 1)
	)
	(via
		(at 96.6 74.9)
		(size 0.45)
		(drill 0.2)
		(layers "F.Cu" "B.Cu")
		(remove_unused_layers yes)
		(keep_end_layers yes)
		(zone_layer_connections "In1.Cu" "In3.Cu" "In5.Cu")
		(net 1)
	)
	(via
		(at 126.3 91.1)
		(size 0.45)
		(drill 0.2)
		(layers "F.Cu" "B.Cu")
		(remove_unused_layers yes)
		(keep_end_layers yes)
		(zone_layer_connections "In1.Cu" "In3.Cu" "In5.Cu")
		(net 1)
	)
	(via
		(at 81.03 79.65)
		(size 0.45)
		(drill 0.2)
		(layers "F.Cu" "B.Cu")
		(remove_unused_layers yes)
		(keep_end_layers yes)
		(zone_layer_connections "In3.Cu" "In5.Cu")
		(net 1)
	)
	(via
		(at 102.5 85.9)
		(size 0.45)
		(drill 0.2)
		(layers "F.Cu" "B.Cu")
		(remove_unused_layers yes)
		(keep_end_layers yes)
		(zone_layer_connections "In1.Cu" "In3.Cu" "In5.Cu")
		(net 1)
	)
	(via
		(at 111.03 66.15)
		(size 0.45)
		(drill 0.2)
		(layers "F.Cu" "B.Cu")
		(remove_unused_layers yes)
		(keep_end_layers yes)
		(free yes)
		(zone_layer_connections "In1.Cu" "In3.Cu" "In5.Cu")
		(net 1)
	)
	(via
		(at 92.6 80.9)
		(size 0.45)
		(drill 0.2)
		(layers "F.Cu" "B.Cu")
		(remove_unused_layers yes)
		(keep_end_layers yes)
		(zone_layer_connections "In1.Cu" "In3.Cu" "In5.Cu")
		(net 1)
	)
	(via
		(at 158.59 64.2)
		(size 0.45)
		(drill 0.2)
		(layers "F.Cu" "B.Cu")
		(remove_unused_layers yes)
		(keep_end_layers yes)
		(free yes)
		(zone_layer_connections "In1.Cu" "In3.Cu" "In5.Cu")
		(net 1)
	)
	(via
		(at 106.03 66.15)
		(size 0.45)
		(drill 0.2)
		(layers "F.Cu" "B.Cu")
		(remove_unused_layers yes)
		(keep_end_layers yes)
		(free yes)
		(zone_layer_connections "In1.Cu" "In3.Cu" "In5.Cu")
		(net 1)
	)
	(via
		(at 155.33 59.25)
		(size 0.45)
		(drill 0.2)
		(layers "F.Cu" "B.Cu")
		(remove_unused_layers yes)
		(keep_end_layers yes)
		(zone_layer_connections "In1.Cu" "In3.Cu" "In5.Cu")
		(net 1)
	)
	(via
		(at 120.76 71.64)
		(size 0.45)
		(drill 0.2)
		(layers "F.Cu" "B.Cu")
		(remove_unused_layers yes)
		(keep_end_layers yes)
		(zone_layer_connections "In1.Cu" "In3.Cu" "In5.Cu")
		(net 1)
	)
	(via
		(at 132.63 112.15)
		(size 0.45)
		(drill 0.2)
		(layers "F.Cu" "B.Cu")
		(remove_unused_layers yes)
		(keep_end_layers yes)
		(zone_layer_connections "In1.Cu" "In3.Cu" "In5.Cu")
		(net 1)
	)
	(via
		(at 93.6 76.9)
		(size 0.45)
		(drill 0.2)
		(layers "F.Cu" "B.Cu")
		(remove_unused_layers yes)
		(keep_end_layers yes)
		(zone_layer_connections "In1.Cu" "In3.Cu" "In5.Cu")
		(net 1)
	)
	(via
		(at 141.61 65.41)
		(size 0.45)
		(drill 0.2)
		(layers "F.Cu" "B.Cu")
		(remove_unused_layers yes)
		(keep_end_layers yes)
		(free yes)
		(zone_layer_connections "In1.Cu" "In3.Cu" "In5.Cu")
		(net 1)
	)
	(via
		(at 174.03 103.15)
		(size 0.45)
		(drill 0.2)
		(layers "F.Cu" "B.Cu")
		(remove_unused_layers yes)
		(keep_end_layers yes)
		(free yes)
		(zone_layer_connections "In1.Cu" "In3.Cu" "In5.Cu")
		(net 1)
	)
	(via
		(at 133.03 122.15)
		(size 0.45)
		(drill 0.2)
		(layers "F.Cu" "B.Cu")
		(remove_unused_layers yes)
		(keep_end_layers yes)
		(free yes)
		(zone_layer_connections "In1.Cu" "In3.Cu" "In5.Cu")
		(net 1)
	)
	(via
		(at 127.21 121.09)
		(size 0.45)
		(drill 0.2)
		(layers "F.Cu" "B.Cu")
		(remove_unused_layers yes)
		(keep_end_layers yes)
		(zone_layer_connections "In1.Cu" "In3.Cu" "In5.Cu")
		(net 1)
	)
	(via
		(at 133.37 62.52)
		(size 0.45)
		(drill 0.2)
		(layers "F.Cu" "B.Cu")
		(remove_unused_layers yes)
		(keep_end_layers yes)
		(free yes)
		(zone_layer_connections "In1.Cu" "In3.Cu" "In5.Cu")
		(net 1)
	)
	(via
		(at 92.36 72.47)
		(size 0.45)
		(drill 0.2)
		(layers "F.Cu" "B.Cu")
		(remove_unused_layers yes)
		(keep_end_layers yes)
		(zone_layer_connections "In1.Cu" "In3.Cu" "In5.Cu")
		(net 1)
	)
	(via
		(at 174.03 64.15)
		(size 0.45)
		(drill 0.2)
		(layers "F.Cu" "B.Cu")
		(remove_unused_layers yes)
		(keep_end_layers yes)
		(free yes)
		(zone_layer_connections "In1.Cu" "In3.Cu" "In5.Cu")
		(net 1)
	)
	(via
		(at 118.53 62.4)
		(size 0.45)
		(drill 0.2)
		(layers "F.Cu" "B.Cu")
		(remove_unused_layers yes)
		(keep_end_layers yes)
		(zone_layer_connections "In1.Cu" "In3.Cu" "In5.Cu")
		(net 1)
	)
	(via
		(at 162.63 99.55)
		(size 0.45)
		(drill 0.2)
		(layers "F.Cu" "B.Cu")
		(remove_unused_layers yes)
		(keep_end_layers yes)
		(zone_layer_connections "In1.Cu" "In3.Cu" "In5.Cu")
		(net 1)
	)
	(via
		(at 126.3 95.9)
		(size 0.45)
		(drill 0.2)
		(layers "F.Cu" "B.Cu")
		(remove_unused_layers yes)
		(keep_end_layers yes)
		(zone_layer_connections "In1.Cu" "In3.Cu" "In5.Cu")
		(net 1)
	)
	(via
		(at 156.404019 82.846255)
		(size 0.45)
		(drill 0.2)
		(layers "F.Cu" "B.Cu")
		(remove_unused_layers yes)
		(keep_end_layers yes)
		(zone_layer_connections "In1.Cu" "In3.Cu" "In5.Cu")
		(net 1)
	)
	(via
		(at 102.93 79.24)
		(size 0.45)
		(drill 0.2)
		(layers "F.Cu" "B.Cu")
		(remove_unused_layers yes)
		(keep_end_layers yes)
		(zone_layer_connections "In1.Cu" "In3.Cu" "In5.Cu")
		(net 1)
	)
	(via
		(at 174.03 67.15)
		(size 0.45)
		(drill 0.2)
		(layers "F.Cu" "B.Cu")
		(remove_unused_layers yes)
		(keep_end_layers yes)
		(free yes)
		(zone_layer_connections "In1.Cu" "In3.Cu" "In5.Cu")
		(net 1)
	)
	(via
		(at 116.03 124.15)
		(size 0.45)
		(drill 0.2)
		(layers "F.Cu" "B.Cu")
		(remove_unused_layers yes)
		(keep_end_layers yes)
		(free yes)
		(zone_layer_connections "In1.Cu" "In3.Cu" "In5.Cu")
		(net 1)
	)
	(via
		(at 166.41 111.37)
		(size 0.45)
		(drill 0.2)
		(layers "F.Cu" "B.Cu")
		(remove_unused_layers yes)
		(keep_end_layers yes)
		(free yes)
		(zone_layer_connections "In1.Cu" "In3.Cu" "In5.Cu")
		(net 1)
	)
	(via
		(at 91.34 71.62)
		(size 0.45)
		(drill 0.2)
		(layers "F.Cu" "B.Cu")
		(remove_unused_layers yes)
		(keep_end_layers yes)
		(zone_layer_connections "In1.Cu" "In3.Cu" "In5.Cu")
		(net 1)
	)
	(via
		(at 91.63 75.85)
		(size 0.45)
		(drill 0.2)
		(layers "F.Cu" "B.Cu")
		(remove_unused_layers yes)
		(keep_end_layers yes)
		(zone_layer_connections "In1.Cu" "In3.Cu" "In5.Cu")
		(net 1)
	)
	(via
		(at 101.03 124.15)
		(size 0.45)
		(drill 0.2)
		(layers "F.Cu" "B.Cu")
		(remove_unused_layers yes)
		(keep_end_layers yes)
		(free yes)
		(zone_layer_connections "In1.Cu" "In3.Cu" "In5.Cu")
		(net 1)
	)
	(via
		(at 149.83 64.95)
		(size 0.45)
		(drill 0.2)
		(layers "F.Cu" "B.Cu")
		(remove_unused_layers yes)
		(keep_end_layers yes)
		(free yes)
		(zone_layer_connections "In1.Cu" "In3.Cu" "In5.Cu")
		(net 1)
	)
	(via
		(at 121.76 117.71)
		(size 0.45)
		(drill 0.2)
		(layers "F.Cu" "B.Cu")
		(remove_unused_layers yes)
		(keep_end_layers yes)
		(free yes)
		(zone_layer_connections "In1.Cu" "In3.Cu" "In5.Cu")
		(net 1)
	)
	(via
		(at 155.59 74.34)
		(size 0.45)
		(drill 0.2)
		(layers "F.Cu" "B.Cu")
		(remove_unused_layers yes)
		(keep_end_layers yes)
		(free yes)
		(zone_layer_connections "In1.Cu" "In3.Cu" "In5.Cu")
		(net 1)
	)
	(via
		(at 112.487695 118.282908)
		(size 0.45)
		(drill 0.2)
		(layers "F.Cu" "B.Cu")
		(remove_unused_layers yes)
		(keep_end_layers yes)
		(free yes)
		(zone_layer_connections "In1.Cu" "In3.Cu" "In5.Cu")
		(net 1)
	)
	(via
		(at 174.03 112.15)
		(size 0.45)
		(drill 0.2)
		(layers "F.Cu" "B.Cu")
		(remove_unused_layers yes)
		(keep_end_layers yes)
		(free yes)
		(zone_layer_connections "In1.Cu" "In3.Cu" "In5.Cu")
		(net 1)
	)
	(via
		(at 125.5 95.9)
		(size 0.45)
		(drill 0.2)
		(layers "F.Cu" "B.Cu")
		(remove_unused_layers yes)
		(keep_end_layers yes)
		(zone_layer_connections "In1.Cu" "In3.Cu" "In5.Cu")
		(net 1)
	)
	(via
		(at 132.4 97.62)
		(size 0.45)
		(drill 0.2)
		(layers "F.Cu" "B.Cu")
		(remove_unused_layers yes)
		(keep_end_layers yes)
		(zone_layer_connections "In1.Cu" "In3.Cu" "In5.Cu")
		(net 1)
	)
	(via
		(at 95.6 78.9)
		(size 0.45)
		(drill 0.2)
		(layers "F.Cu" "B.Cu")
		(remove_unused_layers yes)
		(keep_end_layers yes)
		(zone_layer_connections "In1.Cu" "In3.Cu" "In5.Cu")
		(net 1)
	)
	(via
		(at 88.2 80.4)
		(size 0.45)
		(drill 0.2)
		(layers "F.Cu" "B.Cu")
		(remove_unused_layers yes)
		(keep_end_layers yes)
		(zone_layer_connections "In1.Cu" "In3.Cu" "In5.Cu")
		(net 1)
	)
	(via
		(at 100.03 66.15)
		(size 0.45)
		(drill 0.2)
		(layers "F.Cu" "B.Cu")
		(remove_unused_layers yes)
		(keep_end_layers yes)
		(free yes)
		(zone_layer_connections "In1.Cu" "In3.Cu" "In5.Cu")
		(net 1)
	)
	(via
		(at 127.69 72.77)
		(size 0.45)
		(drill 0.2)
		(layers "F.Cu" "B.Cu")
		(remove_unused_layers yes)
		(keep_end_layers yes)
		(free yes)
		(zone_layer_connections "In1.Cu" "In3.Cu" "In5.Cu")
		(net 1)
	)
	(via
		(at 142 120.75)
		(size 0.45)
		(drill 0.2)
		(layers "F.Cu" "B.Cu")
		(remove_unused_layers yes)
		(keep_end_layers yes)
		(zone_layer_connections "In1.Cu" "In3.Cu" "In5.Cu")
		(net 1)
	)
	(via
		(at 160.91 123.31)
		(size 0.45)
		(drill 0.2)
		(layers "F.Cu" "B.Cu")
		(net 1)
	)
	(via
		(at 143.59 113)
		(size 0.45)
		(drill 0.2)
		(layers "F.Cu" "B.Cu")
		(remove_unused_layers yes)
		(keep_end_layers yes)
		(free yes)
		(zone_layer_connections "In1.Cu" "In3.Cu" "In5.Cu")
		(net 1)
	)
	(via
		(at 163.5 104.5)
		(size 0.45)
		(drill 0.2)
		(layers "F.Cu" "B.Cu")
		(remove_unused_layers yes)
		(keep_end_layers yes)
		(zone_layer_connections "In1.Cu" "In3.Cu" "In5.Cu")
		(net 1)
	)
	(via
		(at 120.56 67.34)
		(size 0.45)
		(drill 0.2)
		(layers "F.Cu" "B.Cu")
		(remove_unused_layers yes)
		(keep_end_layers yes)
		(zone_layer_connections "In1.Cu" "In3.Cu" "In5.Cu")
		(net 1)
	)
	(via
		(at 174.03 121.15)
		(size 0.45)
		(drill 0.2)
		(layers "F.Cu" "B.Cu")
		(remove_unused_layers yes)
		(keep_end_layers yes)
		(free yes)
		(zone_layer_connections "In1.Cu" "In3.Cu" "In5.Cu")
		(net 1)
	)
	(via
		(at 101.84 102.7495)
		(size 0.45)
		(drill 0.2)
		(layers "F.Cu" "B.Cu")
		(remove_unused_layers yes)
		(keep_end_layers yes)
		(zone_layer_connections "In1.Cu" "In3.Cu" "In5.Cu")
		(net 1)
	)
	(via
		(at 159.4 91.15)
		(size 0.45)
		(drill 0.2)
		(layers "F.Cu" "B.Cu")
		(remove_unused_layers yes)
		(keep_end_layers yes)
		(zone_layer_connections "In1.Cu" "In3.Cu" "In5.Cu")
		(net 1)
	)
	(via
		(at 139.59 76.6)
		(size 0.45)
		(drill 0.2)
		(layers "F.Cu" "B.Cu")
		(remove_unused_layers yes)
		(keep_end_layers yes)
		(free yes)
		(zone_layer_connections "In1.Cu" "In3.Cu" "In5.Cu")
		(net 1)
	)
	(via
		(at 106.03 85.15)
		(size 0.45)
		(drill 0.2)
		(layers "F.Cu" "B.Cu")
		(remove_unused_layers yes)
		(keep_end_layers yes)
		(free yes)
		(zone_layer_connections "In1.Cu" "In3.Cu" "In5.Cu")
		(net 1)
	)
	(via
		(at 102.43 75.82)
		(size 0.45)
		(drill 0.2)
		(layers "F.Cu" "B.Cu")
		(remove_unused_layers yes)
		(keep_end_layers yes)
		(free yes)
		(zone_layer_connections "In1.Cu" "In3.Cu" "In5.Cu")
		(net 1)
	)
	(via
		(at 174.35 79.55)
		(size 0.45)
		(drill 0.2)
		(layers "F.Cu" "B.Cu")
		(remove_unused_layers yes)
		(keep_end_layers yes)
		(free yes)
		(zone_layer_connections "In1.Cu" "In3.Cu" "In5.Cu")
		(net 1)
	)
	(via
		(at 161.03 122.15)
		(size 0.45)
		(drill 0.2)
		(layers "F.Cu" "B.Cu")
		(remove_unused_layers yes)
		(keep_end_layers yes)
		(free yes)
		(zone_layer_connections "In1.Cu" "In3.Cu" "In5.Cu")
		(net 1)
	)
	(via
		(at 98.646047 71.147791)
		(size 0.45)
		(drill 0.2)
		(layers "F.Cu" "B.Cu")
		(remove_unused_layers yes)
		(keep_end_layers yes)
		(free yes)
		(zone_layer_connections "In1.Cu" "In3.Cu" "In5.Cu")
		(net 1)
	)
	(via
		(at 119.9 68.93)
		(size 0.45)
		(drill 0.2)
		(layers "F.Cu" "B.Cu")
		(remove_unused_layers yes)
		(keep_end_layers yes)
		(free yes)
		(zone_layer_connections "In1.Cu" "In3.Cu" "In5.Cu")
		(net 1)
	)
	(via
		(at 145.38 70.2)
		(size 0.45)
		(drill 0.2)
		(layers "F.Cu" "B.Cu")
		(remove_unused_layers yes)
		(keep_end_layers yes)
		(free yes)
		(zone_layer_connections "In1.Cu" "In3.Cu" "In5.Cu")
		(net 1)
	)
	(via
		(at 105.4195 98.7)
		(size 0.45)
		(drill 0.2)
		(layers "F.Cu" "B.Cu")
		(remove_unused_layers yes)
		(keep_end_layers yes)
		(zone_layer_connections "In1.Cu" "In3.Cu" "In5.Cu")
		(net 1)
	)
	(via
		(at 156.23 66.65)
		(size 0.45)
		(drill 0.2)
		(layers "F.Cu" "B.Cu")
		(remove_unused_layers yes)
		(keep_end_layers yes)
		(zone_layer_connections "In1.Cu" "In3.Cu" "In5.Cu")
		(net 1)
	)
	(via
		(at 130.28 68.4)
		(size 0.45)
		(drill 0.2)
		(layers "F.Cu" "B.Cu")
		(remove_unused_layers yes)
		(keep_end_layers yes)
		(free yes)
		(zone_layer_connections "In1.Cu" "In3.Cu" "In5.Cu")
		(net 1)
	)
	(via
		(at 158.59 66.9)
		(size 0.45)
		(drill 0.2)
		(layers "F.Cu" "B.Cu")
		(remove_unused_layers yes)
		(keep_end_layers yes)
		(free yes)
		(zone_layer_connections "In1.Cu" "In3.Cu" "In5.Cu")
		(net 1)
	)
	(via
		(at 127.9 87.1)
		(size 0.45)
		(drill 0.2)
		(layers "F.Cu" "B.Cu")
		(remove_unused_layers yes)
		(keep_end_layers yes)
		(zone_layer_connections "In1.Cu" "In3.Cu" "In5.Cu")
		(net 1)
	)
	(via
		(at 113.03 58.15)
		(size 0.45)
		(drill 0.2)
		(layers "F.Cu" "B.Cu")
		(remove_unused_layers yes)
		(keep_end_layers yes)
		(free yes)
		(zone_layer_connections "In1.Cu" "In3.Cu" "In5.Cu")
		(net 1)
	)
	(via
		(at 147.59 69.15)
		(size 0.45)
		(drill 0.2)
		(layers "F.Cu" "B.Cu")
		(remove_unused_layers yes)
		(keep_end_layers yes)
		(free yes)
		(zone_layer_connections "In1.Cu" "In3.Cu" "In5.Cu")
		(net 1)
	)
	(via
		(at 122.3 86.3)
		(size 0.45)
		(drill 0.2)
		(layers "F.Cu" "B.Cu")
		(remove_unused_layers yes)
		(keep_end_layers yes)
		(zone_layer_connections "In1.Cu" "In3.Cu" "In5.Cu")
		(net 1)
	)
	(via
		(at 142.63 66.4)
		(size 0.45)
		(drill 0.2)
		(layers "F.Cu" "B.Cu")
		(remove_unused_layers yes)
		(keep_end_layers yes)
		(free yes)
		(zone_layer_connections "In1.Cu" "In3.Cu" "In5.Cu")
		(net 1)
	)
	(via
		(at 138.89 75.6)
		(size 0.45)
		(drill 0.2)
		(layers "F.Cu" "B.Cu")
		(remove_unused_layers yes)
		(keep_end_layers yes)
		(free yes)
		(zone_layer_connections "In1.Cu" "In3.Cu" "In5.Cu")
		(net 1)
	)
	(via
		(at 143.19 114.45)
		(size 0.45)
		(drill 0.2)
		(layers "F.Cu" "B.Cu")
		(remove_unused_layers yes)
		(keep_end_layers yes)
		(free yes)
		(zone_layer_connections "In1.Cu" "In3.Cu" "In5.Cu")
		(net 1)
	)
	(via
		(at 122.3 89.5)
		(size 0.45)
		(drill 0.2)
		(layers "F.Cu" "B.Cu")
		(remove_unused_layers yes)
		(keep_end_layers yes)
		(zone_layer_connections "In1.Cu" "In3.Cu" "In5.Cu")
		(net 1)
	)
	(via
		(at 124.7 95.1)
		(size 0.45)
		(drill 0.2)
		(layers "F.Cu" "B.Cu")
		(remove_unused_layers yes)
		(keep_end_layers yes)
		(zone_layer_connections "In1.Cu" "In3.Cu" "In5.Cu")
		(net 1)
	)
	(via
		(at 158.59 66)
		(size 0.45)
		(drill 0.2)
		(layers "F.Cu" "B.Cu")
		(remove_unused_layers yes)
		(keep_end_layers yes)
		(free yes)
		(zone_layer_connections "In1.Cu" "In3.Cu" "In5.Cu")
		(net 1)
	)
	(via
		(at 171.172488 56.133443)
		(size 0.45)
		(drill 0.2)
		(layers "F.Cu" "B.Cu")
		(remove_unused_layers yes)
		(keep_end_layers yes)
		(free yes)
		(zone_layer_connections "In1.Cu" "In3.Cu" "In5.Cu")
		(net 1)
	)
	(via
		(at 107.099001 114.732219)
		(size 0.45)
		(drill 0.2)
		(layers "F.Cu" "B.Cu")
		(remove_unused_layers yes)
		(keep_end_layers yes)
		(free yes)
		(zone_layer_connections "In1.Cu" "In3.Cu" "In5.Cu")
		(net 1)
	)
	(via
		(at 174.375 86.175)
		(size 0.45)
		(drill 0.2)
		(layers "F.Cu" "B.Cu")
		(remove_unused_layers yes)
		(keep_end_layers yes)
		(free yes)
		(zone_layer_connections "In1.Cu" "In3.Cu" "In5.Cu")
		(net 1)
	)
	(via
		(at 143.19 115.45)
		(size 0.45)
		(drill 0.2)
		(layers "F.Cu" "B.Cu")
		(remove_unused_layers yes)
		(keep_end_layers yes)
		(free yes)
		(zone_layer_connections "In1.Cu" "In3.Cu" "In5.Cu")
		(net 1)
	)
	(via
		(at 166.444253 116.708199)
		(size 0.45)
		(drill 0.2)
		(layers "F.Cu" "B.Cu")
		(remove_unused_layers yes)
		(keep_end_layers yes)
		(zone_layer_connections "In1.Cu" "In3.Cu" "In5.Cu")
		(net 1)
	)
	(via
		(at 92.6 77.9)
		(size 0.45)
		(drill 0.2)
		(layers "F.Cu" "B.Cu")
		(remove_unused_layers yes)
		(keep_end_layers yes)
		(zone_layer_connections "In1.Cu" "In3.Cu" "In5.Cu")
		(net 1)
	)
	(via
		(at 174.03 94.15)
		(size 0.45)
		(drill 0.2)
		(layers "F.Cu" "B.Cu")
		(remove_unused_layers yes)
		(keep_end_layers yes)
		(free yes)
		(zone_layer_connections "In1.Cu" "In3.Cu" "In5.Cu")
		(net 1)
	)
	(via
		(at 99.7 82.97)
		(size 0.45)
		(drill 0.2)
		(layers "F.Cu" "B.Cu")
		(remove_unused_layers yes)
		(keep_end_layers yes)
		(free yes)
		(zone_layer_connections "In1.Cu" "In3.Cu" "In5.Cu")
		(net 1)
	)
	(via
		(at 103.53 70.9)
		(size 0.45)
		(drill 0.2)
		(layers "F.Cu" "B.Cu")
		(remove_unused_layers yes)
		(keep_end_layers yes)
		(free yes)
		(zone_layer_connections "In1.Cu" "In3.Cu" "In5.Cu")
		(net 1)
	)
	(via
		(at 137.19 109.7)
		(size 0.45)
		(drill 0.2)
		(layers "F.Cu" "B.Cu")
		(remove_unused_layers yes)
		(keep_end_layers yes)
		(zone_layer_connections "In1.Cu" "In3.Cu" "In5.Cu")
		(net 1)
	)
	(via
		(at 95.6 79.9)
		(size 0.45)
		(drill 0.2)
		(layers "F.Cu" "B.Cu")
		(remove_unused_layers yes)
		(keep_end_layers yes)
		(zone_layer_connections "In1.Cu" "In3.Cu" "In5.Cu")
		(net 1)
	)
	(via
		(at 129.65 104.09)
		(size 0.45)
		(drill 0.2)
		(layers "F.Cu" "B.Cu")
		(remove_unused_layers yes)
		(keep_end_layers yes)
		(free yes)
		(zone_layer_connections "In1.Cu" "In3.Cu" "In5.Cu")
		(net 1)
	)
	(via
		(at 141.69 110.7)
		(size 0.45)
		(drill 0.2)
		(layers "F.Cu" "B.Cu")
		(remove_unused_layers yes)
		(keep_end_layers yes)
		(free yes)
		(zone_layer_connections "In1.Cu" "In3.Cu" "In5.Cu")
		(net 1)
	)
	(via
		(at 149.84 69.15)
		(size 0.45)
		(drill 0.2)
		(layers "F.Cu" "B.Cu")
		(remove_unused_layers yes)
		(keep_end_layers yes)
		(free yes)
		(zone_layer_connections "In1.Cu" "In3.Cu" "In5.Cu")
		(net 1)
	)
	(via
		(at 120.56 66.54)
		(size 0.45)
		(drill 0.2)
		(layers "F.Cu" "B.Cu")
		(remove_unused_layers yes)
		(keep_end_layers yes)
		(zone_layer_connections "In1.Cu" "In3.Cu" "In5.Cu")
		(net 1)
	)
	(via
		(at 166.39 59.15)
		(size 0.45)
		(drill 0.2)
		(layers "F.Cu" "B.Cu")
		(remove_unused_layers yes)
		(keep_end_layers yes)
		(zone_layer_connections "In1.Cu" "In3.Cu" "In5.Cu")
		(net 1)
	)
	(via
		(at 103.53 119.99)
		(size 0.45)
		(drill 0.2)
		(layers "F.Cu" "B.Cu")
		(remove_unused_layers yes)
		(keep_end_layers yes)
		(zone_layer_connections "In1.Cu" "In3.Cu" "In5.Cu")
		(net 1)
	)
	(via
		(at 95.014208 108.143893)
		(size 0.45)
		(drill 0.2)
		(layers "F.Cu" "B.Cu")
		(remove_unused_layers yes)
		(keep_end_layers yes)
		(free yes)
		(zone_layer_connections "In1.Cu" "In3.Cu" "In5.Cu")
		(net 1)
	)
	(via
		(at 127.06 68.54)
		(size 0.45)
		(drill 0.2)
		(layers "F.Cu" "B.Cu")
		(remove_unused_layers yes)
		(keep_end_layers yes)
		(zone_layer_connections "In1.Cu" "In3.Cu" "In5.Cu")
		(net 1)
	)
	(via
		(at 132.7 83.9)
		(size 0.45)
		(drill 0.2)
		(layers "F.Cu" "B.Cu")
		(remove_unused_layers yes)
		(keep_end_layers yes)
		(zone_layer_connections "In1.Cu" "In3.Cu" "In5.Cu")
		(net 1)
	)
	(via
		(at 121.9 96.9)
		(size 0.45)
		(drill 0.2)
		(layers "F.Cu" "B.Cu")
		(remove_unused_layers yes)
		(keep_end_layers yes)
		(zone_layer_connections "In1.Cu" "In3.Cu" "In5.Cu")
		(net 1)
	)
	(via
		(at 162.43 64.35)
		(size 0.45)
		(drill 0.2)
		(layers "F.Cu" "B.Cu")
		(remove_unused_layers yes)
		(keep_end_layers yes)
		(free yes)
		(zone_layer_connections "In1.Cu" "In3.Cu" "In5.Cu")
		(net 1)
	)
	(via
		(at 168.03 56.15)
		(size 0.45)
		(drill 0.2)
		(layers "F.Cu" "B.Cu")
		(remove_unused_layers yes)
		(keep_end_layers yes)
		(free yes)
		(zone_layer_connections "In1.Cu" "In3.Cu" "In5.Cu")
		(net 1)
	)
	(via
		(at 148.88 76.05)
		(size 0.45)
		(drill 0.2)
		(layers "F.Cu" "B.Cu")
		(remove_unused_layers yes)
		(keep_end_layers yes)
		(free yes)
		(zone_layer_connections "In1.Cu" "In3.Cu" "In5.Cu")
		(net 1)
	)
	(via
		(at 146.85 79.9)
		(size 0.45)
		(drill 0.2)
		(layers "F.Cu" "B.Cu")
		(remove_unused_layers yes)
		(keep_end_layers yes)
		(free yes)
		(zone_layer_connections "In1.Cu" "In3.Cu" "In5.Cu")
		(net 1)
	)
	(via
		(at 122.161665 65.299464)
		(size 0.45)
		(drill 0.2)
		(layers "F.Cu" "B.Cu")
		(remove_unused_layers yes)
		(keep_end_layers yes)
		(zone_layer_connections "In1.Cu" "In3.Cu" "In5.Cu")
		(net 1)
	)
	(via
		(at 121.5 86.3)
		(size 0.45)
		(drill 0.2)
		(layers "F.Cu" "B.Cu")
		(remove_unused_layers yes)
		(keep_end_layers yes)
		(zone_layer_connections "In1.Cu" "In3.Cu" "In5.Cu")
		(net 1)
	)
	(via
		(at 93.6 77.9)
		(size 0.45)
		(drill 0.2)
		(layers "F.Cu" "B.Cu")
		(remove_unused_layers yes)
		(keep_end_layers yes)
		(zone_layer_connections "In1.Cu" "In3.Cu" "In5.Cu")
		(net 1)
	)
	(via
		(at 82.01 107.61)
		(size 0.45)
		(drill 0.2)
		(layers "F.Cu" "B.Cu")
		(remove_unused_layers yes)
		(keep_end_layers yes)
		(zone_layer_connections "In3.Cu" "In5.Cu")
		(net 1)
	)
	(via
		(at 77.03 70.15)
		(size 0.45)
		(drill 0.2)
		(layers "F.Cu" "B.Cu")
		(remove_unused_layers yes)
		(keep_end_layers yes)
		(zone_layer_connections "In3.Cu" "In5.Cu")
		(net 1)
	)
	(via
		(at 170.79 73.7)
		(size 0.45)
		(drill 0.2)
		(layers "F.Cu" "B.Cu")
		(remove_unused_layers yes)
		(keep_end_layers yes)
		(zone_layer_connections "In1.Cu" "In3.Cu" "In5.Cu")
		(net 1)
	)
	(via
		(at 166.83 97.73)
		(size 0.45)
		(drill 0.2)
		(layers "F.Cu" "B.Cu")
		(remove_unused_layers yes)
		(keep_end_layers yes)
		(free yes)
		(zone_layer_connections "In1.Cu" "In3.Cu" "In5.Cu")
		(net 1)
	)
	(via
		(at 93.11 95.97)
		(size 0.45)
		(drill 0.2)
		(layers "F.Cu" "B.Cu")
		(remove_unused_layers yes)
		(keep_end_layers yes)
		(zone_layer_connections "In1.Cu" "In3.Cu" "In5.Cu")
		(net 1)
	)
	(via
		(at 127.1 89.5)
		(size 0.45)
		(drill 0.2)
		(layers "F.Cu" "B.Cu")
		(remove_unused_layers yes)
		(keep_end_layers yes)
		(zone_layer_connections "In1.Cu" "In3.Cu" "In5.Cu")
		(net 1)
	)
	(via
		(at 147.39 76.05)
		(size 0.45)
		(drill 0.2)
		(layers "F.Cu" "B.Cu")
		(remove_unused_layers yes)
		(keep_end_layers yes)
		(free yes)
		(zone_layer_connections "In1.Cu" "In3.Cu" "In5.Cu")
		(net 1)
	)
	(via
		(at 134.475015 106.529815)
		(size 0.45)
		(drill 0.2)
		(layers "F.Cu" "B.Cu")
		(remove_unused_layers yes)
		(keep_end_layers yes)
		(zone_layer_connections "In1.Cu" "In3.Cu" "In5.Cu")
		(net 1)
	)
	(via
		(at 126.26 70.94)
		(size 0.45)
		(drill 0.2)
		(layers "F.Cu" "B.Cu")
		(remove_unused_layers yes)
		(keep_end_layers yes)
		(zone_layer_connections "In1.Cu" "In3.Cu" "In5.Cu")
		(net 1)
	)
	(via
		(at 138.94 103.45)
		(size 0.45)
		(drill 0.2)
		(layers "F.Cu" "B.Cu")
		(remove_unused_layers yes)
		(keep_end_layers yes)
		(free yes)
		(zone_layer_connections "In1.Cu" "In3.Cu" "In5.Cu")
		(net 1)
	)
	(via
		(at 142.49 113)
		(size 0.45)
		(drill 0.2)
		(layers "F.Cu" "B.Cu")
		(remove_unused_layers yes)
		(keep_end_layers yes)
		(free yes)
		(zone_layer_connections "In1.Cu" "In3.Cu" "In5.Cu")
		(net 1)
	)
	(via
		(at 159.115175 98.264825)
		(size 0.45)
		(drill 0.2)
		(layers "F.Cu" "B.Cu")
		(remove_unused_layers yes)
		(keep_end_layers yes)
		(zone_layer_connections "In1.Cu" "In3.Cu" "In5.Cu")
		(net 1)
	)
	(via
		(at 174.03 56.15)
		(size 0.45)
		(drill 0.2)
		(layers "F.Cu" "B.Cu")
		(remove_unused_layers yes)
		(keep_end_layers yes)
		(free yes)
		(zone_layer_connections "In1.Cu" "In3.Cu" "In5.Cu")
		(net 1)
	)
	(via
		(at 99.67 84.92)
		(size 0.45)
		(drill 0.2)
		(layers "F.Cu" "B.Cu")
		(remove_unused_layers yes)
		(keep_end_layers yes)
		(free yes)
		(zone_layer_connections "In1.Cu" "In3.Cu" "In5.Cu")
		(net 1)
	)
	(via
		(at 75.9 79.65)
		(size 0.45)
		(drill 0.2)
		(layers "F.Cu" "B.Cu")
		(remove_unused_layers yes)
		(keep_end_layers yes)
		(zone_layer_connections "In3.Cu" "In5.Cu")
		(net 1)
	)
	(via
		(at 127.03 123.15)
		(size 0.45)
		(drill 0.2)
		(layers "F.Cu" "B.Cu")
		(remove_unused_layers yes)
		(keep_end_layers yes)
		(free yes)
		(zone_layer_connections "In1.Cu" "In3.Cu" "In5.Cu")
		(net 1)
	)
	(via
		(at 92.6 79.9)
		(size 0.45)
		(drill 0.2)
		(layers "F.Cu" "B.Cu")
		(remove_unused_layers yes)
		(keep_end_layers yes)
		(zone_layer_connections "In1.Cu" "In3.Cu" "In5.Cu")
		(net 1)
	)
	(via
		(at 174.03 58.15)
		(size 0.45)
		(drill 0.2)
		(layers "F.Cu" "B.Cu")
		(remove_unused_layers yes)
		(keep_end_layers yes)
		(free yes)
		(zone_layer_connections "In1.Cu" "In3.Cu" "In5.Cu")
		(net 1)
	)
	(via
		(at 143.19 108.7)
		(size 0.45)
		(drill 0.2)
		(layers "F.Cu" "B.Cu")
		(remove_unused_layers yes)
		(keep_end_layers yes)
		(free yes)
		(zone_layer_connections "In1.Cu" "In3.Cu" "In5.Cu")
		(net 1)
	)
	(via
		(at 124.7 95.9)
		(size 0.45)
		(drill 0.2)
		(layers "F.Cu" "B.Cu")
		(remove_unused_layers yes)
		(keep_end_layers yes)
		(zone_layer_connections "In1.Cu" "In3.Cu" "In5.Cu")
		(net 1)
	)
	(via
		(at 75.775 100.175)
		(size 0.45)
		(drill 0.2)
		(layers "F.Cu" "B.Cu")
		(remove_unused_layers yes)
		(keep_end_layers yes)
		(zone_layer_connections "In3.Cu" "In5.Cu")
		(net 1)
	)
	(via
		(at 116.011369 56.077485)
		(size 0.45)
		(drill 0.2)
		(layers "F.Cu" "B.Cu")
		(remove_unused_layers yes)
		(keep_end_layers yes)
		(free yes)
		(zone_layer_connections "In1.Cu" "In3.Cu" "In5.Cu")
		(net 1)
	)
	(via
		(at 129.37 68.32)
		(size 0.45)
		(drill 0.2)
		(layers "F.Cu" "B.Cu")
		(remove_unused_layers yes)
		(keep_end_layers yes)
		(free yes)
		(zone_layer_connections "In1.Cu" "In3.Cu" "In5.Cu")
		(net 1)
	)
	(via
		(at 163.74 71.05)
		(size 0.45)
		(drill 0.2)
		(layers "F.Cu" "B.Cu")
		(remove_unused_layers yes)
		(keep_end_layers yes)
		(zone_layer_connections "In1.Cu" "In3.Cu" "In5.Cu")
		(net 1)
	)
	(via
		(at 128.56 62.37)
		(size 0.45)
		(drill 0.2)
		(layers "F.Cu" "B.Cu")
		(remove_unused_layers yes)
		(keep_end_layers yes)
		(zone_layer_connections "In1.Cu" "In3.Cu" "In5.Cu")
		(net 1)
	)
	(via
		(at 91.54438 77.936279)
		(size 0.45)
		(drill 0.2)
		(layers "F.Cu" "B.Cu")
		(remove_unused_layers yes)
		(keep_end_layers yes)
		(zone_layer_connections "In1.Cu" "In3.Cu" "In5.Cu")
		(net 1)
	)
	(via
		(at 82.03 66.15)
		(size 0.45)
		(drill 0.2)
		(layers "F.Cu" "B.Cu")
		(remove_unused_layers yes)
		(keep_end_layers yes)
		(free yes)
		(zone_layer_connections "In1.Cu" "In3.Cu" "In5.Cu")
		(net 1)
	)
	(via
		(at 127.3 81.6)
		(size 0.45)
		(drill 0.2)
		(layers "F.Cu" "B.Cu")
		(net 1)
	)
	(via
		(at 136.86 85.5)
		(size 0.45)
		(drill 0.2)
		(layers "F.Cu" "B.Cu")
		(remove_unused_layers yes)
		(keep_end_layers yes)
		(zone_layer_connections "In1.Cu" "In3.Cu" "In5.Cu")
		(net 1)
	)
	(via
		(at 170.65 97.91)
		(size 0.45)
		(drill 0.2)
		(layers "F.Cu" "B.Cu")
		(remove_unused_layers yes)
		(keep_end_layers yes)
		(zone_layer_connections "In1.Cu" "In3.Cu" "In5.Cu")
		(net 1)
	)
	(via
		(at 109.000419 98.499581)
		(size 0.45)
		(drill 0.2)
		(layers "F.Cu" "B.Cu")
		(net 1)
	)
	(via
		(at 121.46 66.14)
		(size 0.45)
		(drill 0.2)
		(layers "F.Cu" "B.Cu")
		(remove_unused_layers yes)
		(keep_end_layers yes)
		(zone_layer_connections "In1.Cu" "In3.Cu" "In5.Cu")
		(net 1)
	)
	(via
		(at 98.6 76.9)
		(size 0.45)
		(drill 0.2)
		(layers "F.Cu" "B.Cu")
		(remove_unused_layers yes)
		(keep_end_layers yes)
		(zone_layer_connections "In1.Cu" "In3.Cu" "In5.Cu")
		(net 1)
	)
	(via
		(at 94.6 76.9)
		(size 0.45)
		(drill 0.2)
		(layers "F.Cu" "B.Cu")
		(remove_unused_layers yes)
		(keep_end_layers yes)
		(zone_layer_connections "In1.Cu" "In3.Cu" "In5.Cu")
		(net 1)
	)
	(via
		(at 121.5 89.5)
		(size 0.45)
		(drill 0.2)
		(layers "F.Cu" "B.Cu")
		(remove_unused_layers yes)
		(keep_end_layers yes)
		(zone_layer_connections "In1.Cu" "In3.Cu" "In5.Cu")
		(net 1)
	)
	(via
		(at 162.23 65.15)
		(size 0.45)
		(drill 0.2)
		(layers "F.Cu" "B.Cu")
		(remove_unused_layers yes)
		(keep_end_layers yes)
		(free yes)
		(zone_layer_connections "In1.Cu" "In3.Cu" "In5.Cu")
		(net 1)
	)
	(via
		(at 137.021648 60.133803)
		(size 0.45)
		(drill 0.2)
		(layers "F.Cu" "B.Cu")
		(remove_unused_layers yes)
		(keep_end_layers yes)
		(zone_layer_connections "In1.Cu" "In3.Cu" "In5.Cu")
		(net 1)
	)
	(via
		(at 150.18 85.5)
		(size 0.45)
		(drill 0.2)
		(layers "F.Cu" "B.Cu")
		(remove_unused_layers yes)
		(keep_end_layers yes)
		(zone_layer_connections "In1.Cu" "In3.Cu" "In5.Cu")
		(net 1)
	)
	(via
		(at 166.8 103.33)
		(size 0.45)
		(drill 0.2)
		(layers "F.Cu" "B.Cu")
		(remove_unused_layers yes)
		(keep_end_layers yes)
		(free yes)
		(zone_layer_connections "In1.Cu" "In3.Cu" "In5.Cu")
		(net 1)
	)
	(via
		(at 103.42 78.15)
		(size 0.45)
		(drill 0.2)
		(layers "F.Cu" "B.Cu")
		(remove_unused_layers yes)
		(keep_end_layers yes)
		(free yes)
		(zone_layer_connections "In1.Cu" "In3.Cu" "In5.Cu")
		(net 1)
	)
	(via
		(at 76.03 94.15)
		(size 0.45)
		(drill 0.2)
		(layers "F.Cu" "B.Cu")
		(remove_unused_layers yes)
		(keep_end_layers yes)
		(free yes)
		(zone_layer_connections "In1.Cu" "In3.Cu" "In5.Cu")
		(net 1)
	)
	(via
		(at 120.75 60.7955)
		(size 0.45)
		(drill 0.2)
		(layers "F.Cu" "B.Cu")
		(remove_unused_layers yes)
		(keep_end_layers yes)
		(zone_layer_connections "In1.Cu" "In3.Cu" "In5.Cu")
		(net 1)
	)
	(via
		(at 155.949935 89.319935)
		(size 0.45)
		(drill 0.2)
		(layers "F.Cu" "B.Cu")
		(remove_unused_layers yes)
		(keep_end_layers yes)
		(zone_layer_connections "In1.Cu" "In3.Cu" "In5.Cu")
		(net 1)
	)
	(via
		(at 123.9 91.8995)
		(size 0.45)
		(drill 0.2)
		(layers "F.Cu" "B.Cu")
		(remove_unused_layers yes)
		(keep_end_layers yes)
		(zone_layer_connections "In1.Cu" "In3.Cu" "In5.Cu")
		(net 1)
	)
	(via
		(at 132.68 59.5)
		(size 0.45)
		(drill 0.2)
		(layers "F.Cu" "B.Cu")
		(net 1)
	)
	(via
		(at 159.03 86.65)
		(size 0.45)
		(drill 0.2)
		(layers "F.Cu" "B.Cu")
		(remove_unused_layers yes)
		(keep_end_layers yes)
		(zone_layer_connections "In1.Cu" "In3.Cu" "In5.Cu")
		(net 1)
	)
	(via
		(at 138.79 114.35)
		(size 0.45)
		(drill 0.2)
		(layers "F.Cu" "B.Cu")
		(remove_unused_layers yes)
		(keep_end_layers yes)
		(free yes)
		(zone_layer_connections "In1.Cu" "In3.Cu" "In5.Cu")
		(net 1)
	)
	(via
		(at 109.512099 92.993218)
		(size 0.45)
		(drill 0.2)
		(layers "F.Cu" "B.Cu")
		(net 1)
	)
	(via
		(at 150.83 110.6)
		(size 0.45)
		(drill 0.2)
		(layers "F.Cu" "B.Cu")
		(remove_unused_layers yes)
		(keep_end_layers yes)
		(zone_layer_connections "In1.Cu" "In3.Cu" "In5.Cu")
		(net 1)
	)
	(via
		(at 125.969216 104.45917)
		(size 0.45)
		(drill 0.2)
		(layers "F.Cu" "B.Cu")
		(remove_unused_layers yes)
		(keep_end_layers yes)
		(free yes)
		(zone_layer_connections "In1.Cu" "In3.Cu" "In5.Cu")
		(net 1)
	)
	(via
		(at 159.69 62.65)
		(size 0.45)
		(drill 0.2)
		(layers "F.Cu" "B.Cu")
		(remove_unused_layers yes)
		(keep_end_layers yes)
		(free yes)
		(zone_layer_connections "In1.Cu" "In3.Cu" "In5.Cu")
		(net 1)
	)
	(via
		(at 149.09 69.15)
		(size 0.45)
		(drill 0.2)
		(layers "F.Cu" "B.Cu")
		(remove_unused_layers yes)
		(keep_end_layers yes)
		(free yes)
		(zone_layer_connections "In1.Cu" "In3.Cu" "In5.Cu")
		(net 1)
	)
	(via
		(at 124.29 71.11)
		(size 0.45)
		(drill 0.2)
		(layers "F.Cu" "B.Cu")
		(remove_unused_layers yes)
		(keep_end_layers yes)
		(free yes)
		(zone_layer_connections "In1.Cu" "In3.Cu" "In5.Cu")
		(net 1)
	)
	(via
		(at 77.03 109.65)
		(size 0.45)
		(drill 0.2)
		(layers "F.Cu" "B.Cu")
		(remove_unused_layers yes)
		(keep_end_layers yes)
		(zone_layer_connections "In3.Cu" "In5.Cu")
		(net 1)
	)
	(via
		(at 145.44 104.45)
		(size 0.45)
		(drill 0.2)
		(layers "F.Cu" "B.Cu")
		(remove_unused_layers yes)
		(keep_end_layers yes)
		(free yes)
		(zone_layer_connections "In1.Cu" "In3.Cu" "In5.Cu")
		(net 1)
	)
	(via
		(at 106.8185 77.15)
		(size 0.45)
		(drill 0.2)
		(layers "F.Cu" "B.Cu")
		(remove_unused_layers yes)
		(keep_end_layers yes)
		(free yes)
		(zone_layer_connections "In1.Cu" "In3.Cu" "In5.Cu")
		(net 1)
	)
	(via
		(at 161.699825 96.480175)
		(size 0.45)
		(drill 0.2)
		(layers "F.Cu" "B.Cu")
		(remove_unused_layers yes)
		(keep_end_layers yes)
		(zone_layer_connections "In1.Cu" "In3.Cu" "In5.Cu")
		(net 1)
	)
	(via
		(at 76.03 121.15)
		(size 0.45)
		(drill 0.2)
		(layers "F.Cu" "B.Cu")
		(remove_unused_layers yes)
		(keep_end_layers yes)
		(free yes)
		(zone_layer_connections "In1.Cu" "In3.Cu" "In5.Cu")
		(net 1)
	)
	(via
		(at 76.03 115.15)
		(size 0.45)
		(drill 0.2)
		(layers "F.Cu" "B.Cu")
		(remove_unused_layers yes)
		(keep_end_layers yes)
		(free yes)
		(zone_layer_connections "In1.Cu" "In3.Cu" "In5.Cu")
		(net 1)
	)
	(via
		(at 85.03 66.15)
		(size 0.45)
		(drill 0.2)
		(layers "F.Cu" "B.Cu")
		(remove_unused_layers yes)
		(keep_end_layers yes)
		(free yes)
		(zone_layer_connections "In1.Cu" "In3.Cu" "In5.Cu")
		(net 1)
	)
	(via
		(at 79.03 66.15)
		(size 0.45)
		(drill 0.2)
		(layers "F.Cu" "B.Cu")
		(remove_unused_layers yes)
		(keep_end_layers yes)
		(free yes)
		(zone_layer_connections "In1.Cu" "In3.Cu" "In5.Cu")
		(net 1)
	)
	(via
		(at 76.03 91.15)
		(size 0.45)
		(drill 0.2)
		(layers "F.Cu" "B.Cu")
		(remove_unused_layers yes)
		(keep_end_layers yes)
		(free yes)
		(zone_layer_connections "In1.Cu" "In3.Cu" "In5.Cu")
		(net 1)
	)
	(via
		(at 140.19 110.7)
		(size 0.45)
		(drill 0.2)
		(layers "F.Cu" "B.Cu")
		(remove_unused_layers yes)
		(keep_end_layers yes)
		(free yes)
		(zone_layer_connections "In1.Cu" "In3.Cu" "In5.Cu")
		(net 1)
	)
	(via
		(at 110.029347 124.139637)
		(size 0.45)
		(drill 0.2)
		(layers "F.Cu" "B.Cu")
		(remove_unused_layers yes)
		(keep_end_layers yes)
		(free yes)
		(zone_layer_connections "In1.Cu" "In3.Cu" "In5.Cu")
		(net 1)
	)
	(via
		(at 166.71 112.81)
		(size 0.45)
		(drill 0.2)
		(layers "F.Cu" "B.Cu")
		(remove_unused_layers yes)
		(keep_end_layers yes)
		(free yes)
		(zone_layer_connections "In1.Cu" "In3.Cu" "In5.Cu")
		(net 1)
	)
	(via
		(at 144.78 61.35)
		(size 0.45)
		(drill 0.2)
		(layers "F.Cu" "B.Cu")
		(remove_unused_layers yes)
		(keep_end_layers yes)
		(free yes)
		(zone_layer_connections "In1.Cu" "In3.Cu" "In5.Cu")
		(net 1)
	)
	(via
		(at 93.65 74.72)
		(size 0.45)
		(drill 0.2)
		(layers "F.Cu" "B.Cu")
		(remove_unused_layers yes)
		(keep_end_layers yes)
		(zone_layer_connections "In1.Cu" "In3.Cu" "In5.Cu")
		(net 1)
	)
	(via
		(at 87.03 94.15)
		(size 0.45)
		(drill 0.2)
		(layers "F.Cu" "B.Cu")
		(remove_unused_layers yes)
		(keep_end_layers yes)
		(free yes)
		(zone_layer_connections "In1.Cu" "In3.Cu" "In5.Cu")
		(net 1)
	)
	(via
		(at 140.69 78.1)
		(size 0.45)
		(drill 0.2)
		(layers "F.Cu" "B.Cu")
		(remove_unused_layers yes)
		(keep_end_layers yes)
		(free yes)
		(zone_layer_connections "In1.Cu" "In3.Cu" "In5.Cu")
		(net 1)
	)
	(via
		(at 152.23 98.35)
		(size 0.45)
		(drill 0.2)
		(layers "F.Cu" "B.Cu")
		(remove_unused_layers yes)
		(keep_end_layers yes)
		(zone_layer_connections "In1.Cu" "In3.Cu" "In5.Cu")
		(net 1)
	)
	(via
		(at 150.03 56.15)
		(size 0.45)
		(drill 0.2)
		(layers "F.Cu" "B.Cu")
		(remove_unused_layers yes)
		(keep_end_layers yes)
		(free yes)
		(zone_layer_connections "In1.Cu" "In3.Cu" "In5.Cu")
		(net 1)
	)
	(via
		(at 76.03 68.15)
		(size 0.45)
		(drill 0.2)
		(layers "F.Cu" "B.Cu")
		(remove_unused_layers yes)
		(keep_end_layers yes)
		(free yes)
		(zone_layer_connections "In3.Cu" "In5.Cu")
		(net 1)
	)
	(via
		(at 89.54 82.45)
		(size 0.45)
		(drill 0.2)
		(layers "F.Cu" "B.Cu")
		(remove_unused_layers yes)
		(keep_end_layers yes)
		(free yes)
		(zone_layer_connections "In1.Cu" "In3.Cu" "In5.Cu")
		(net 1)
	)
	(via
		(at 150.65 64.05)
		(size 0.45)
		(drill 0.2)
		(layers "F.Cu" "B.Cu")
		(remove_unused_layers yes)
		(keep_end_layers yes)
		(free yes)
		(zone_layer_connections "In1.Cu" "In3.Cu" "In5.Cu")
		(net 1)
	)
	(via
		(at 138.49 65.2)
		(size 0.45)
		(drill 0.2)
		(layers "F.Cu" "B.Cu")
		(remove_unused_layers yes)
		(keep_end_layers yes)
		(free yes)
		(zone_layer_connections "In1.Cu" "In3.Cu" "In5.Cu")
		(net 1)
	)
	(via
		(at 174.03 89.15)
		(size 0.45)
		(drill 0.2)
		(layers "F.Cu" "B.Cu")
		(remove_unused_layers yes)
		(keep_end_layers yes)
		(free yes)
		(zone_layer_connections "In1.Cu" "In3.Cu" "In5.Cu")
		(net 1)
	)
	(via
		(at 127.1 92.7)
		(size 0.45)
		(drill 0.2)
		(layers "F.Cu" "B.Cu")
		(remove_unused_layers yes)
		(keep_end_layers yes)
		(zone_layer_connections "In1.Cu" "In3.Cu" "In5.Cu")
		(net 1)
	)
	(via
		(at 168.17 100.48)
		(size 0.45)
		(drill 0.2)
		(layers "F.Cu" "B.Cu")
		(remove_unused_layers yes)
		(keep_end_layers yes)
		(free yes)
		(zone_layer_connections "In1.Cu" "In3.Cu" "In5.Cu")
		(net 1)
	)
	(via
		(at 81.03 109.65)
		(size 0.45)
		(drill 0.2)
		(layers "F.Cu" "B.Cu")
		(remove_unused_layers yes)
		(keep_end_layers yes)
		(zone_layer_connections "In3.Cu" "In5.Cu")
		(net 1)
	)
	(via
		(at 170.64 106.9)
		(size 0.45)
		(drill 0.2)
		(layers "F.Cu" "B.Cu")
		(remove_unused_layers yes)
		(keep_end_layers yes)
		(zone_layer_connections "In1.Cu" "In3.Cu" "In5.Cu")
		(net 1)
	)
	(via
		(at 141.94 107.2)
		(size 0.45)
		(drill 0.2)
		(layers "F.Cu" "B.Cu")
		(remove_unused_layers yes)
		(keep_end_layers yes)
		(free yes)
		(zone_layer_connections "In1.Cu" "In3.Cu" "In5.Cu")
		(net 1)
	)
	(via
		(at 132.68 58.9)
		(size 0.45)
		(drill 0.2)
		(layers "F.Cu" "B.Cu")
		(net 1)
	)
	(via
		(at 170.59 103.91)
		(size 0.45)
		(drill 0.2)
		(layers "F.Cu" "B.Cu")
		(remove_unused_layers yes)
		(keep_end_layers yes)
		(zone_layer_connections "In1.Cu" "In3.Cu" "In5.Cu")
		(net 1)
	)
	(via
		(at 126.3 94.3)
		(size 0.45)
		(drill 0.2)
		(layers "F.Cu" "B.Cu")
		(remove_unused_layers yes)
		(keep_end_layers yes)
		(zone_layer_connections "In1.Cu" "In3.Cu" "In5.Cu")
		(net 1)
	)
	(via
		(at 144.84 78.05)
		(size 0.45)
		(drill 0.2)
		(layers "F.Cu" "B.Cu")
		(remove_unused_layers yes)
		(keep_end_layers yes)
		(free yes)
		(zone_layer_connections "In1.Cu" "In3.Cu" "In5.Cu")
		(net 1)
	)
	(via
		(at 121.5 87.9)
		(size 0.45)
		(drill 0.2)
		(layers "F.Cu" "B.Cu")
		(remove_unused_layers yes)
		(keep_end_layers yes)
		(zone_layer_connections "In1.Cu" "In3.Cu" "In5.Cu")
		(net 1)
	)
	(via
		(at 162.57 72.79)
		(size 0.45)
		(drill 0.2)
		(layers "F.Cu" "B.Cu")
		(remove_unused_layers yes)
		(keep_end_layers yes)
		(zone_layer_connections "In1.Cu" "In3.Cu" "In5.Cu")
		(net 1)
	)
	(via
		(at 125.1 96.9)
		(size 0.45)
		(drill 0.2)
		(layers "F.Cu" "B.Cu")
		(remove_unused_layers yes)
		(keep_end_layers yes)
		(zone_layer_connections "In1.Cu" "In3.Cu" "In5.Cu")
		(net 1)
	)
	(via
		(at 141.94 108.2)
		(size 0.45)
		(drill 0.2)
		(layers "F.Cu" "B.Cu")
		(remove_unused_layers yes)
		(keep_end_layers yes)
		(free yes)
		(zone_layer_connections "In1.Cu" "In3.Cu" "In5.Cu")
		(net 1)
	)
	(via
		(at 143.19 116.45)
		(size 0.45)
		(drill 0.2)
		(layers "F.Cu" "B.Cu")
		(remove_unused_layers yes)
		(keep_end_layers yes)
		(free yes)
		(zone_layer_connections "In1.Cu" "In3.Cu" "In5.Cu")
		(net 1)
	)
	(via
		(at 165.63 120.91)
		(size 0.45)
		(drill 0.2)
		(layers "F.Cu" "B.Cu")
		(remove_unused_layers yes)
		(keep_end_layers yes)
		(zone_layer_connections "In1.Cu" "In3.Cu" "In5.Cu")
		(net 1)
	)
	(via
		(at 162.99 76.6)
		(size 0.45)
		(drill 0.2)
		(layers "F.Cu" "B.Cu")
		(remove_unused_layers yes)
		(keep_end_layers yes)
		(zone_layer_connections "In1.Cu" "In3.Cu" "In5.Cu")
		(net 1)
	)
	(via
		(at 102.4 75.03)
		(size 0.45)
		(drill 0.2)
		(layers "F.Cu" "B.Cu")
		(remove_unused_layers yes)
		(keep_end_layers yes)
		(free yes)
		(zone_layer_connections "In1.Cu" "In3.Cu" "In5.Cu")
		(net 1)
	)
	(via
		(at 119.69 121.13)
		(size 0.45)
		(drill 0.2)
		(layers "F.Cu" "B.Cu")
		(remove_unused_layers yes)
		(keep_end_layers yes)
		(zone_layer_connections "In1.Cu" "In3.Cu" "In5.Cu")
		(net 1)
	)
	(via
		(at 144.44 104.45)
		(size 0.45)
		(drill 0.2)
		(layers "F.Cu" "B.Cu")
		(remove_unused_layers yes)
		(keep_end_layers yes)
		(free yes)
		(zone_layer_connections "In1.Cu" "In3.Cu" "In5.Cu")
		(net 1)
	)
	(via
		(at 76.03 102.15)
		(size 0.45)
		(drill 0.2)
		(layers "F.Cu" "B.Cu")
		(remove_unused_layers yes)
		(keep_end_layers yes)
		(free yes)
		(zone_layer_connections "In3.Cu" "In5.Cu")
		(net 1)
	)
	(via
		(at 152.23 101.15)
		(size 0.45)
		(drill 0.2)
		(layers "F.Cu" "B.Cu")
		(remove_unused_layers yes)
		(keep_end_layers yes)
		(zone_layer_connections "In1.Cu" "In3.Cu" "In5.Cu")
		(net 1)
	)
	(via
		(at 87.2 78.5)
		(size 0.45)
		(drill 0.2)
		(layers "F.Cu" "B.Cu")
		(remove_unused_layers yes)
		(keep_end_layers yes)
		(zone_layer_connections "In3.Cu" "In5.Cu")
		(net 1)
	)
	(via
		(at 140.44 103.45)
		(size 0.45)
		(drill 0.2)
		(layers "F.Cu" "B.Cu")
		(remove_unused_layers yes)
		(keep_end_layers yes)
		(free yes)
		(zone_layer_connections "In1.Cu" "In3.Cu" "In5.Cu")
		(net 1)
	)
	(via
		(at 156.57 118.8)
		(size 0.45)
		(drill 0.2)
		(layers "F.Cu" "B.Cu")
		(net 1)
	)
	(via
		(at 139.14 120)
		(size 0.45)
		(drill 0.2)
		(layers "F.Cu" "B.Cu")
		(remove_unused_layers yes)
		(keep_end_layers yes)
		(zone_layer_connections "In1.Cu" "In3.Cu" "In5.Cu")
		(net 1)
	)
	(via
		(at 84.03 113.15)
		(size 0.45)
		(drill 0.2)
		(layers "F.Cu" "B.Cu")
		(remove_unused_layers yes)
		(keep_end_layers yes)
		(free yes)
		(zone_layer_connections "In1.Cu" "In3.Cu" "In5.Cu")
		(net 1)
	)
	(via
		(at 160.97 118.98)
		(size 0.45)
		(drill 0.2)
		(layers "F.Cu" "B.Cu")
		(net 1)
	)
	(via
		(at 166.86 106.9)
		(size 0.45)
		(drill 0.2)
		(layers "F.Cu" "B.Cu")
		(remove_unused_layers yes)
		(keep_end_layers yes)
		(free yes)
		(zone_layer_connections "In1.Cu" "In3.Cu" "In5.Cu")
		(net 1)
	)
	(via
		(at 121.5 85.5)
		(size 0.45)
		(drill 0.2)
		(layers "F.Cu" "B.Cu")
		(remove_unused_layers yes)
		(keep_end_layers yes)
		(zone_layer_connections "In1.Cu" "In3.Cu" "In5.Cu")
		(net 1)
	)
	(via
		(at 85.03 124.15)
		(size 0.45)
		(drill 0.2)
		(layers "F.Cu" "B.Cu")
		(remove_unused_layers yes)
		(keep_end_layers yes)
		(free yes)
		(zone_layer_connections "In1.Cu" "In3.Cu" "In5.Cu")
		(net 1)
	)
	(via
		(at 93.6 78.9)
		(size 0.45)
		(drill 0.2)
		(layers "F.Cu" "B.Cu")
		(remove_unused_layers yes)
		(keep_end_layers yes)
		(zone_layer_connections "In1.Cu" "In3.Cu" "In5.Cu")
		(net 1)
	)
	(via
		(at 111.79 103.4)
		(size 0.45)
		(drill 0.2)
		(layers "F.Cu" "B.Cu")
		(remove_unused_layers yes)
		(keep_end_layers yes)
		(zone_layer_connections "In1.Cu" "In3.Cu" "In5.Cu")
		(net 1)
	)
	(via
		(at 128.67 71.78)
		(size 0.45)
		(drill 0.2)
		(layers "F.Cu" "B.Cu")
		(remove_unused_layers yes)
		(keep_end_layers yes)
		(free yes)
		(zone_layer_connections "In1.Cu" "In3.Cu" "In5.Cu")
		(net 1)
	)
	(via
		(at 76.03 88.15)
		(size 0.45)
		(drill 0.2)
		(layers "F.Cu" "B.Cu")
		(remove_unused_layers yes)
		(keep_end_layers yes)
		(free yes)
		(zone_layer_connections "In1.Cu" "In3.Cu" "In5.Cu")
		(net 1)
	)
	(via
		(at 174.375 83.45)
		(size 0.45)
		(drill 0.2)
		(layers "F.Cu" "B.Cu")
		(remove_unused_layers yes)
		(keep_end_layers yes)
		(free yes)
		(zone_layer_connections "In1.Cu" "In3.Cu" "In5.Cu")
		(net 1)
	)
	(via
		(at 86.1 79)
		(size 0.45)
		(drill 0.2)
		(layers "F.Cu" "B.Cu")
		(remove_unused_layers yes)
		(keep_end_layers yes)
		(zone_layer_connections "In3.Cu" "In5.Cu")
		(net 1)
	)
	(via
		(at 110.7 77.67)
		(size 0.45)
		(drill 0.2)
		(layers "F.Cu" "B.Cu")
		(remove_unused_layers yes)
		(keep_end_layers yes)
		(free yes)
		(zone_layer_connections "In1.Cu" "In3.Cu" "In5.Cu")
		(net 1)
	)
	(via
		(at 156.03 56.15)
		(size 0.45)
		(drill 0.2)
		(layers "F.Cu" "B.Cu")
		(remove_unused_layers yes)
		(keep_end_layers yes)
		(free yes)
		(zone_layer_connections "In1.Cu" "In3.Cu" "In5.Cu")
		(net 1)
	)
	(via
		(at 83.69 110.79)
		(size 0.45)
		(drill 0.2)
		(layers "F.Cu" "B.Cu")
		(remove_unused_layers yes)
		(keep_end_layers yes)
		(zone_layer_connections "In3.Cu" "In5.Cu")
		(net 1)
	)
	(via
		(at 101.03 68.65)
		(size 0.45)
		(drill 0.2)
		(layers "F.Cu" "B.Cu")
		(remove_unused_layers yes)
		(keep_end_layers yes)
		(free yes)
		(zone_layer_connections "In1.Cu" "In3.Cu" "In5.Cu")
		(net 1)
	)
	(via
		(at 125.55 106.26)
		(size 0.45)
		(drill 0.2)
		(layers "F.Cu" "B.Cu")
		(remove_unused_layers yes)
		(keep_end_layers yes)
		(zone_layer_connections "In1.Cu" "In3.Cu" "In5.Cu")
		(net 1)
	)
	(via
		(at 92.06 97.25)
		(size 0.45)
		(drill 0.2)
		(layers "F.Cu" "B.Cu")
		(remove_unused_layers yes)
		(keep_end_layers yes)
		(free yes)
		(zone_layer_connections "In1.Cu" "In3.Cu" "In5.Cu")
		(net 1)
	)
	(via
		(at 127.5 101.325)
		(size 0.45)
		(drill 0.2)
		(layers "F.Cu" "B.Cu")
		(remove_unused_layers yes)
		(keep_end_layers yes)
		(free yes)
		(zone_layer_connections "In1.Cu" "In3.Cu" "In5.Cu")
		(net 1)
	)
	(via
		(at 79.53 100.15)
		(size 0.45)
		(drill 0.2)
		(layers "F.Cu" "B.Cu")
		(remove_unused_layers yes)
		(keep_end_layers yes)
		(zone_layer_connections "In3.Cu" "In5.Cu")
		(net 1)
	)
	(via
		(at 140.19 106.95)
		(size 0.45)
		(drill 0.2)
		(layers "F.Cu" "B.Cu")
		(remove_unused_layers yes)
		(keep_end_layers yes)
		(free yes)
		(zone_layer_connections "In1.Cu" "In3.Cu" "In5.Cu")
		(net 1)
	)
	(via
		(at 141.39 113)
		(size 0.45)
		(drill 0.2)
		(layers "F.Cu" "B.Cu")
		(remove_unused_layers yes)
		(keep_end_layers yes)
		(free yes)
		(zone_layer_connections "In1.Cu" "In3.Cu" "In5.Cu")
		(net 1)
	)
	(via
		(at 107.03 124.15)
		(size 0.45)
		(drill 0.2)
		(layers "F.Cu" "B.Cu")
		(remove_unused_layers yes)
		(keep_end_layers yes)
		(free yes)
		(zone_layer_connections "In1.Cu" "In3.Cu" "In5.Cu")
		(net 1)
	)
	(via
		(at 120.66 62.54)
		(size 0.45)
		(drill 0.2)
		(layers "F.Cu" "B.Cu")
		(remove_unused_layers yes)
		(keep_end_layers yes)
		(zone_layer_connections "In1.Cu" "In3.Cu" "In5.Cu")
		(net 1)
	)
	(via
		(at 127.3 82.2)
		(size 0.45)
		(drill 0.2)
		(layers "F.Cu" "B.Cu")
		(net 1)
	)
	(via
		(at 130.299998 85.48)
		(size 0.45)
		(drill 0.2)
		(layers "F.Cu" "B.Cu")
		(remove_unused_layers yes)
		(keep_end_layers yes)
		(zone_layer_connections "In1.Cu" "In3.Cu" "In5.Cu")
		(net 1)
	)
	(via
		(at 82.03 124.15)
		(size 0.45)
		(drill 0.2)
		(layers "F.Cu" "B.Cu")
		(remove_unused_layers yes)
		(keep_end_layers yes)
		(free yes)
		(zone_layer_connections "In1.Cu" "In3.Cu" "In5.Cu")
		(net 1)
	)
	(via
		(at 119.9 87.9)
		(size 0.45)
		(drill 0.2)
		(layers "F.Cu" "B.Cu")
		(remove_unused_layers yes)
		(keep_end_layers yes)
		(zone_layer_connections "In1.Cu" "In3.Cu" "In5.Cu")
		(net 1)
	)
	(via
		(at 120.7 87.9)
		(size 0.45)
		(drill 0.2)
		(layers "F.Cu" "B.Cu")
		(remove_unused_layers yes)
		(keep_end_layers yes)
		(zone_layer_connections "In1.Cu" "In3.Cu" "In5.Cu")
		(net 1)
	)
	(via
		(at 142.62 90.76)
		(size 0.45)
		(drill 0.2)
		(layers "F.Cu" "B.Cu")
		(remove_unused_layers yes)
		(keep_end_layers yes)
		(free yes)
		(zone_layer_connections "In1.Cu" "In3.Cu" "In5.Cu")
		(net 1)
	)
	(via
		(at 101.32 82.94)
		(size 0.45)
		(drill 0.2)
		(layers "F.Cu" "B.Cu")
		(remove_unused_layers yes)
		(keep_end_layers yes)
		(free yes)
		(zone_layer_connections "In1.Cu" "In3.Cu" "In5.Cu")
		(net 1)
	)
	(via
		(at 160.73 65.35)
		(size 0.45)
		(drill 0.2)
		(layers "F.Cu" "B.Cu")
		(remove_unused_layers yes)
		(keep_end_layers yes)
		(free yes)
		(zone_layer_connections "In1.Cu" "In3.Cu" "In5.Cu")
		(net 1)
	)
	(via
		(at 76.024203 66.161814)
		(size 0.45)
		(drill 0.2)
		(layers "F.Cu" "B.Cu")
		(remove_unused_layers yes)
		(keep_end_layers yes)
		(free yes)
		(zone_layer_connections "In1.Cu" "In3.Cu" "In5.Cu")
		(net 1)
	)
	(via
		(at 86.48 115.56)
		(size 0.45)
		(drill 0.2)
		(layers "F.Cu" "B.Cu")
		(remove_unused_layers yes)
		(keep_end_layers yes)
		(zone_layer_connections "In1.Cu" "In3.Cu" "In5.Cu")
		(net 1)
	)
	(via
		(at 121.5 94.3)
		(size 0.45)
		(drill 0.2)
		(layers "F.Cu" "B.Cu")
		(remove_unused_layers yes)
		(keep_end_layers yes)
		(zone_layer_connections "In1.Cu" "In3.Cu" "In5.Cu")
		(net 1)
	)
	(via
		(at 103.3 66.15)
		(size 0.45)
		(drill 0.2)
		(layers "F.Cu" "B.Cu")
		(remove_unused_layers yes)
		(keep_end_layers yes)
		(free yes)
		(zone_layer_connections "In1.Cu" "In3.Cu" "In5.Cu")
		(net 1)
	)
	(via
		(at 174.03 124.15)
		(size 0.45)
		(drill 0.2)
		(layers "F.Cu" "B.Cu")
		(remove_unused_layers yes)
		(keep_end_layers yes)
		(free yes)
		(zone_layer_connections "In1.Cu" "In3.Cu" "In5.Cu")
		(net 1)
	)
	(via
		(at 122.3 87.9)
		(size 0.45)
		(drill 0.2)
		(layers "F.Cu" "B.Cu")
		(remove_unused_layers yes)
		(keep_end_layers yes)
		(zone_layer_connections "In1.Cu" "In3.Cu" "In5.Cu")
		(net 1)
	)
	(via
		(at 172.19 75)
		(size 0.45)
		(drill 0.2)
		(layers "F.Cu" "B.Cu")
		(remove_unused_layers yes)
		(keep_end_layers yes)
		(zone_layer_connections "In1.Cu" "In3.Cu" "In5.Cu")
		(net 1)
	)
	(via
		(at 123.1 87.1)
		(size 0.45)
		(drill 0.2)
		(layers "F.Cu" "B.Cu")
		(remove_unused_layers yes)
		(keep_end_layers yes)
		(zone_layer_connections "In1.Cu" "In3.Cu" "In5.Cu")
		(net 1)
	)
	(via
		(at 122.03 124.15)
		(size 0.45)
		(drill 0.2)
		(layers "F.Cu" "B.Cu")
		(remove_unused_layers yes)
		(keep_end_layers yes)
		(free yes)
		(zone_layer_connections "In1.Cu" "In3.Cu" "In5.Cu")
		(net 1)
	)
	(via
		(at 111.19 104.4)
		(size 0.45)
		(drill 0.2)
		(layers "F.Cu" "B.Cu")
		(remove_unused_layers yes)
		(keep_end_layers yes)
		(zone_layer_connections "In1.Cu" "In3.Cu" "In5.Cu")
		(net 1)
	)
	(via
		(at 103.75 90.6955)
		(size 0.45)
		(drill 0.2)
		(layers "F.Cu" "B.Cu")
		(remove_unused_layers yes)
		(keep_end_layers yes)
		(zone_layer_connections "In1.Cu" "In3.Cu" "In5.Cu")
		(net 1)
	)
	(via
		(at 102.59 73.2)
		(size 0.45)
		(drill 0.2)
		(layers "F.Cu" "B.Cu")
		(remove_unused_layers yes)
		(keep_end_layers yes)
		(free yes)
		(zone_layer_connections "In1.Cu" "In3.Cu" "In5.Cu")
		(net 1)
	)
	(via
		(at 91.83 105.74)
		(size 0.45)
		(drill 0.2)
		(layers "F.Cu" "B.Cu")
		(remove_unused_layers yes)
		(keep_end_layers yes)
		(zone_layer_connections "In1.Cu" "In3.Cu" "In5.Cu")
		(net 1)
	)
	(via
		(at 120.4 72.6295)
		(size 0.45)
		(drill 0.2)
		(layers "F.Cu" "B.Cu")
		(remove_unused_layers yes)
		(keep_end_layers yes)
		(free yes)
		(zone_layer_connections "In1.Cu" "In3.Cu" "In5.Cu")
		(net 1)
	)
	(via
		(at 76.03 124.15)
		(size 0.45)
		(drill 0.2)
		(layers "F.Cu" "B.Cu")
		(remove_unused_layers yes)
		(keep_end_layers yes)
		(free yes)
		(zone_layer_connections "In1.Cu" "In3.Cu" "In5.Cu")
		(net 1)
	)
	(via
		(at 126.3 84.7)
		(size 0.45)
		(drill 0.2)
		(layers "F.Cu" "B.Cu")
		(remove_unused_layers yes)
		(keep_end_layers yes)
		(free yes)
		(zone_layer_connections "In1.Cu" "In3.Cu" "In5.Cu")
		(net 1)
	)
	(via
		(at 174.03 72.15)
		(size 0.45)
		(drill 0.2)
		(layers "F.Cu" "B.Cu")
		(remove_unused_layers yes)
		(keep_end_layers yes)
		(free yes)
		(zone_layer_connections "In1.Cu" "In3.Cu" "In5.Cu")
		(net 1)
	)
	(via
		(at 118.21 121.14)
		(size 0.45)
		(drill 0.2)
		(layers "F.Cu" "B.Cu")
		(remove_unused_layers yes)
		(keep_end_layers yes)
		(zone_layer_connections "In1.Cu" "In3.Cu" "In5.Cu")
		(net 1)
	)
	(via
		(at 131.1 94.3)
		(size 0.45)
		(drill 0.2)
		(layers "F.Cu" "B.Cu")
		(remove_unused_layers yes)
		(keep_end_layers yes)
		(zone_layer_connections "In1.Cu" "In3.Cu" "In5.Cu")
		(net 1)
	)
	(via
		(at 170.67 105.36)
		(size 0.45)
		(drill 0.2)
		(layers "F.Cu" "B.Cu")
		(remove_unused_layers yes)
		(keep_end_layers yes)
		(zone_layer_connections "In1.Cu" "In3.Cu" "In5.Cu")
		(net 1)
	)
	(via
		(at 127.96 68.14)
		(size 0.45)
		(drill 0.2)
		(layers "F.Cu" "B.Cu")
		(remove_unused_layers yes)
		(keep_end_layers yes)
		(zone_layer_connections "In1.Cu" "In3.Cu" "In5.Cu")
		(net 1)
	)
	(via
		(at 102.309401 82.3985)
		(size 0.45)
		(drill 0.2)
		(layers "F.Cu" "B.Cu")
		(remove_unused_layers yes)
		(keep_end_layers yes)
		(free yes)
		(zone_layer_connections "In1.Cu" "In3.Cu" "In5.Cu")
		(net 1)
	)
	(via
		(at 87.03 86.15)
		(size 0.45)
		(drill 0.2)
		(layers "F.Cu" "B.Cu")
		(remove_unused_layers yes)
		(keep_end_layers yes)
		(free yes)
		(zone_layer_connections "In1.Cu" "In3.Cu" "In5.Cu")
		(net 1)
	)
	(via
		(at 125.5 90.3)
		(size 0.45)
		(drill 0.2)
		(layers "F.Cu" "B.Cu")
		(remove_unused_layers yes)
		(keep_end_layers yes)
		(zone_layer_connections "In1.Cu" "In3.Cu" "In5.Cu")
		(net 1)
	)
	(via
		(at 99.72 120.02)
		(size 0.45)
		(drill 0.2)
		(layers "F.Cu" "B.Cu")
		(remove_unused_layers yes)
		(keep_end_layers yes)
		(zone_layer_connections "In1.Cu" "In3.Cu" "In5.Cu")
		(net 1)
	)
	(via
		(at 141.69 111.7)
		(size 0.45)
		(drill 0.2)
		(layers "F.Cu" "B.Cu")
		(remove_unused_layers yes)
		(keep_end_layers yes)
		(free yes)
		(zone_layer_connections "In1.Cu" "In3.Cu" "In5.Cu")
		(net 1)
	)
	(via
		(at 97.1 85.1)
		(size 0.45)
		(drill 0.2)
		(layers "F.Cu" "B.Cu")
		(remove_unused_layers yes)
		(keep_end_layers yes)
		(zone_layer_connections "In1.Cu" "In3.Cu" "In5.Cu")
		(net 1)
	)
	(via
		(at 132.68 58.3)
		(size 0.45)
		(drill 0.2)
		(layers "F.Cu" "B.Cu")
		(net 1)
	)
	(via
		(at 128.18 73.7095)
		(size 0.45)
		(drill 0.2)
		(layers "F.Cu" "B.Cu")
		(remove_unused_layers yes)
		(keep_end_layers yes)
		(free yes)
		(zone_layer_connections "In1.Cu" "In3.Cu" "In5.Cu")
		(net 1)
	)
	(via
		(at 169.43 85.95)
		(size 0.45)
		(drill 0.2)
		(layers "F.Cu" "B.Cu")
		(remove_unused_layers yes)
		(keep_end_layers yes)
		(zone_layer_connections "In1.Cu" "In3.Cu" "In5.Cu")
		(net 1)
	)
	(via
		(at 144.44 109.2)
		(size 0.45)
		(drill 0.2)
		(layers "F.Cu" "B.Cu")
		(remove_unused_layers yes)
		(keep_end_layers yes)
		(free yes)
		(zone_layer_connections "In1.Cu" "In3.Cu" "In5.Cu")
		(net 1)
	)
	(via
		(at 100.89 72.16)
		(size 0.45)
		(drill 0.2)
		(layers "F.Cu" "B.Cu")
		(remove_unused_layers yes)
		(keep_end_layers yes)
		(free yes)
		(zone_layer_connections "In1.Cu" "In3.Cu" "In5.Cu")
		(net 1)
	)
	(via
		(at 170.09 114.33)
		(size 0.45)
		(drill 0.2)
		(layers "F.Cu" "B.Cu")
		(remove_unused_layers yes)
		(keep_end_layers yes)
		(zone_layer_connections "In1.Cu" "In3.Cu" "In5.Cu")
		(net 1)
	)
	(via
		(at 128.06 59.34)
		(size 0.45)
		(drill 0.2)
		(layers "F.Cu" "B.Cu")
		(remove_unused_layers yes)
		(keep_end_layers yes)
		(zone_layer_connections "In1.Cu" "In3.Cu" "In5.Cu")
		(net 1)
	)
	(via
		(at 88.99 105.85)
		(size 0.45)
		(drill 0.2)
		(layers "F.Cu" "B.Cu")
		(remove_unused_layers yes)
		(keep_end_layers yes)
		(zone_layer_connections "In3.Cu" "In5.Cu")
		(net 1)
	)
	(via
		(at 121.31 117.24)
		(size 0.45)
		(drill 0.2)
		(layers "F.Cu" "B.Cu")
		(remove_unused_layers yes)
		(keep_end_layers yes)
		(free yes)
		(zone_layer_connections "In1.Cu" "In3.Cu" "In5.Cu")
		(net 1)
	)
	(via
		(at 140.19 108.7)
		(size 0.45)
		(drill 0.2)
		(layers "F.Cu" "B.Cu")
		(remove_unused_layers yes)
		(keep_end_layers yes)
		(free yes)
		(zone_layer_connections "In1.Cu" "In3.Cu" "In5.Cu")
		(net 1)
	)
	(via
		(at 120.450023 70.5545)
		(size 0.45)
		(drill 0.2)
		(layers "F.Cu" "B.Cu")
		(remove_unused_layers yes)
		(keep_end_layers yes)
		(zone_layer_connections "In1.Cu" "In3.Cu" "In5.Cu")
		(net 1)
	)
	(via
		(at 75.8 109.65)
		(size 0.45)
		(drill 0.2)
		(layers "F.Cu" "B.Cu")
		(remove_unused_layers yes)
		(keep_end_layers yes)
		(zone_layer_connections "In3.Cu" "In5.Cu")
		(net 1)
	)
	(via
		(at 163.39 80.2)
		(size 0.45)
		(drill 0.2)
		(layers "F.Cu" "B.Cu")
		(remove_unused_layers yes)
		(keep_end_layers yes)
		(zone_layer_connections "In1.Cu" "In3.Cu" "In5.Cu")
		(net 1)
	)
	(via
		(at 113.03 56.15)
		(size 0.45)
		(drill 0.2)
		(layers "F.Cu" "B.Cu")
		(remove_unused_layers yes)
		(keep_end_layers yes)
		(free yes)
		(zone_layer_connections "In1.Cu" "In3.Cu" "In5.Cu")
		(net 1)
	)
	(via
		(at 127.96 60.94)
		(size 0.45)
		(drill 0.2)
		(layers "F.Cu" "B.Cu")
		(remove_unused_layers yes)
		(keep_end_layers yes)
		(zone_layer_connections "In1.Cu" "In3.Cu" "In5.Cu")
		(net 1)
	)
	(via
		(at 94.6 79.9)
		(size 0.45)
		(drill 0.2)
		(layers "F.Cu" "B.Cu")
		(remove_unused_layers yes)
		(keep_end_layers yes)
		(zone_layer_connections "In1.Cu" "In3.Cu" "In5.Cu")
		(net 1)
	)
	(via
		(at 156.61 123.28)
		(size 0.45)
		(drill 0.2)
		(layers "F.Cu" "B.Cu")
		(net 1)
	)
	(via
		(at 94.6 77.9)
		(size 0.45)
		(drill 0.2)
		(layers "F.Cu" "B.Cu")
		(remove_unused_layers yes)
		(keep_end_layers yes)
		(zone_layer_connections "In1.Cu" "In3.Cu" "In5.Cu")
		(net 1)
	)
	(via
		(at 148.08 88.25)
		(size 0.45)
		(drill 0.2)
		(layers "F.Cu" "B.Cu")
		(remove_unused_layers yes)
		(keep_end_layers yes)
		(zone_layer_connections "In1.Cu" "In3.Cu" "In5.Cu")
		(net 1)
	)
	(via
		(at 79.53 70.15)
		(size 0.45)
		(drill 0.2)
		(layers "F.Cu" "B.Cu")
		(remove_unused_layers yes)
		(keep_end_layers yes)
		(zone_layer_connections "In3.Cu" "In5.Cu")
		(net 1)
	)
	(via
		(at 141.94 106.2)
		(size 0.45)
		(drill 0.2)
		(layers "F.Cu" "B.Cu")
		(remove_unused_layers yes)
		(keep_end_layers yes)
		(free yes)
		(zone_layer_connections "In1.Cu" "In3.Cu" "In5.Cu")
		(net 1)
	)
	(via
		(at 152.23 59.25)
		(size 0.45)
		(drill 0.2)
		(layers "F.Cu" "B.Cu")
		(remove_unused_layers yes)
		(keep_end_layers yes)
		(zone_layer_connections "In1.Cu" "In3.Cu" "In5.Cu")
		(net 1)
	)
	(via
		(at 141.61 66.14)
		(size 0.45)
		(drill 0.2)
		(layers "F.Cu" "B.Cu")
		(remove_unused_layers yes)
		(keep_end_layers yes)
		(free yes)
		(zone_layer_connections "In1.Cu" "In3.Cu" "In5.Cu")
		(net 1)
	)
	(via
		(at 127.3 81)
		(size 0.45)
		(drill 0.2)
		(layers "F.Cu" "B.Cu")
		(net 1)
	)
	(via
		(at 75.85 70.15)
		(size 0.45)
		(drill 0.2)
		(layers "F.Cu" "B.Cu")
		(remove_unused_layers yes)
		(keep_end_layers yes)
		(zone_layer_connections "In3.Cu" "In5.Cu")
		(net 1)
	)
	(via
		(at 131.1 91.9)
		(size 0.45)
		(drill 0.2)
		(layers "F.Cu" "B.Cu")
		(remove_unused_layers yes)
		(keep_end_layers yes)
		(zone_layer_connections "In1.Cu" "In3.Cu" "In5.Cu")
		(net 1)
	)
	(via
		(at 128.46 66.04)
		(size 0.45)
		(drill 0.2)
		(layers "F.Cu" "B.Cu")
		(remove_unused_layers yes)
		(keep_end_layers yes)
		(zone_layer_connections "In1.Cu" "In3.Cu" "In5.Cu")
		(net 1)
	)
	(via
		(at 96.6 80.9)
		(size 0.45)
		(drill 0.2)
		(layers "F.Cu" "B.Cu")
		(remove_unused_layers yes)
		(keep_end_layers yes)
		(zone_layer_connections "In1.Cu" "In3.Cu" "In5.Cu")
		(net 1)
	)
	(via
		(at 109.8715 72.176202)
		(size 0.45)
		(drill 0.2)
		(layers "F.Cu" "B.Cu")
		(remove_unused_layers yes)
		(keep_end_layers yes)
		(free yes)
		(zone_layer_connections "In1.Cu" "In3.Cu" "In5.Cu")
		(net 1)
	)
	(via
		(at 126.58 117.79)
		(size 0.45)
		(drill 0.2)
		(layers "F.Cu" "B.Cu")
		(remove_unused_layers yes)
		(keep_end_layers yes)
		(free yes)
		(zone_layer_connections "In1.Cu" "In3.Cu" "In5.Cu")
		(net 1)
	)
	(via
		(at 120.66 59.34)
		(size 0.45)
		(drill 0.2)
		(layers "F.Cu" "B.Cu")
		(remove_unused_layers yes)
		(keep_end_layers yes)
		(zone_layer_connections "In1.Cu" "In3.Cu" "In5.Cu")
		(net 1)
	)
	(via
		(at 105.41 75.97)
		(size 0.45)
		(drill 0.2)
		(layers "F.Cu" "B.Cu")
		(remove_unused_layers yes)
		(keep_end_layers yes)
		(free yes)
		(zone_layer_connections "In1.Cu" "In3.Cu" "In5.Cu")
		(net 1)
	)
	(via
		(at 77.03 100.15)
		(size 0.45)
		(drill 0.2)
		(layers "F.Cu" "B.Cu")
		(remove_unused_layers yes)
		(keep_end_layers yes)
		(zone_layer_connections "In3.Cu" "In5.Cu")
		(net 1)
	)
	(via
		(at 146.14 63.5)
		(size 0.45)
		(drill 0.2)
		(layers "F.Cu" "B.Cu")
		(remove_unused_layers yes)
		(keep_end_layers yes)
		(free yes)
		(zone_layer_connections "In1.Cu" "In3.Cu" "In5.Cu")
		(net 1)
	)
	(via
		(at 125.9 96.9)
		(size 0.45)
		(drill 0.2)
		(layers "F.Cu" "B.Cu")
		(remove_unused_layers yes)
		(keep_end_layers yes)
		(zone_layer_connections "In1.Cu" "In3.Cu" "In5.Cu")
		(net 1)
	)
	(via
		(at 79.53 109.65)
		(size 0.45)
		(drill 0.2)
		(layers "F.Cu" "B.Cu")
		(remove_unused_layers yes)
		(keep_end_layers yes)
		(zone_layer_connections "In3.Cu" "In5.Cu")
		(net 1)
	)
	(via
		(at 150.73 64.95)
		(size 0.45)
		(drill 0.2)
		(layers "F.Cu" "B.Cu")
		(remove_unused_layers yes)
		(keep_end_layers yes)
		(free yes)
		(zone_layer_connections "In1.Cu" "In3.Cu" "In5.Cu")
		(net 1)
	)
	(via
		(at 138.49 72.9)
		(size 0.45)
		(drill 0.2)
		(layers "F.Cu" "B.Cu")
		(remove_unused_layers yes)
		(keep_end_layers yes)
		(free yes)
		(zone_layer_connections "In1.Cu" "In3.Cu" "In5.Cu")
		(net 1)
	)
	(via
		(at 109.03 66.15)
		(size 0.45)
		(drill 0.2)
		(layers "F.Cu" "B.Cu")
		(remove_unused_layers yes)
		(keep_end_layers yes)
		(free yes)
		(zone_layer_connections "In1.Cu" "In3.Cu" "In5.Cu")
		(net 1)
	)
	(via
		(at 137.45 62.02)
		(size 0.45)
		(drill 0.2)
		(layers "F.Cu" "B.Cu")
		(remove_unused_layers yes)
		(keep_end_layers yes)
		(zone_layer_connections "In1.Cu" "In3.Cu" "In5.Cu")
		(net 1)
	)
	(via
		(at 144.63 60.31)
		(size 0.45)
		(drill 0.2)
		(layers "F.Cu" "B.Cu")
		(remove_unused_layers yes)
		(keep_end_layers yes)
		(free yes)
		(zone_layer_connections "In1.Cu" "In3.Cu" "In5.Cu")
		(net 1)
	)
	(via
		(at 130.3 89.5)
		(size 0.45)
		(drill 0.2)
		(layers "F.Cu" "B.Cu")
		(remove_unused_layers yes)
		(keep_end_layers yes)
		(zone_layer_connections "In1.Cu" "In3.Cu" "In5.Cu")
		(net 1)
	)
	(via
		(at 127.14 117.68)
		(size 0.45)
		(drill 0.2)
		(layers "F.Cu" "B.Cu")
		(remove_unused_layers yes)
		(keep_end_layers yes)
		(free yes)
		(zone_layer_connections "In1.Cu" "In3.Cu" "In5.Cu")
		(net 1)
	)
	(via
		(at 102.356734 77.493436)
		(size 0.45)
		(drill 0.2)
		(layers "F.Cu" "B.Cu")
		(remove_unused_layers yes)
		(keep_end_layers yes)
		(free yes)
		(zone_layer_connections "In1.Cu" "In3.Cu" "In5.Cu")
		(net 1)
	)
	(via
		(at 120.7 89.5)
		(size 0.45)
		(drill 0.2)
		(layers "F.Cu" "B.Cu")
		(remove_unused_layers yes)
		(keep_end_layers yes)
		(zone_layer_connections "In1.Cu" "In3.Cu" "In5.Cu")
		(net 1)
	)
	(via
		(at 116.71 121.14)
		(size 0.45)
		(drill 0.2)
		(layers "F.Cu" "B.Cu")
		(remove_unused_layers yes)
		(keep_end_layers yes)
		(zone_layer_connections "In1.Cu" "In3.Cu" "In5.Cu")
		(net 1)
	)
	(via
		(at 159.03 56.15)
		(size 0.45)
		(drill 0.2)
		(layers "F.Cu" "B.Cu")
		(remove_unused_layers yes)
		(keep_end_layers yes)
		(free yes)
		(zone_layer_connections "In1.Cu" "In3.Cu" "In5.Cu")
		(net 1)
	)
	(via
		(at 125.5 91.1)
		(size 0.45)
		(drill 0.2)
		(layers "F.Cu" "B.Cu")
		(remove_unused_layers yes)
		(keep_end_layers yes)
		(zone_layer_connections "In1.Cu" "In3.Cu" "In5.Cu")
		(net 1)
	)
	(via
		(at 86.45 105.47)
		(size 0.45)
		(drill 0.2)
		(layers "F.Cu" "B.Cu")
		(remove_unused_layers yes)
		(keep_end_layers yes)
		(zone_layer_connections "In3.Cu" "In5.Cu")
		(net 1)
	)
	(via
		(at 96.96 88.98)
		(size 0.45)
		(drill 0.2)
		(layers "F.Cu" "B.Cu")
		(remove_unused_layers yes)
		(keep_end_layers yes)
		(zone_layer_connections "In1.Cu" "In3.Cu" "In5.Cu")
		(net 1)
	)
	(via
		(at 144.4 93.44)
		(size 0.45)
		(drill 0.2)
		(layers "F.Cu" "B.Cu")
		(remove_unused_layers yes)
		(keep_end_layers yes)
		(zone_layer_connections "In1.Cu" "In3.Cu" "In5.Cu")
		(net 1)
	)
	(via
		(at 141.43 101.1)
		(size 0.45)
		(drill 0.2)
		(layers "F.Cu" "B.Cu")
		(remove_unused_layers yes)
		(keep_end_layers yes)
		(zone_layer_connections "In1.Cu" "In3.Cu" "In5.Cu")
		(net 1)
	)
	(via
		(at 108.811687 116.695541)
		(size 0.45)
		(drill 0.2)
		(layers "F.Cu" "B.Cu")
		(remove_unused_layers yes)
		(keep_end_layers yes)
		(free yes)
		(zone_layer_connections "In1.Cu" "In3.Cu" "In5.Cu")
		(net 1)
	)
	(via
		(at 174.03 76.15)
		(size 0.45)
		(drill 0.2)
		(layers "F.Cu" "B.Cu")
		(remove_unused_layers yes)
		(keep_end_layers yes)
		(free yes)
		(zone_layer_connections "In1.Cu" "In3.Cu" "In5.Cu")
		(net 1)
	)
	(via
		(at 174.03 97.15)
		(size 0.45)
		(drill 0.2)
		(layers "F.Cu" "B.Cu")
		(remove_unused_layers yes)
		(keep_end_layers yes)
		(free yes)
		(zone_layer_connections "In1.Cu" "In3.Cu" "In5.Cu")
		(net 1)
	)
	(via
		(at 86.3 79.6)
		(size 0.45)
		(drill 0.2)
		(layers "F.Cu" "B.Cu")
		(remove_unused_layers yes)
		(keep_end_layers yes)
		(zone_layer_connections "In3.Cu" "In5.Cu")
		(net 1)
	)
	(via
		(at 83.03 90.15)
		(size 0.45)
		(drill 0.2)
		(layers "F.Cu" "B.Cu")
		(remove_unused_layers yes)
		(keep_end_layers yes)
		(free yes)
		(zone_layer_connections "In1.Cu" "In3.Cu" "In5.Cu")
		(net 1)
	)
	(via
		(at 123.258214 116.756765)
		(size 0.45)
		(drill 0.2)
		(layers "F.Cu" "B.Cu")
		(remove_unused_layers yes)
		(keep_end_layers yes)
		(free yes)
		(zone_layer_connections "In1.Cu" "In3.Cu" "In5.Cu")
		(net 1)
	)
	(via
		(at 147.75 120.75)
		(size 0.45)
		(drill 0.2)
		(layers "F.Cu" "B.Cu")
		(remove_unused_layers yes)
		(keep_end_layers yes)
		(zone_layer_connections "In1.Cu" "In3.Cu" "In5.Cu")
		(net 1)
	)
	(via
		(at 121.46 67.74)
		(size 0.45)
		(drill 0.2)
		(layers "F.Cu" "B.Cu")
		(remove_unused_layers yes)
		(keep_end_layers yes)
		(zone_layer_connections "In1.Cu" "In3.Cu" "In5.Cu")
		(net 1)
	)
	(via
		(at 154.75 120)
		(size 0.45)
		(drill 0.2)
		(layers "F.Cu" "B.Cu")
		(remove_unused_layers yes)
		(keep_end_layers yes)
		(zone_layer_connections "In1.Cu" "In3.Cu" "In5.Cu")
		(net 1)
	)
	(via
		(at 125.72 121.07)
		(size 0.45)
		(drill 0.2)
		(layers "F.Cu" "B.Cu")
		(remove_unused_layers yes)
		(keep_end_layers yes)
		(zone_layer_connections "In1.Cu" "In3.Cu" "In5.Cu")
		(net 1)
	)
	(via
		(at 79.53 79.65)
		(size 0.45)
		(drill 0.2)
		(layers "F.Cu" "B.Cu")
		(remove_unused_layers yes)
		(keep_end_layers yes)
		(zone_layer_connections "In3.Cu" "In5.Cu")
		(net 1)
	)
	(via
		(at 143.44 104.45)
		(size 0.45)
		(drill 0.2)
		(layers "F.Cu" "B.Cu")
		(remove_unused_layers yes)
		(keep_end_layers yes)
		(free yes)
		(zone_layer_connections "In1.Cu" "In3.Cu" "In5.Cu")
		(net 1)
	)
	(via
		(at 148.86 97.15)
		(size 0.45)
		(drill 0.2)
		(layers "F.Cu" "B.Cu")
		(remove_unused_layers yes)
		(keep_end_layers yes)
		(zone_layer_connections "In1.Cu" "In3.Cu" "In5.Cu")
		(net 1)
	)
	(via
		(at 124.7 87.9)
		(size 0.45)
		(drill 0.2)
		(layers "F.Cu" "B.Cu")
		(remove_unused_layers yes)
		(keep_end_layers yes)
		(zone_layer_connections "In1.Cu" "In3.Cu" "In5.Cu")
		(net 1)
	)
	(via
		(at 88.2 74.4)
		(size 0.45)
		(drill 0.2)
		(layers "F.Cu" "B.Cu")
		(remove_unused_layers yes)
		(keep_end_layers yes)
		(zone_layer_connections "In3.Cu" "In5.Cu")
		(net 1)
	)
	(via
		(at 130.03 70.65)
		(size 0.45)
		(drill 0.2)
		(layers "F.Cu" "B.Cu")
		(remove_unused_layers yes)
		(keep_end_layers yes)
		(free yes)
		(zone_layer_connections "In1.Cu" "In3.Cu" "In5.Cu")
		(net 1)
	)
	(via
		(at 129.5825 101.47)
		(size 0.45)
		(drill 0.2)
		(layers "F.Cu" "B.Cu")
		(remove_unused_layers yes)
		(keep_end_layers yes)
		(free yes)
		(zone_layer_connections "In1.Cu" "In3.Cu" "In5.Cu")
		(net 1)
	)
	(via
		(at 100.004726 71.194642)
		(size 0.45)
		(drill 0.2)
		(layers "F.Cu" "B.Cu")
		(remove_unused_layers yes)
		(keep_end_layers yes)
		(free yes)
		(zone_layer_connections "In1.Cu" "In3.Cu" "In5.Cu")
		(net 1)
	)
	(via
		(at 108.49 75.72)
		(size 0.45)
		(drill 0.2)
		(layers "F.Cu" "B.Cu")
		(remove_unused_layers yes)
		(keep_end_layers yes)
		(free yes)
		(zone_layer_connections "In1.Cu" "In3.Cu" "In5.Cu")
		(net 1)
	)
	(via
		(at 174.03 115.15)
		(size 0.45)
		(drill 0.2)
		(layers "F.Cu" "B.Cu")
		(remove_unused_layers yes)
		(keep_end_layers yes)
		(free yes)
		(zone_layer_connections "In1.Cu" "In3.Cu" "In5.Cu")
		(net 1)
	)
	(via
		(at 165.46 109.92)
		(size 0.45)
		(drill 0.2)
		(layers "F.Cu" "B.Cu")
		(remove_unused_layers yes)
		(keep_end_layers yes)
		(free yes)
		(zone_layer_connections "In1.Cu" "In3.Cu" "In5.Cu")
		(net 1)
	)
	(via
		(at 162.5 95.8)
		(size 0.45)
		(drill 0.2)
		(layers "F.Cu" "B.Cu")
		(remove_unused_layers yes)
		(keep_end_layers yes)
		(zone_layer_connections "In1.Cu" "In3.Cu" "In5.Cu")
		(net 1)
	)
	(via
		(at 158.25 123)
		(size 0.45)
		(drill 0.2)
		(layers "F.Cu" "B.Cu")
		(remove_unused_layers yes)
		(keep_end_layers yes)
		(zone_layer_connections "In1.Cu" "In3.Cu" "In5.Cu")
		(net 1)
	)
	(via
		(at 91.78 68.04)
		(size 0.45)
		(drill 0.2)
		(layers "F.Cu" "B.Cu")
		(remove_unused_layers yes)
		(keep_end_layers yes)
		(zone_layer_connections "In1.Cu" "In3.Cu" "In5.Cu")
		(net 1)
	)
	(via
		(at 162.81 120.97)
		(size 0.45)
		(drill 0.2)
		(layers "F.Cu" "B.Cu")
		(remove_unused_layers yes)
		(keep_end_layers yes)
		(zone_layer_connections "In1.Cu" "In3.Cu" "In5.Cu")
		(net 1)
	)
	(via
		(at 121.12751 121.20249)
		(size 0.45)
		(drill 0.2)
		(layers "F.Cu" "B.Cu")
		(remove_unused_layers yes)
		(keep_end_layers yes)
		(zone_layer_connections "In1.Cu" "In3.Cu" "In5.Cu")
		(net 1)
	)
	(via
		(at 81.03 70.15)
		(size 0.45)
		(drill 0.2)
		(layers "F.Cu" "B.Cu")
		(remove_unused_layers yes)
		(keep_end_layers yes)
		(zone_layer_connections "In3.Cu" "In5.Cu")
		(net 1)
	)
	(via
		(at 146.14 64.2)
		(size 0.45)
		(drill 0.2)
		(layers "F.Cu" "B.Cu")
		(remove_unused_layers yes)
		(keep_end_layers yes)
		(free yes)
		(zone_layer_connections "In1.Cu" "In3.Cu" "In5.Cu")
		(net 1)
	)
	(via
		(at 157.69 65.1)
		(size 0.45)
		(drill 0.2)
		(layers "F.Cu" "B.Cu")
		(remove_unused_layers yes)
		(keep_end_layers yes)
		(free yes)
		(zone_layer_connections "In1.Cu" "In3.Cu" "In5.Cu")
		(net 1)
	)
	(via
		(at 95.6 77.9)
		(size 0.45)
		(drill 0.2)
		(layers "F.Cu" "B.Cu")
		(remove_unused_layers yes)
		(keep_end_layers yes)
		(zone_layer_connections "In1.Cu" "In3.Cu" "In5.Cu")
		(net 1)
	)
	(via
		(at 95.03 124.15)
		(size 0.45)
		(drill 0.2)
		(layers "F.Cu" "B.Cu")
		(remove_unused_layers yes)
		(keep_end_layers yes)
		(free yes)
		(zone_layer_connections "In1.Cu" "In3.Cu" "In5.Cu")
		(net 1)
	)
	(via
		(at 145.03 66.4)
		(size 0.45)
		(drill 0.2)
		(layers "F.Cu" "B.Cu")
		(remove_unused_layers yes)
		(keep_end_layers yes)
		(free yes)
		(zone_layer_connections "In1.Cu" "In3.Cu" "In5.Cu")
		(net 1)
	)
	(via
		(at 75.975202 82.885706)
		(size 0.45)
		(drill 0.2)
		(layers "F.Cu" "B.Cu")
		(remove_unused_layers yes)
		(keep_end_layers yes)
		(free yes)
		(zone_layer_connections "In3.Cu" "In5.Cu")
		(net 1)
	)
	(via
		(at 113.03 124.15)
		(size 0.45)
		(drill 0.2)
		(layers "F.Cu" "B.Cu")
		(remove_unused_layers yes)
		(keep_end_layers yes)
		(free yes)
		(zone_layer_connections "In1.Cu" "In3.Cu" "In5.Cu")
		(net 1)
	)
	(via
		(at 97.7 84.97)
		(size 0.45)
		(drill 0.2)
		(layers "F.Cu" "B.Cu")
		(remove_unused_layers yes)
		(keep_end_layers yes)
		(free yes)
		(zone_layer_connections "In1.Cu" "In3.Cu" "In5.Cu")
		(net 1)
	)
	(via
		(at 141.69 115.45)
		(size 0.45)
		(drill 0.2)
		(layers "F.Cu" "B.Cu")
		(remove_unused_layers yes)
		(keep_end_layers yes)
		(free yes)
		(zone_layer_connections "In1.Cu" "In3.Cu" "In5.Cu")
		(net 1)
	)
	(via
		(at 94.99 98.09)
		(size 0.45)
		(drill 0.2)
		(layers "F.Cu" "B.Cu")
		(remove_unused_layers yes)
		(keep_end_layers yes)
		(free yes)
		(zone_layer_connections "In1.Cu" "In3.Cu" "In5.Cu")
		(net 1)
	)
	(via
		(at 129.5 87.1)
		(size 0.45)
		(drill 0.2)
		(layers "F.Cu" "B.Cu")
		(remove_unused_layers yes)
		(keep_end_layers yes)
		(zone_layer_connections "In1.Cu" "In3.Cu" "In5.Cu")
		(net 1)
	)
	(via
		(at 125.08 116.69)
		(size 0.45)
		(drill 0.2)
		(layers "F.Cu" "B.Cu")
		(remove_unused_layers yes)
		(keep_end_layers yes)
		(free yes)
		(zone_layer_connections "In1.Cu" "In3.Cu" "In5.Cu")
		(net 1)
	)
	(via
		(at 103.41 72.05)
		(size 0.45)
		(drill 0.2)
		(layers "F.Cu" "B.Cu")
		(remove_unused_layers yes)
		(keep_end_layers yes)
		(free yes)
		(zone_layer_connections "In1.Cu" "In3.Cu" "In5.Cu")
		(net 1)
	)
	(via
		(at 174.012383 100.228763)
		(size 0.45)
		(drill 0.2)
		(layers "F.Cu" "B.Cu")
		(remove_unused_layers yes)
		(keep_end_layers yes)
		(free yes)
		(zone_layer_connections "In1.Cu" "In3.Cu" "In5.Cu")
		(net 1)
	)
	(via
		(at 174.03 61.15)
		(size 0.45)
		(drill 0.2)
		(layers "F.Cu" "B.Cu")
		(remove_unused_layers yes)
		(keep_end_layers yes)
		(free yes)
		(zone_layer_connections "In1.Cu" "In3.Cu" "In5.Cu")
		(net 1)
	)
	(via
		(at 168.69 97.83)
		(size 0.45)
		(drill 0.2)
		(layers "F.Cu" "B.Cu")
		(remove_unused_layers yes)
		(keep_end_layers yes)
		(free yes)
		(zone_layer_connections "In1.Cu" "In3.Cu" "In5.Cu")
		(net 1)
	)
	(via
		(at 163.28 64.35)
		(size 0.45)
		(drill 0.2)
		(layers "F.Cu" "B.Cu")
		(remove_unused_layers yes)
		(keep_end_layers yes)
		(free yes)
		(zone_layer_connections "In1.Cu" "In3.Cu" "In5.Cu")
		(net 1)
	)
	(via
		(at 81.03 100.15)
		(size 0.45)
		(drill 0.2)
		(layers "F.Cu" "B.Cu")
		(remove_unused_layers yes)
		(keep_end_layers yes)
		(zone_layer_connections "In3.Cu" "In5.Cu")
		(net 1)
	)
	(via
		(at 104.03 124.15)
		(size 0.45)
		(drill 0.2)
		(layers "F.Cu" "B.Cu")
		(remove_unused_layers yes)
		(keep_end_layers yes)
		(free yes)
		(zone_layer_connections "In1.Cu" "In3.Cu" "In5.Cu")
		(net 1)
	)
	(via
		(at 94.31 69.81)
		(size 0.45)
		(drill 0.2)
		(layers "F.Cu" "B.Cu")
		(remove_unused_layers yes)
		(keep_end_layers yes)
		(zone_layer_connections "In1.Cu" "In3.Cu" "In5.Cu")
		(net 1)
	)
	(via
		(at 118.1 57.19)
		(size 0.45)
		(drill 0.2)
		(layers "F.Cu" "B.Cu")
		(remove_unused_layers yes)
		(keep_end_layers yes)
		(zone_layer_connections "In1.Cu" "In3.Cu" "In5.Cu")
		(net 1)
	)
	(via
		(at 132.88 65.22)
		(size 0.45)
		(drill 0.2)
		(layers "F.Cu" "B.Cu")
		(remove_unused_layers yes)
		(keep_end_layers yes)
		(free yes)
		(zone_layer_connections "In1.Cu" "In3.Cu" "In5.Cu")
		(net 1)
	)
	(via
		(at 125.5 85.5)
		(size 0.45)
		(drill 0.2)
		(layers "F.Cu" "B.Cu")
		(remove_unused_layers yes)
		(keep_end_layers yes)
		(zone_layer_connections "In1.Cu" "In3.Cu" "In5.Cu")
		(net 1)
	)
	(via
		(at 142.03 120.15)
		(size 0.45)
		(drill 0.2)
		(layers "F.Cu" "B.Cu")
		(remove_unused_layers yes)
		(keep_end_layers yes)
		(free yes)
		(zone_layer_connections "In1.Cu" "In3.Cu" "In5.Cu")
		(net 1)
	)
	(via
		(at 148.34 69.15)
		(size 0.45)
		(drill 0.2)
		(layers "F.Cu" "B.Cu")
		(remove_unused_layers yes)
		(keep_end_layers yes)
		(free yes)
		(zone_layer_connections "In1.Cu" "In3.Cu" "In5.Cu")
		(net 1)
	)
	(via
		(at 131.93 122.89)
		(size 0.45)
		(drill 0.2)
		(layers "F.Cu" "B.Cu")
		(remove_unused_layers yes)
		(keep_end_layers yes)
		(free yes)
		(zone_layer_connections "In1.Cu" "In3.Cu" "In5.Cu")
		(net 1)
	)
	(via
		(at 174.03 118.15)
		(size 0.45)
		(drill 0.2)
		(layers "F.Cu" "B.Cu")
		(remove_unused_layers yes)
		(keep_end_layers yes)
		(free yes)
		(zone_layer_connections "In1.Cu" "In3.Cu" "In5.Cu")
		(net 1)
	)
	(via
		(at 75.97 112.38)
		(size 0.45)
		(drill 0.2)
		(layers "F.Cu" "B.Cu")
		(remove_unused_layers yes)
		(keep_end_layers yes)
		(free yes)
		(zone_layer_connections "In1.Cu" "In3.Cu" "In5.Cu")
		(net 1)
	)
	(via
		(at 120.8295 97.13749)
		(size 0.45)
		(drill 0.2)
		(layers "F.Cu" "B.Cu")
		(remove_unused_layers yes)
		(keep_end_layers yes)
		(zone_layer_connections "In1.Cu" "In3.Cu" "In5.Cu")
		(net 1)
	)
	(via
		(at 100.99 119.98)
		(size 0.45)
		(drill 0.2)
		(layers "F.Cu" "B.Cu")
		(remove_unused_layers yes)
		(keep_end_layers yes)
		(zone_layer_connections "In1.Cu" "In3.Cu" "In5.Cu")
		(net 1)
	)
	(via
		(at 149.297348 81.349616)
		(size 0.45)
		(drill 0.2)
		(layers "F.Cu" "B.Cu")
		(remove_unused_layers yes)
		(keep_end_layers yes)
		(zone_layer_connections "In1.Cu" "In3.Cu" "In5.Cu")
		(net 1)
	)
	(via
		(at 152.63 83.55)
		(size 0.45)
		(drill 0.2)
		(layers "F.Cu" "B.Cu")
		(remove_unused_layers yes)
		(keep_end_layers yes)
		(zone_layer_connections "In1.Cu" "In3.Cu" "In5.Cu")
		(net 1)
	)
	(via
		(at 159.25 123)
		(size 0.45)
		(drill 0.2)
		(layers "F.Cu" "B.Cu")
		(remove_unused_layers yes)
		(keep_end_layers yes)
		(zone_layer_connections "In1.Cu" "In3.Cu" "In5.Cu")
		(net 1)
	)
	(via
		(at 146.14 64.85)
		(size 0.45)
		(drill 0.2)
		(layers "F.Cu" "B.Cu")
		(remove_unused_layers yes)
		(keep_end_layers yes)
		(free yes)
		(zone_layer_connections "In1.Cu" "In3.Cu" "In5.Cu")
		(net 1)
	)
	(via
		(at 128.7 95.1)
		(size 0.45)
		(drill 0.2)
		(layers "F.Cu" "B.Cu")
		(remove_unused_layers yes)
		(keep_end_layers yes)
		(zone_layer_connections "In1.Cu" "In3.Cu" "In5.Cu")
		(net 1)
	)
	(via
		(at 156.25 118.25)
		(size 0.45)
		(drill 0.2)
		(layers "F.Cu" "B.Cu")
		(remove_unused_layers yes)
		(keep_end_layers yes)
		(free yes)
		(zone_layer_connections "In1.Cu" "In3.Cu" "In5.Cu")
		(net 1)
	)
	(via
		(at 123.9 87.1)
		(size 0.45)
		(drill 0.2)
		(layers "F.Cu" "B.Cu")
		(remove_unused_layers yes)
		(keep_end_layers yes)
		(zone_layer_connections "In1.Cu" "In3.Cu" "In5.Cu")
		(net 1)
	)
	(via
		(at 102.9 76.4)
		(size 0.45)
		(drill 0.2)
		(layers "F.Cu" "B.Cu")
		(remove_unused_layers yes)
		(keep_end_layers yes)
		(zone_layer_connections "In1.Cu" "In3.Cu" "In5.Cu")
		(net 1)
	)
	(via
		(at 79.03 124.15)
		(size 0.45)
		(drill 0.2)
		(layers "F.Cu" "B.Cu")
		(remove_unused_layers yes)
		(keep_end_layers yes)
		(free yes)
		(zone_layer_connections "In1.Cu" "In3.Cu" "In5.Cu")
		(net 1)
	)
	(via
		(at 126.3 90.3)
		(size 0.45)
		(drill 0.2)
		(layers "F.Cu" "B.Cu")
		(remove_unused_layers yes)
		(keep_end_layers yes)
		(zone_layer_connections "In1.Cu" "In3.Cu" "In5.Cu")
		(net 1)
	)
	(via
		(at 165.03 122.15)
		(size 0.45)
		(drill 0.2)
		(layers "F.Cu" "B.Cu")
		(remove_unused_layers yes)
		(keep_end_layers yes)
		(free yes)
		(zone_layer_connections "In1.Cu" "In3.Cu" "In5.Cu")
		(net 1)
	)
	(via
		(at 88.03 66.15)
		(size 0.45)
		(drill 0.2)
		(layers "F.Cu" "B.Cu")
		(remove_unused_layers yes)
		(keep_end_layers yes)
		(free yes)
		(zone_layer_connections "In1.Cu" "In3.Cu" "In5.Cu")
		(net 1)
	)
	(via
		(at 134.27751 90.72751)
		(size 0.45)
		(drill 0.2)
		(layers "F.Cu" "B.Cu")
		(remove_unused_layers yes)
		(keep_end_layers yes)
		(zone_layer_connections "In1.Cu" "In3.Cu" "In5.Cu")
		(net 1)
	)
	(via
		(at 129.5 91.9)
		(size 0.45)
		(drill 0.2)
		(layers "F.Cu" "B.Cu")
		(remove_unused_layers yes)
		(keep_end_layers yes)
		(zone_layer_connections "In1.Cu" "In3.Cu" "In5.Cu")
		(net 1)
	)
	(via
		(at 141.69 109.7)
		(size 0.45)
		(drill 0.2)
		(layers "F.Cu" "B.Cu")
		(remove_unused_layers yes)
		(keep_end_layers yes)
		(free yes)
		(zone_layer_connections "In1.Cu" "In3.Cu" "In5.Cu")
		(net 1)
	)
	(via
		(at 125.4995 95.1)
		(size 0.45)
		(drill 0.2)
		(layers "F.Cu" "B.Cu")
		(remove_unused_layers yes)
		(keep_end_layers yes)
		(zone_layer_connections "In1.Cu" "In3.Cu" "In5.Cu")
		(net 1)
	)
	(via
		(at 94.6 78.9)
		(size 0.45)
		(drill 0.2)
		(layers "F.Cu" "B.Cu")
		(remove_unused_layers yes)
		(keep_end_layers yes)
		(zone_layer_connections "In1.Cu" "In3.Cu" "In5.Cu")
		(net 1)
	)
	(via
		(at 125.608496 111.633476)
		(size 0.45)
		(drill 0.2)
		(layers "F.Cu" "B.Cu")
		(remove_unused_layers yes)
		(keep_end_layers yes)
		(zone_layer_connections "In1.Cu" "In3.Cu" "In5.Cu")
		(net 1)
	)
	(via
		(at 135.28 113.45)
		(size 0.45)
		(drill 0.2)
		(layers "F.Cu" "B.Cu")
		(remove_unused_layers yes)
		(keep_end_layers yes)
		(zone_layer_connections "In1.Cu" "In3.Cu" "In5.Cu")
		(net 1)
	)
	(via
		(at 146.63 70.15)
		(size 0.45)
		(drill 0.2)
		(layers "F.Cu" "B.Cu")
		(remove_unused_layers yes)
		(keep_end_layers yes)
		(free yes)
		(zone_layer_connections "In1.Cu" "In3.Cu" "In5.Cu")
		(net 1)
	)
	(via
		(at 160.58 88.07)
		(size 0.45)
		(drill 0.2)
		(layers "F.Cu" "B.Cu")
		(remove_unused_layers yes)
		(keep_end_layers yes)
		(zone_layer_connections "In1.Cu" "In3.Cu" "In5.Cu")
		(net 1)
	)
	(via
		(at 99.6 79.9)
		(size 0.45)
		(drill 0.2)
		(layers "F.Cu" "B.Cu")
		(remove_unused_layers yes)
		(keep_end_layers yes)
		(zone_layer_connections "In1.Cu" "In3.Cu" "In5.Cu")
		(net 1)
	)
	(via
		(at 138.49 56.5)
		(size 0.45)
		(drill 0.2)
		(layers "F.Cu" "B.Cu")
		(remove_unused_layers yes)
		(keep_end_layers yes)
		(zone_layer_connections "In1.Cu" "In3.Cu" "In5.Cu")
		(net 1)
	)
	(via
		(at 127.96 68.94)
		(size 0.45)
		(drill 0.2)
		(layers "F.Cu" "B.Cu")
		(remove_unused_layers yes)
		(keep_end_layers yes)
		(zone_layer_connections "In1.Cu" "In3.Cu" "In5.Cu")
		(net 1)
	)
	(via
		(at 154.29 75.69)
		(size 0.45)
		(drill 0.2)
		(layers "F.Cu" "B.Cu")
		(remove_unused_layers yes)
		(keep_end_layers yes)
		(free yes)
		(zone_layer_connections "In1.Cu" "In3.Cu" "In5.Cu")
		(net 1)
	)
	(via
		(at 129.915997 123.10013)
		(size 0.45)
		(drill 0.2)
		(layers "F.Cu" "B.Cu")
		(remove_unused_layers yes)
		(keep_end_layers yes)
		(free yes)
		(zone_layer_connections "In1.Cu" "In3.Cu" "In5.Cu")
		(net 1)
	)
	(segment
		(start 127.0995 93.5)
		(end 127.0995 93.932048)
		(width 0.3)
		(layer "B.Cu")
		(net 1)
	)
	(segment
		(start 93.25 95.75)
		(end 93.25 95.25)
		(width 0.15)
		(layer "B.Cu")
		(net 1)
	)
	(segment
		(start 162.43 99.75)
		(end 162.43 100.465)
		(width 0.15)
		(layer "B.Cu")
		(net 1)
	)
	(segment
		(start 162.43 105.35)
		(end 162.83 105.35)
		(width 0.15)
		(layer "B.Cu")
		(net 1)
	)
	(segment
		(start 134.31 91.36)
		(end 134.09 91.14)
		(width 0.3)
		(layer "B.Cu")
		(net 1)
	)
	(segment
		(start 152.23 65.765)
		(end 152.23 64.95)
		(width 0.3)
		(layer "B.Cu")
		(net 1)
	)
	(segment
		(start 93.25 95.25)
		(end 93.765 95.25)
		(width 0.15)
		(layer "B.Cu")
		(net 1)
	)
	(segment
		(start 166.444253 116.708199)
		(end 165.1 115.363946)
		(width 0.5)
		(layer "B.Cu")
		(net 1)
	)
	(segment
		(start 162.63 99.55)
		(end 162.43 99.75)
		(width 0.15)
		(layer "B.Cu")
		(net 1)
	)
	(segment
		(start 162.83 105.35)
		(end 163.63 104.55)
		(width 0.15)
		(layer "B.Cu")
		(net 1)
	)
	(segment
		(start 127.15 84.7)
		(end 127.743726 85.293726)
		(width 0.3)
		(layer "B.Cu")
		(net 1)
	)
	(segment
		(start 133.7 95.231146)
		(end 134.031146 94.9)
		(width 0.5)
		(layer "B.Cu")
		(net 1)
	)
	(segment
		(start 146.725 87.05)
		(end 147.25 87.05)
		(width 0.3)
		(layer "B.Cu")
		(net 1)
	)
	(segment
		(start 161.49 72.8)
		(end 162.56 72.8)
		(width 0.3)
		(layer "B.Cu")
		(net 1)
	)
	(segment
		(start 132.4 97.62)
		(end 131.89 97.62)
		(width 0.3)
		(layer "B.Cu")
		(net 1)
	)
	(segment
		(start 88.815 80.4)
		(end 88.2 80.4)
		(width 0.1)
		(layer "B.Cu")
		(net 1)
	)
	(segment
		(start 152.38 102.7)
		(end 152.23 102.55)
		(width 0.3)
		(layer "B.Cu")
		(net 1)
	)
	(segment
		(start 120.52 62.4)
		(end 120.66 62.54)
		(width 0.5)
		(layer "B.Cu")
		(net 1)
	)
	(segment
		(start 97.1 85.1)
		(end 97.1 84.485)
		(width 0.5)
		(layer "B.Cu")
		(net 1)
	)
	(segment
		(start 159.03 66.05)
		(end 158.64 66.05)
		(width 0.3)
		(layer "B.Cu")
		(net 1)
	)
	(segment
		(start 153.03 98.835)
		(end 152.715 98.835)
		(width 0.3)
		(layer "B.Cu")
		(net 1)
	)
	(segment
		(start 126.88 92.48)
		(end 127.1 92.7)
		(width 0.3)
		(layer "B.Cu")
		(net 1)
	)
	(segment
		(start 159.58 66.6)
		(end 159.03 66.05)
		(width 0.3)
		(layer "B.Cu")
		(net 1)
	)
	(segment
		(start 155.89 73.385)
		(end 155.89 74.04)
		(width 0.3)
		(layer "B.Cu")
		(net 1)
	)
	(segment
		(start 133.08 83.3)
		(end 133.08 83.52)
		(width 0.3)
		(layer "B.Cu")
		(net 1)
	)
	(segment
		(start 160.3925 96.5)
		(end 161.68 96.5)
		(width 0.3)
		(layer "B.Cu")
		(net 1)
	)
	(segment
		(start 129.5 87.82)
		(end 129.42 87.9)
		(width 0.3)
		(layer "B.Cu")
		(net 1)
	)
	(segment
		(start 165.1 115.363946)
		(end 165.1 112.72)
		(width 0.5)
		(layer "B.Cu")
		(net 1)
	)
	(segment
		(start 127.0995 93.5)
		(end 127.0995 92.7005)
		(width 0.3)
		(layer "B.Cu")
		(net 1)
	)
	(segment
		(start 136.92 62.55)
		(end 137.45 62.02)
		(width 0.3)
		(layer "B.Cu")
		(net 1)
	)
	(segment
		(start 93.565 74.635)
		(end 93.565 74.06)
		(width 0.5)
		(layer "B.Cu")
		(net 1)
	)
	(segment
		(start 159.69 72.35)
		(end 161.04 72.35)
		(width 0.5)
		(layer "B.Cu")
		(net 1)
	)
	(segment
		(start 124.123726 86.976274)
		(end 124.023726 86.976274)
		(width 0.3)
		(layer "B.Cu")
		(net 1)
	)
	(segment
		(start 90.56 71.625)
		(end 91.335 71.625)
		(width 0.5)
		(layer "B.Cu")
		(net 1)
	)
	(segment
		(start 132.68 58.3)
		(end 130.76 58.3)
		(width 0.2)
		(layer "B.Cu")
		(net 1)
	)
	(segment
		(start 159.58 97.8)
		(end 159.115175 98.264825)
		(width 0.3)
		(layer "B.Cu")
		(net 1)
	)
	(segment
		(start 131.1 94.3)
		(end 130.3 94.3)
		(width 0.3)
		(layer "B.Cu")
		(net 1)
	)
	(segment
		(start 93.11 95.97)
		(end 93.25 95.75)
		(width 0.15)
		(layer "B.Cu")
		(net 1)
	)
	(segment
		(start 92.355 72.475)
		(end 92.36 72.47)
		(width 0.5)
		(layer "B.Cu")
		(net 1)
	)
	(segment
		(start 93.25 93.25)
		(end 93.25 95.25)
		(width 0.15)
		(layer "B.Cu")
		(net 1)
	)
	(segment
		(start 152.715 98.835)
		(end 152.23 98.35)
		(width 0.3)
		(layer "B.Cu")
		(net 1)
	)
	(segment
		(start 133.08 83.52)
		(end 132.7 83.9)
		(width 0.3)
		(layer "B.Cu")
		(net 1)
	)
	(segment
		(start 127.0995 92.7005)
		(end 127.1 92.7)
		(width 0.3)
		(layer "B.Cu")
		(net 1)
	)
	(segment
		(start 97.325 74.175)
		(end 96.6 74.9)
		(width 0.5)
		(layer "B.Cu")
		(net 1)
	)
	(segment
		(start 124.7 88.38)
		(end 124.7 87.9)
		(width 0.3)
		(layer "B.Cu")
		(net 1)
	)
	(segment
		(start 126.3 84.7)
		(end 127.15 84.7)
		(width 0.3)
		(layer "B.Cu")
		(net 1)
	)
	(segment
		(start 148.661964 81.985)
		(end 149.297348 81.349616)
		(width 0.3)
		(layer "B.Cu")
		(net 1)
	)
	(segment
		(start 132.4135 96.8)
		(end 132.4135 96.7435)
		(width 0.3)
		(layer "B.Cu")
		(net 1)
	)
	(segment
		(start 152.23 59.765)
		(end 152.23 59.25)
		(width 0.3)
		(layer "B.Cu")
		(net 1)
	)
	(segment
		(start 147.25 87.05)
		(end 148.08 87.88)
		(width 0.3)
		(layer "B.Cu")
		(net 1)
	)
	(segment
		(start 93.765 93.25)
		(end 93.25 93.25)
		(width 0.15)
		(layer "B.Cu")
		(net 1)
	)
	(segment
		(start 97.1 71.215)
		(end 97.1 70.6)
		(width 0.5)
		(layer "B.Cu")
		(net 1)
	)
	(segment
		(start 142.84 84.925)
		(end 142.5 85.265)
		(width 0.3)
		(layer "B.Cu")
		(net 1)
	)
	(segment
		(start 120.445 62.4)
		(end 120.52 62.4)
		(width 0.5)
		(layer "B.Cu")
		(net 1)
	)
	(segment
		(start 161.68 96.5)
		(end 161.699825 96.480175)
		(width 0.3)
		(layer "B.Cu")
		(net 1)
	)
	(segment
		(start 102.77 79.4)
		(end 102.93 79.24)
		(width 0.5)
		(layer "B.Cu")
		(net 1)
	)
	(segment
		(start 146.725 87.05)
		(end 146.725 86.225)
		(width 0.3)
		(layer "B.Cu")
		(net 1)
	)
	(segment
		(start 159.58 67.3)
		(end 159.58 66.6)
		(width 0.3)
		(layer "B.Cu")
		(net 1)
	)
	(segment
		(start 102.285 79.4)
		(end 102.77 79.4)
		(width 0.5)
		(layer "B.Cu")
		(net 1)
	)
	(segment
		(start 93.65 75.305)
		(end 93.65 74.72)
		(width 0.5)
		(layer "B.Cu")
		(net 1)
	)
	(segment
		(start 127.13 90.3)
		(end 126.38 90.3)
		(width 0.3)
		(layer "B.Cu")
		(net 1)
	)
	(segment
		(start 155.89 74.04)
		(end 155.59 74.34)
		(width 0.3)
		(layer "B.Cu")
		(net 1)
	)
	(segment
		(start 124.023726 86.976274)
		(end 123.9 87.1)
		(width 0.3)
		(layer "B.Cu")
		(net 1)
	)
	(segment
		(start 158.64 66.05)
		(end 158.59 66)
		(width 0.3)
		(layer "B.Cu")
		(net 1)
	)
	(segment
		(start 132.4135 96.7435)
		(end 132.28 96.61)
		(width 0.3)
		(layer "B.Cu")
		(net 1)
	)
	(segment
		(start 160.3925 97.8)
		(end 159.58 97.8)
		(width 0.3)
		(layer "B.Cu")
		(net 1)
	)
	(segment
		(start 143.95 84.925)
		(end 145.425 84.925)
		(width 0.3)
		(layer "B.Cu")
		(net 1)
	)
	(segment
		(start 155.33 59.765)
		(end 155.33 59.25)
		(width 0.3)
		(layer "B.Cu")
		(net 1)
	)
	(segment
		(start 134.31 92.2)
		(end 134.31 91.36)
		(width 0.3)
		(layer "B.Cu")
		(net 1)
	)
	(segment
		(start 93.65 74.72)
		(end 93.565 74.635)
		(width 0.5)
		(layer "B.Cu")
		(net 1)
	)
	(segment
		(start 89.14 78.07)
		(end 88.815 77.745)
		(width 0.5)
		(layer "B.Cu")
		(net 1)
	)
	(segment
		(start 149.5 82.823036)
		(end 148.661964 81.985)
		(width 0.3)
		(layer "B.Cu")
		(net 1)
	)
	(segment
		(start 154.6675 102.7)
		(end 152.38 102.7)
		(width 0.3)
		(layer "B.Cu")
		(net 1)
	)
	(segment
		(start 136.55 62.56)
		(end 136.56 62.55)
		(width 0.3)
		(layer "B.Cu")
		(net 1)
	)
	(segment
		(start 136.58 59.692155)
		(end 137.021648 60.133803)
		(width 0.3)
		(layer "B.Cu")
		(net 1)
	)
	(segment
		(start 146.725 86.225)
		(end 145.75 85.25)
		(width 0.3)
		(layer "B.Cu")
		(net 1)
	)
	(segment
		(start 147.5 81.985)
		(end 148.661964 81.985)
		(width 0.3)
		(layer "B.Cu")
		(net 1)
	)
	(segment
		(start 118.13 57.16)
		(end 118.1 57.19)
		(width 0.15)
		(layer "B.Cu")
		(net 1)
	)
	(segment
		(start 102.9 76.4)
		(end 102.285 76.4)
		(width 0.5)
		(layer "B.Cu")
		(net 1)
	)
	(segment
		(start 96.285 74.585)
		(end 96.6 74.9)
		(width 0.5)
		(layer "B.Cu")
		(net 1)
	)
	(segment
		(start 91.410659 78.07)
		(end 89.14 78.07)
		(width 0.5)
		(layer "B.Cu")
		(net 1)
	)
	(segment
		(start 127.0995 93.932048)
		(end 127.343726 94.176274)
		(width 0.3)
		(layer "B.Cu")
		(net 1)
	)
	(segment
		(start 162.56 72.8)
		(end 162.57 72.79)
		(width 0.3)
		(layer "B.Cu")
		(net 1)
	)
	(segment
		(start 136.56 62.55)
		(end 136.92 62.55)
		(width 0.3)
		(layer "B.Cu")
		(net 1)
	)
	(segment
		(start 126.38 90.3)
		(end 126.3 90.22)
		(width 0.3)
		(layer "B.Cu")
		(net 1)
	)
	(segment
		(start 131.1 95.1)
		(end 131.1 95.42)
		(width 0.3)
		(layer "B.Cu")
		(net 1)
	)
	(segment
		(start 156.23 65.835)
		(end 156.23 66.65)
		(width 0.3)
		(layer "B.Cu")
		(net 1)
	)
	(segment
		(start 149.5 83.265)
		(end 149.5 82.823036)
		(width 0.3)
		(layer "B.Cu")
		(net 1)
	)
	(segment
		(start 133.7 95.5)
		(end 133.7 95.231146)
		(width 0.5)
		(layer "B.Cu")
		(net 1)
	)
	(segment
		(start 129.5 87.1)
		(end 129.5 87.82)
		(width 0.3)
		(layer "B.Cu")
		(net 1)
	)
	(segment
		(start 91.62 72.475)
		(end 92.355 72.475)
		(width 0.5)
		(layer "B.Cu")
		(net 1)
	)
	(segment
		(start 143.95 84.925)
		(end 142.84 84.925)
		(width 0.3)
		(layer "B.Cu")
		(net 1)
	)
	(segment
		(start 95.58 74.585)
		(end 96.285 74.585)
		(width 0.5)
		(layer "B.Cu")
		(net 1)
	)
	(segment
		(start 130.76 58.3)
		(end 130.51 58.05)
		(width 0.2)
		(layer "B.Cu")
		(net 1)
	)
	(segment
		(start 91.335 71.625)
		(end 91.34 71.62)
		(width 0.5)
		(layer "B.Cu")
		(net 1)
	)
	(segment
		(start 148.08 87.88)
		(end 148.08 88.25)
		(width 0.3)
		(layer "B.Cu")
		(net 1)
	)
	(segment
		(start 130.3 94.3)
		(end 130.126274 94.473726)
		(width 0.3)
		(layer "B.Cu")
		(net 1)
	)
	(segment
		(start 91.54438 77.936279)
		(end 91.410659 78.07)
		(width 0.5)
		(layer "B.Cu")
		(net 1)
	)
	(segment
		(start 97.105 80.395)
		(end 96.6 80.9)
		(width 0.5)
		(layer "B.Cu")
		(net 1)
	)
	(segment
		(start 152.23 102.55)
		(end 152.23 101.15)
		(width 0.3)
		(layer "B.Cu")
		(net 1)
	)
	(segment
		(start 88.815 77.745)
		(end 88.815 77.4)
		(width 0.5)
		(layer "B.Cu")
		(net 1)
	)
	(segment
		(start 133.435 57.14)
		(end 133.435 58.915)
		(width 0.3)
		(layer "B.Cu")
		(net 1)
	)
	(segment
		(start 161.04 72.35)
		(end 161.49 72.8)
		(width 0.5)
		(layer "B.Cu")
		(net 1)
	)
	(segment
		(start 130.23 62.85)
		(end 129.04 62.85)
		(width 0.3)
		(layer "B.Cu")
		(net 1)
	)
	(segment
		(start 88.2 74.4)
		(end 88.815 74.4)
		(width 0.5)
		(layer "B.Cu")
		(net 1)
	)
	(segment
		(start 120.445 62.4)
		(end 120.445 62.86)
		(width 0.3)
		(layer "B.Cu")
		(net 1)
	)
	(segment
		(start 131.1 95.42)
		(end 131.02 95.5)
		(width 0.3)
		(layer "B.Cu")
		(net 1)
	)
	(segment
		(start 143.97887 81.985)
		(end 143.371113 81.377243)
		(width 0.3)
		(layer "B.Cu")
		(net 1)
	)
	(segment
		(start 129.04 62.85)
		(end 128.56 62.37)
		(width 0.3)
		(layer "B.Cu")
		(net 1)
	)
	(segment
		(start 118.13 56.15)
		(end 118.13 57.16)
		(width 0.15)
		(layer "B.Cu")
		(net 1)
	)
	(segment
		(start 120.445 62.86)
		(end 119.885 63.42)
		(width 0.3)
		(layer "B.Cu")
		(net 1)
	)
	(segment
		(start 136.635 56.5)
		(end 138.49 56.5)
		(width 0.3)
		(layer "B.Cu")
		(net 1)
	)
	(segment
		(start 160.074 80.454)
		(end 160.69 81.07)
		(width 0.2)
		(layer "F.Cu")
		(net 2)
	)
	(segment
		(start 91.1 74.4)
		(end 90.5 74.4)
		(width 0.5)
		(layer "F.Cu")
		(net 2)
	)
	(segment
		(start 160.69 81.07)
		(end 162.36 81.07)
		(width 0.3)
		(layer "F.Cu")
		(net 2)
	)
	(segment
		(start 90.8 68.715)
		(end 90.105 68.715)
		(width 0.3)
		(layer "F.Cu")
		(net 2)
	)
	(segment
		(start 81.935 106.665)
		(end 81.92 106.65)
		(width 0.3)
		(layer "F.Cu")
		(net 2)
	)
	(segment
		(start 157.59 80.454)
		(end 160.074 80.454)
		(width 0.2)
		(layer "F.Cu")
		(net 2)
	)
	(segment
		(start 109.6 97.5)
		(end 109.4 97.7)
		(width 0.15)
		(layer "F.Cu")
		(net 2)
	)
	(segment
		(start 157.59 81.2)
		(end 157.59 80.454)
		(width 0.3)
		(layer "F.Cu")
		(net 2)
	)
	(segment
		(start 101.2 103.8005)
		(end 101.2 103.185)
		(width 0.15)
		(layer "F.Cu")
		(net 2)
	)
	(segment
		(start 158.53 89.35)
		(end 158.53 90.15)
		(width 0.15)
		(layer "F.Cu")
		(net 2)
	)
	(segment
		(start 132.83 110.15)
		(end 132.56251 109.88251)
		(width 0.15)
		(layer "F.Cu")
		(net 2)
	)
	(segment
		(start 109.39 97.81)
		(end 109.39 98.19)
		(width 0.15)
		(layer "F.Cu")
		(net 2)
	)
	(segment
		(start 156 116.25)
		(end 155.141 116.25)
		(width 0.5)
		(layer "F.Cu")
		(net 2)
	)
	(segment
		(start 87.025 104.875)
		(end 87.025 104.375)
		(width 0.3)
		(layer "F.Cu")
		(net 2)
	)
	(segment
		(start 100.1 79.4)
		(end 100.6 79.4)
		(width 0.5)
		(layer "F.Cu")
		(net 2)
	)
	(segment
		(start 128.7 91.88)
		(end 128.7 91.9)
		(width 0.3)
		(layer "F.Cu")
		(net 2)
	)
	(segment
		(start 109.75 98.55)
		(end 109.1 99.2)
		(width 0.15)
		(layer "F.Cu")
		(net 2)
	)
	(segment
		(start 93.085 103.955)
		(end 93.08 103.95)
		(width 0.3)
		(layer "F.Cu")
		(net 2)
	)
	(segment
		(start 111.83 104.04)
		(end 111.19 103.4)
		(width 0.15)
		(layer "F.Cu")
		(net 2)
	)
	(segment
		(start 83.715 106.15)
		(end 83.715 107.15)
		(width 0.3)
		(layer "F.Cu")
		(net 2)
	)
	(segment
		(start 150.18 107.7)
		(end 148.69 107.7)
		(width 0.3)
		(layer "F.Cu")
		(net 2)
	)
	(segment
		(start 121.545 109.65)
		(end 121.545 110.65)
		(width 0.3)
		(layer "F.Cu")
		(net 2)
	)
	(segment
		(start 158.48 90.2)
		(end 156.58 90.2)
		(width 0.3)
		(layer "F.Cu")
		(net 2)
	)
	(segment
		(start 89.97 110.035)
		(end 89.97 110.87)
		(width 0.3)
		(layer "F.Cu")
		(net 2)
	)
	(segment
		(start 109.4 97.8)
		(end 109.39 97.81)
		(width 0.15)
		(layer "F.Cu")
		(net 2)
	)
	(segment
		(start 158.53 90.25)
		(end 158.48 90.2)
		(width 0.15)
		(layer "F.Cu")
		(net 2)
	)
	(segment
		(start 115.8 87.51)
		(end 116.13 87.18)
		(width 0.15)
		(layer "F.Cu")
		(net 2)
	)
	(segment
		(start 108.43 99.2)
		(end 107.9 98.67)
		(width 0.15)
		(layer "F.Cu")
		(net 2)
	)
	(segment
		(start 106.975 98.7)
		(end 107.19 98.7)
		(width 0.3)
		(layer "F.Cu")
		(net 2)
	)
	(segment
		(start 156.80751 79.8)
		(end 156.82 79.7)
		(width 0.3)
		(layer "F.Cu")
		(net 2)
	)
	(segment
		(start 97.5925 121.9875)
		(end 97.58 122)
		(width 0.3)
		(layer "F.Cu")
		(net 2)
	)
	(segment
		(start 129.5 90.3)
		(end 129.9 89.9)
		(width 0.3)
		(layer "F.Cu")
		(net 2)
	)
	(segment
		(start 159.925 88.785)
		(end 159.925 89.825)
		(width 0.5)
		(layer "F.Cu")
		(net 2)
	)
	(segment
		(start 100.1 76.4)
		(end 100.6 76.4)
		(width 0.5)
		(layer "F.Cu")
		(net 2)
	)
	(segment
		(start 98.46 121.9875)
		(end 97.5925 121.9875)
		(width 0.3)
		(layer "F.Cu")
		(net 2)
	)
	(segment
		(start 111.175 103.415)
		(end 111.19 103.4)
		(width 0.3)
		(layer "F.Cu")
		(net 2)
	)
	(segment
		(start 156.82 79.7)
		(end 157.59 79.7)
		(width 0.3)
		(layer "F.Cu")
		(net 2)
	)
	(segment
		(start 153.53 104.35)
		(end 150.18 107.7)
		(width 0.3)
		(layer "F.Cu")
		(net 2)
	)
	(segment
		(start 101.0005 104)
		(end 101.2 103.8005)
		(width 0.15)
		(layer "F.Cu")
		(net 2)
	)
	(segment
		(start 115.8 88.315)
		(end 115.8 87.51)
		(width 0.15)
		(layer "F.Cu")
		(net 2)
	)
	(segment
		(start 111.115 105.55)
		(end 111.43 105.55)
		(width 0.15)
		(layer "F.Cu")
		(net 2)
	)
	(segment
		(start 158.53 90.15)
		(end 158.48 90.2)
		(width 0.15)
		(layer "F.Cu")
		(net 2)
	)
	(segment
		(start 90.105 68.715)
		(end 90.09 68.7)
		(width 0.3)
		(layer "F.Cu")
		(net 2)
	)
	(segment
		(start 119.69 110.65)
		(end 121.545 110.65)
		(width 0.3)
		(layer "F.Cu")
		(net 2)
	)
	(segment
		(start 97.1 82.4)
		(end 97.1 82.9)
		(width 0.5)
		(layer "F.Cu")
		(net 2)
	)
	(segment
		(start 82.7 106.665)
		(end 81.935 106.665)
		(width 0.3)
		(layer "F.Cu")
		(net 2)
	)
	(segment
		(start 111.83 105.15)
		(end 111.83 104.04)
		(width 0.15)
		(layer "F.Cu")
		(net 2)
	)
	(segment
		(start 122.3 90.28)
		(end 122.7 89.9)
		(width 0.3)
		(layer "F.Cu")
		(net 2)
	)
	(segment
		(start 91.1 80.4)
		(end 90.5 80.4)
		(width 0.5)
		(layer "F.Cu")
		(net 2)
	)
	(segment
		(start 109.39 98.19)
		(end 109.75 98.55)
		(width 0.15)
		(layer "F.Cu")
		(net 2)
	)
	(segment
		(start 82.7 106.665)
		(end 83.715 106.665)
		(width 0.3)
		(layer "F.Cu")
		(net 2)
	)
	(segment
		(start 108.615 103.425)
		(end 110.28 103.425)
		(width 0.3)
		(layer "F.Cu")
		(net 2)
	)
	(segment
		(start 87.025 104.375)
		(end 87 104.35)
		(width 0.3)
		(layer "F.Cu")
		(net 2)
	)
	(segment
		(start 123.1 92.7)
		(end 122.7 92.3)
		(width 0.3)
		(layer "F.Cu")
		(net 2)
	)
	(segment
		(start 133.345 110.15)
		(end 132.83 110.15)
		(width 0.15)
		(layer "F.Cu")
		(net 2)
	)
	(segment
		(start 111.43 105.55)
		(end 111.83 105.15)
		(width 0.15)
		(layer "F.Cu")
		(net 2)
	)
	(segment
		(start 157.59 80.454)
		(end 157.59 79.7)
		(width 0.3)
		(layer "F.Cu")
		(net 2)
	)
	(segment
		(start 107.56 98.33)
		(end 107.56 97.07)
		(width 0.3)
		(layer "F.Cu")
		(net 2)
	)
	(segment
		(start 113.885 85.6)
		(end 113.885 87.625)
		(width 0.15)
		(layer "F.Cu")
		(net 2)
	)
	(segment
		(start 121.545 110.65)
		(end 121.545 112.15)
		(width 0.3)
		(layer "F.Cu")
		(net 2)
	)
	(segment
		(start 118.29 112.05)
		(end 119.69 110.65)
		(width 0.3)
		(layer "F.Cu")
		(net 2)
	)
	(segment
		(start 158.53 90.95)
		(end 158.53 90.25)
		(width 0.15)
		(layer "F.Cu")
		(net 2)
	)
	(segment
		(start 110 97)
		(end 110 97.3)
		(width 0.15)
		(layer "F.Cu")
		(net 2)
	)
	(segment
		(start 91.1 77.4)
		(end 90.5 77.4)
		(width 0.5)
		(layer "F.Cu")
		(net 2)
	)
	(segment
		(start 115.8 88.315)
		(end 114.575 88.315)
		(width 0.15)
		(layer "F.Cu")
		(net 2)
	)
	(segment
		(start 109.4 97.7)
		(end 109.4 97.8)
		(width 0.15)
		(layer "F.Cu")
		(net 2)
	)
	(segment
		(start 156.58 90.2)
		(end 153.53 93.25)
		(width 0.3)
		(layer "F.Cu")
		(net 2)
	)
	(segment
		(start 159.925 89.825)
		(end 160.25 90.15)
		(width 0.5)
		(layer "F.Cu")
		(net 2)
	)
	(segment
		(start 83.715 106.665)
		(end 83.715 107.15)
		(width 0.3)
		(layer "F.Cu")
		(net 2)
	)
	(segment
		(start 153.53 93.25)
		(end 153.53 104.35)
		(width 0.3)
		(layer "F.Cu")
		(net 2)
	)
	(segment
		(start 107.9 98.67)
		(end 107.56 98.33)
		(width 0.3)
		(layer "F.Cu")
		(net 2)
	)
	(segment
		(start 93.085 104.85)
		(end 93.085 103.955)
		(width 0.3)
		(layer "F.Cu")
		(net 2)
	)
	(segment
		(start 89.97 110.87)
		(end 90 110.9)
		(width 0.3)
		(layer "F.Cu")
		(net 2)
	)
	(segment
		(start 110.29 103.415)
		(end 111.175 103.415)
		(width 0.3)
		(layer "F.Cu")
		(net 2)
	)
	(segment
		(start 160.2 90.2)
		(end 158.48 90.2)
		(width 0.3)
		(layer "F.Cu")
		(net 2)
	)
	(segment
		(start 107.19 98.7)
		(end 107.56 98.33)
		(width 0.3)
		(layer "F.Cu")
		(net 2)
	)
	(segment
		(start 122.515 113.12)
		(end 121.545 112.15)
		(width 0.15)
		(layer "F.Cu")
		(net 2)
	)
	(segment
		(start 122.7 93.9)
		(end 122.3 93.5)
		(width 0.3)
		(layer "F.Cu")
		(net 2)
	)
	(segment
		(start 109.1 99.2)
		(end 108.43 99.2)
		(width 0.15)
		(layer "F.Cu")
		(net 2)
	)
	(segment
		(start 97.1 73.4)
		(end 97.1 72.9)
		(width 0.5)
		(layer "F.Cu")
		(net 2)
	)
	(segment
		(start 109.8 97.5)
		(end 109.6 97.5)
		(width 0.15)
		(layer "F.Cu")
		(net 2)
	)
	(segment
		(start 110 97.3)
		(end 109.8 97.5)
		(width 0.15)
		(layer "F.Cu")
		(net 2)
	)
	(segment
		(start 128.7 91.9)
		(end 129.1 92.3)
		(width 0.3)
		(layer "F.Cu")
		(net 2)
	)
	(via
		(at 163.49 56.9)
		(size 0.45)
		(drill 0.2)
		(layers "F.Cu" "B.Cu")
		(remove_unused_layers yes)
		(keep_end_layers yes)
		(free yes)
		(zone_layer_connections "In6.Cu")
		(net 2)
	)
	(via
		(at 87 104.35)
		(size 0.45)
		(drill 0.2)
		(layers "F.Cu" "B.Cu")
		(remove_unused_layers yes)
		(keep_end_layers yes)
		(zone_layer_connections "In6.Cu")
		(net 2)
	)
	(via
		(at 93.08 103.95)
		(size 0.45)
		(drill 0.2)
		(layers "F.Cu" "B.Cu")
		(remove_unused_layers yes)
		(keep_end_layers yes)
		(zone_layer_connections "In6.Cu")
		(net 2)
	)
	(via
		(at 102.1 91.4)
		(size 0.45)
		(drill 0.2)
		(layers "F.Cu" "B.Cu")
		(net 2)
	)
	(via
		(at 148.69 110.7)
		(size 0.45)
		(drill 0.2)
		(layers "F.Cu" "B.Cu")
		(remove_unused_layers yes)
		(keep_end_layers yes)
		(free yes)
		(zone_layer_connections "In6.Cu")
		(net 2)
	)
	(via
		(at 81.92 106.65)
		(size 0.45)
		(drill 0.2)
		(layers "F.Cu" "B.Cu")
		(remove_unused_layers yes)
		(keep_end_layers yes)
		(zone_layer_connections "In6.Cu")
		(net 2)
	)
	(via
		(at 90 110.9)
		(size 0.45)
		(drill 0.2)
		(layers "F.Cu" "B.Cu")
		(remove_unused_layers yes)
		(keep_end_layers yes)
		(zone_layer_connections "In6.Cu")
		(net 2)
	)
	(via
		(at 118.29 112.05)
		(size 0.45)
		(drill 0.2)
		(layers "F.Cu" "B.Cu")
		(remove_unused_layers yes)
		(keep_end_layers yes)
		(zone_layer_connections "In6.Cu")
		(net 2)
	)
	(via
		(at 100.6 79.4)
		(size 0.45)
		(drill 0.2)
		(layers "F.Cu" "B.Cu")
		(remove_unused_layers yes)
		(keep_end_layers yes)
		(zone_layer_connections "In6.Cu")
		(net 2)
	)
	(via
		(at 163.49 56.1)
		(size 0.45)
		(drill 0.2)
		(layers "F.Cu" "B.Cu")
		(remove_unused_layers yes)
		(keep_end_layers yes)
		(free yes)
		(zone_layer_connections "In6.Cu")
		(net 2)
	)
	(via
		(at 90.5 74.4)
		(size 0.45)
		(drill 0.2)
		(layers "F.Cu" "B.Cu")
		(remove_unused_layers yes)
		(keep_end_layers yes)
		(zone_layer_connections "In6.Cu")
		(net 2)
	)
	(via
		(at 129.5 90.3)
		(size 0.45)
		(drill 0.2)
		(layers "F.Cu" "B.Cu")
		(remove_unused_layers yes)
		(keep_end_layers yes)
		(zone_layer_connections "In6.Cu")
		(net 2)
	)
	(via
		(at 136.651732 61.418268)
		(size 0.45)
		(drill 0.2)
		(layers "F.Cu" "B.Cu")
		(remove_unused_layers yes)
		(keep_end_layers yes)
		(zone_layer_connections "In6.Cu")
		(net 2)
	)
	(via
		(at 90.09 68.7)
		(size 0.45)
		(drill 0.2)
		(layers "F.Cu" "B.Cu")
		(remove_unused_layers yes)
		(keep_end_layers yes)
		(zone_layer_connections "In6.Cu")
		(net 2)
	)
	(via
		(at 147.69 108.7)
		(size 0.45)
		(drill 0.2)
		(layers "F.Cu" "B.Cu")
		(remove_unused_layers yes)
		(keep_end_layers yes)
		(free yes)
		(zone_layer_connections "In6.Cu")
		(net 2)
	)
	(via
		(at 165.09 56.9)
		(size 0.45)
		(drill 0.2)
		(layers "F.Cu" "B.Cu")
		(remove_unused_layers yes)
		(keep_end_layers yes)
		(free yes)
		(zone_layer_connections "In6.Cu")
		(net 2)
	)
	(via
		(at 164.29 57.3)
		(size 0.45)
		(drill 0.2)
		(layers "F.Cu" "B.Cu")
		(remove_unused_layers yes)
		(keep_end_layers yes)
		(free yes)
		(zone_layer_connections "In6.Cu")
		(net 2)
	)
	(via
		(at 97.1 82.9)
		(size 0.45)
		(drill 0.2)
		(layers "F.Cu" "B.Cu")
		(remove_unused_layers yes)
		(keep_end_layers yes)
		(zone_layer_connections "In6.Cu")
		(net 2)
	)
	(via
		(at 100.6 76.4)
		(size 0.45)
		(drill 0.2)
		(layers "F.Cu" "B.Cu")
		(remove_unused_layers yes)
		(keep_end_layers yes)
		(zone_layer_connections "In6.Cu")
		(net 2)
	)
	(via
		(at 97.58 122)
		(size 0.45)
		(drill 0.2)
		(layers "F.Cu" "B.Cu")
		(remove_unused_layers yes)
		(keep_end_layers yes)
		(zone_layer_connections "In6.Cu")
		(net 2)
	)
	(via
		(at 128.7 91.88)
		(size 0.45)
		(drill 0.2)
		(layers "F.Cu" "B.Cu")
		(remove_unused_layers yes)
		(keep_end_layers yes)
		(zone_layer_connections "In6.Cu")
		(net 2)
	)
	(via
		(at 115.41 86.34)
		(size 0.45)
		(drill 0.2)
		(layers "F.Cu" "B.Cu")
		(remove_unused_layers yes)
		(keep_end_layers yes)
		(free yes)
		(zone_layer_connections "In6.Cu")
		(net 2)
	)
	(via
		(at 101.0005 104)
		(size 0.45)
		(drill 0.2)
		(layers "F.Cu" "B.Cu")
		(remove_unused_layers yes)
		(keep_end_layers yes)
		(zone_layer_connections "In6.Cu")
		(net 2)
	)
	(via
		(at 97.1 72.9)
		(size 0.45)
		(drill 0.2)
		(layers "F.Cu" "B.Cu")
		(remove_unused_layers yes)
		(keep_end_layers yes)
		(zone_layer_connections "In6.Cu")
		(net 2)
	)
	(via
		(at 148.69 111.6)
		(size 0.45)
		(drill 0.2)
		(layers "F.Cu" "B.Cu")
		(remove_unused_layers yes)
		(keep_end_layers yes)
		(free yes)
		(zone_layer_connections "In6.Cu")
		(net 2)
	)
	(via
		(at 123.1 92.7)
		(size 0.45)
		(drill 0.2)
		(layers "F.Cu" "B.Cu")
		(remove_unused_layers yes)
		(keep_end_layers yes)
		(zone_layer_connections "In6.Cu")
		(net 2)
	)
	(via
		(at 148.69 107.7)
		(size 0.45)
		(drill 0.2)
		(layers "F.Cu" "B.Cu")
		(remove_unused_layers yes)
		(keep_end_layers yes)
		(free yes)
		(zone_layer_connections "In6.Cu")
		(net 2)
	)
	(via
		(at 165.09 56.1)
		(size 0.45)
		(drill 0.2)
		(layers "F.Cu" "B.Cu")
		(remove_unused_layers yes)
		(keep_end_layers yes)
		(free yes)
		(zone_layer_connections "In6.Cu")
		(net 2)
	)
	(via
		(at 107.9 98.67)
		(size 0.45)
		(drill 0.2)
		(layers "F.Cu" "B.Cu")
		(remove_unused_layers yes)
		(keep_end_layers yes)
		(zone_layer_connections "In6.Cu")
		(net 2)
	)
	(via
		(at 156 116.25)
		(size 0.45)
		(drill 0.2)
		(layers "F.Cu" "B.Cu")
		(remove_unused_layers yes)
		(keep_end_layers yes)
		(zone_layer_connections "In6.Cu")
		(net 2)
	)
	(via
		(at 132.56251 109.88251)
		(size 0.45)
		(drill 0.2)
		(layers "F.Cu" "B.Cu")
		(remove_unused_layers yes)
		(keep_end_layers yes)
		(zone_layer_connections "In6.Cu")
		(net 2)
	)
	(via
		(at 164.29 56.5)
		(size 0.45)
		(drill 0.2)
		(layers "F.Cu" "B.Cu")
		(remove_unused_layers yes)
		(keep_end_layers yes)
		(free yes)
		(zone_layer_connections "In6.Cu")
		(net 2)
	)
	(via
		(at 147.69 109.7)
		(size 0.45)
		(drill 0.2)
		(layers "F.Cu" "B.Cu")
		(remove_unused_layers yes)
		(keep_end_layers yes)
		(free yes)
		(zone_layer_connections "In6.Cu")
		(net 2)
	)
	(via
		(at 122.3 90.28)
		(size 0.45)
		(drill 0.2)
		(layers "F.Cu" "B.Cu")
		(remove_unused_layers yes)
		(keep_end_layers yes)
		(zone_layer_connections "In6.Cu")
		(net 2)
	)
	(via
		(at 130.3 87.9)
		(size 0.45)
		(drill 0.2)
		(layers "F.Cu" "B.Cu")
		(free yes)
		(net 2)
	)
	(via
		(at 111.19 103.4)
		(size 0.45)
		(drill 0.2)
		(layers "F.Cu" "B.Cu")
		(remove_unused_layers yes)
		(keep_end_layers yes)
		(zone_layer_connections "In6.Cu")
		(net 2)
	)
	(via
		(at 90.5 77.4)
		(size 0.45)
		(drill 0.2)
		(layers "F.Cu" "B.Cu")
		(remove_unused_layers yes)
		(keep_end_layers yes)
		(zone_layer_connections "In6.Cu")
		(net 2)
	)
	(via
		(at 116.13 87.18)
		(size 0.45)
		(drill 0.2)
		(layers "F.Cu" "B.Cu")
		(remove_unused_layers yes)
		(keep_end_layers yes)
		(free yes)
		(zone_layer_connections "In6.Cu")
		(net 2)
	)
	(via
		(at 147.69 111.6)
		(size 0.45)
		(drill 0.2)
		(layers "F.Cu" "B.Cu")
		(remove_unused_layers yes)
		(keep_end_layers yes)
		(free yes)
		(zone_layer_connections "In6.Cu")
		(net 2)
	)
	(via
		(at 122.3 93.5)
		(size 0.45)
		(drill 0.2)
		(layers "F.Cu" "B.Cu")
		(remove_unused_layers yes)
		(keep_end_layers yes)
		(zone_layer_connections "In6.Cu")
		(net 2)
	)
	(via
		(at 162.275 55.9)
		(size 0.45)
		(drill 0.2)
		(layers "F.Cu" "B.Cu")
		(remove_unused_layers yes)
		(keep_end_layers yes)
		(free yes)
		(zone_layer_connections "In6.Cu")
		(net 2)
	)
	(via
		(at 147.69 110.7)
		(size 0.45)
		(drill 0.2)
		(layers "F.Cu" "B.Cu")
		(remove_unused_layers yes)
		(keep_end_layers yes)
		(free yes)
		(zone_layer_connections "In6.Cu")
		(net 2)
	)
	(via
		(at 147.69 107.7)
		(size 0.45)
		(drill 0.2)
		(layers "F.Cu" "B.Cu")
		(remove_unused_layers yes)
		(keep_end_layers yes)
		(free yes)
		(zone_layer_connections "In6.Cu")
		(net 2)
	)
	(via
		(at 148.69 109.7)
		(size 0.45)
		(drill 0.2)
		(layers "F.Cu" "B.Cu")
		(remove_unused_layers yes)
		(keep_end_layers yes)
		(free yes)
		(zone_layer_connections "In6.Cu")
		(net 2)
	)
	(via
		(at 162.69 56.5)
		(size 0.45)
		(drill 0.2)
		(layers "F.Cu" "B.Cu")
		(remove_unused_layers yes)
		(keep_end_layers yes)
		(free yes)
		(zone_layer_connections "In6.Cu")
		(net 2)
	)
	(via
		(at 115.76 86.73)
		(size 0.45)
		(drill 0.2)
		(layers "F.Cu" "B.Cu")
		(remove_unused_layers yes)
		(keep_end_layers yes)
		(free yes)
		(zone_layer_connections "In6.Cu")
		(net 2)
	)
	(via
		(at 138.34 57.1505)
		(size 0.45)
		(drill 0.2)
		(layers "F.Cu" "B.Cu")
		(remove_unused_layers yes)
		(keep_end_layers yes)
		(zone_layer_connections "In6.Cu")
		(net 2)
	)
	(via
		(at 148.69 108.7)
		(size 0.45)
		(drill 0.2)
		(layers "F.Cu" "B.Cu")
		(remove_unused_layers yes)
		(keep_end_layers yes)
		(free yes)
		(zone_layer_connections "In6.Cu")
		(net 2)
	)
	(via
		(at 123.1 87.9)
		(size 0.45)
		(drill 0.2)
		(layers "F.Cu" "B.Cu")
		(remove_unused_layers yes)
		(keep_end_layers yes)
		(zone_layer_connections "In6.Cu")
		(net 2)
	)
	(via
		(at 160.83 106.75)
		(size 0.45)
		(drill 0.2)
		(layers "F.Cu" "B.Cu")
		(remove_unused_layers yes)
		(keep_end_layers yes)
		(zone_layer_connections "In6.Cu")
		(net 2)
	)
	(via
		(at 162.69 57.3)
		(size 0.45)
		(drill 0.2)
		(layers "F.Cu" "B.Cu")
		(remove_unused_layers yes)
		(keep_end_layers yes)
		(free yes)
		(zone_layer_connections "In6.Cu")
		(net 2)
	)
	(via
		(at 156.80751 79.8)
		(size 0.45)
		(drill 0.2)
		(layers "F.Cu" "B.Cu")
		(remove_unused_layers yes)
		(keep_end_layers yes)
		(zone_layer_connections "In6.Cu")
		(net 2)
	)
	(via
		(at 90.5 80.4)
		(size 0.45)
		(drill 0.2)
		(layers "F.Cu" "B.Cu")
		(remove_unused_layers yes)
		(keep_end_layers yes)
		(zone_layer_connections "In6.Cu")
		(net 2)
	)
	(via
		(at 94.25 96)
		(size 0.45)
		(drill 0.2)
		(layers "F.Cu" "B.Cu")
		(remove_unused_layers yes)
		(keep_end_layers yes)
		(zone_layer_connections "In6.Cu")
		(net 2)
	)
	(segment
		(start 136.65 61.416536)
		(end 136.651732 61.418268)
		(width 0.3)
		(layer "B.Cu")
		(net 2)
	)
	(segment
		(start 137.915 57.5755)
		(end 138.34 57.1505)
		(width 0.15)
		(layer "B.Cu")
		(net 2)
	)
	(segment
		(start 94.25 92.72)
		(end 93.78 92.25)
		(width 0.15)
		(layer "B.Cu")
		(net 2)
	)
	(segment
		(start 104.89 91.315)
		(end 105.89 91.315)
		(width 0.5)
		(layer "B.Cu")
		(net 2)
	)
	(segment
		(start 161.63 104.15)
		(end 161.63 105.95)
		(width 0.3)
		(layer "B.Cu")
		(net 2)
	)
	(segment
		(start 97.1 83.515)
		(end 97.1 82.9)
		(width 0.5)
		(layer "B.Cu")
		(net 2)
	)
	(segment
		(start 101.315 76.4)
		(end 100.6 76.4)
		(width 0.5)
		(layer "B.Cu")
		(net 2)
	)
	(segment
		(start 94 94.25)
		(end 94.25 94)
		(width 0.15)
		(layer "B.Cu")
		(net 2)
	)
	(segment
		(start 89.785 77.4)
		(end 90.5 77.4)
		(width 0.5)
		(layer "B.Cu")
		(net 2)
	)
	(segment
		(start 94.25 94)
		(end 94.25 96)
		(width 0.15)
		(layer "B.Cu")
		(net 2)
	)
	(segment
		(start 161.48 104)
		(end 161.63 104.15)
		(width 0.3)
		(layer "B.Cu")
		(net 2)
	)
	(segment
		(start 89.785 74.4)
		(end 90.5 74.4)
		(width 0.5)
		(layer "B.Cu")
		(net 2)
	)
	(segment
		(start 136.55 61.16)
		(end 136.65 61.26)
		(width 0.3)
		(layer "B.Cu")
		(net 2)
	)
	(segment
		(start 94.25 94)
		(end 94.25 92.72)
		(width 0.15)
		(layer "B.Cu")
		(net 2)
	)
	(segment
		(start 103.89 91.315)
		(end 104.89 91.315)
		(width 0.5)
		(layer "B.Cu")
		(net 2)
	)
	(segment
		(start 101.315 79.4)
		(end 100.6 79.4)
		(width 0.5)
		(layer "B.Cu")
		(net 2)
	)
	(segment
		(start 102.185 91.315)
		(end 102.1 91.4)
		(width 0.5)
		(layer "B.Cu")
		(net 2)
	)
	(segment
		(start 160.3925 104)
		(end 161.48 104)
		(width 0.3)
		(layer "B.Cu")
		(net 2)
	)
	(segment
		(start 97.1 72.185)
		(end 97.1 72.9)
		(width 0.5)
		(layer "B.Cu")
		(net 2)
	)
	(segment
		(start 134.275 61.15)
		(end 134.085 61.34)
		(width 0.3)
		(layer "B.Cu")
		(net 2)
	)
	(segment
		(start 89.785 80.4)
		(end 90.5 80.4)
		(width 0.5)
		(layer "B.Cu")
		(net 2)
	)
	(segment
		(start 136.55 61.16)
		(end 136.54 61.15)
		(width 0.3)
		(layer "B.Cu")
		(net 2)
	)
	(segment
		(start 93.765 94.25)
		(end 94 94.25)
		(width 0.15)
		(layer "B.Cu")
		(net 2)
	)
	(segment
		(start 161.63 105.95)
		(end 160.83 106.75)
		(width 0.3)
		(layer "B.Cu")
		(net 2)
	)
	(segment
		(start 103.89 91.315)
		(end 102.185 91.315)
		(width 0.5)
		(layer "B.Cu")
		(net 2)
	)
	(segment
		(start 136.65 61.26)
		(end 136.65 61.416536)
		(width 0.3)
		(layer "B.Cu")
		(net 2)
	)
	(segment
		(start 136.54 61.15)
		(end 134.275 61.15)
		(width 0.3)
		(layer "B.Cu")
		(net 2)
	)
	(segment
		(start 129.905 88.295)
		(end 129.905 88.853615)
		(width 0.15)
		(layer "In3.Cu")
		(net 2)
	)
	(segment
		(start 129.25 89.1)
		(end 129.1 89.25)
		(width 0.15)
		(layer "In3.Cu")
		(net 2)
	)
	(segment
		(start 129.658615 89.1)
		(end 129.25 89.1)
		(width 0.15)
		(layer "In3.Cu")
		(net 2)
	)
	(segment
		(start 129.1 89.25)
		(end 129.1 89.9)
		(width 0.15)
		(layer "In3.Cu")
		(net 2)
	)
	(segment
		(start 129.905 88.853615)
		(end 129.658615 89.1)
		(width 0.15)
		(layer "In3.Cu")
		(net 2)
	)
	(segment
		(start 129.1 89.9)
		(end 129.5 90.3)
		(width 0.15)
		(layer "In3.Cu")
		(net 2)
	)
	(segment
		(start 130.3 87.9)
		(end 129.905 88.295)
		(width 0.15)
		(layer "In3.Cu")
		(net 2)
	)
	(segment
		(start 96.1 78.4)
		(end 96.6 78.9)
		(width 0.3)
		(layer "F.Cu")
		(net 3)
	)
	(segment
		(start 128.7195 86.3)
		(end 129.1 86.6805)
		(width 0.1)
		(layer "F.Cu")
		(net 3)
	)
	(segment
		(start 129.1 86.7)
		(end 128.7 86.3)
		(width 0.3)
		(layer "F.Cu")
		(net 3)
	)
	(segment
		(start 137.0392 115.1)
		(end 136.2392 114.3)
		(width 0.5)
		(layer "F.Cu")
		(net 3)
	)
	(segment
		(start 96.1 77.4)
		(end 96.1 76.4)
		(width 0.3)
		(layer "F.Cu")
		(net 3)
	)
	(segment
		(start 137.09 115.1)
		(end 137.0392 115.1)
		(width 0.5)
		(layer "F.Cu")
		(net 3)
	)
	(segment
		(start 93.08 75.4)
		(end 92.69 75.79)
		(width 0.5)
		(layer "F.Cu")
		(net 3)
	)
	(segment
		(start 96.1 76.4)
		(end 96.6 75.9)
		(width 0.5)
		(layer "F.Cu")
		(net 3)
	)
	(segment
		(start 92.1 74.4)
		(end 92.14 74.4)
		(width 0.5)
		(layer "F.Cu")
		(net 3)
	)
	(segment
		(start 93.09 75.4)
		(end 93.08 75.4)
		(width 0.5)
		(layer "F.Cu")
		(net 3)
	)
	(segment
		(start 128.7 86.3)
		(end 128.7195 86.3)
		(width 0.1)
		(layer "F.Cu")
		(net 3)
	)
	(segment
		(start 94.1 75.4)
		(end 94.6 75.9)
		(width 0.5)
		(layer "F.Cu")
		(net 3)
	)
	(segment
		(start 96.1 78.4)
		(end 96.1 77.4)
		(width 0.3)
		(layer "F.Cu")
		(net 3)
	)
	(segment
		(start 96.1 79.4)
		(end 96.6 78.9)
		(width 0.5)
		(layer "F.Cu")
		(net 3)
	)
	(segment
		(start 92.14 74.4)
		(end 92.63 74.89)
		(width 0.5)
		(layer "F.Cu")
		(net 3)
	)
	(segment
		(start 93 68.83)
		(end 93 68.207738)
		(width 0.2)
		(layer "F.Cu")
		(net 3)
	)
	(segment
		(start 93 68.207738)
		(end 92.720934 67.928672)
		(width 0.2)
		(layer "F.Cu")
		(net 3)
	)
	(via
		(at 94.6 75.9)
		(size 0.45)
		(drill 0.2)
		(layers "F.Cu" "B.Cu")
		(remove_unused_layers yes)
		(keep_end_layers yes)
		(zone_layer_connections)
		(net 3)
	)
	(via
		(at 114.19 103.6)
		(size 0.45)
		(drill 0.2)
		(layers "F.Cu" "B.Cu")
		(remove_unused_layers yes)
		(keep_end_layers yes)
		(free yes)
		(zone_layer_connections "In6.Cu")
		(net 3)
	)
	(via
		(at 104.34 74.9)
		(size 0.45)
		(drill 0.2)
		(layers "F.Cu" "B.Cu")
		(remove_unused_layers yes)
		(keep_end_layers yes)
		(free yes)
		(zone_layer_connections "In6.Cu")
		(net 3)
	)
	(via
		(at 115.14 102.55)
		(size 0.45)
		(drill 0.2)
		(layers "F.Cu" "B.Cu")
		(remove_unused_layers yes)
		(keep_end_layers yes)
		(free yes)
		(zone_layer_connections "In6.Cu")
		(net 3)
	)
	(via
		(at 110.69 99.5)
		(size 0.45)
		(drill 0.2)
		(layers "F.Cu" "B.Cu")
		(remove_unused_layers yes)
		(keep_end_layers yes)
		(free yes)
		(zone_layer_connections "In6.Cu")
		(net 3)
	)
	(via
		(at 113.14 103.6)
		(size 0.45)
		(drill 0.2)
		(layers "F.Cu" "B.Cu")
		(remove_unused_layers yes)
		(keep_end_layers yes)
		(free yes)
		(zone_layer_connections "In6.Cu")
		(net 3)
	)
	(via
		(at 156.03 95.15)
		(size 0.45)
		(drill 0.2)
		(layers "F.Cu" "B.Cu")
		(remove_unused_layers yes)
		(keep_end_layers yes)
		(zone_layer_connections)
		(net 3)
	)
	(via
		(at 102.16 73.77)
		(size 0.45)
		(drill 0.2)
		(layers "F.Cu" "B.Cu")
		(remove_unused_layers yes)
		(keep_end_layers yes)
		(free yes)
		(zone_layer_connections "In6.Cu")
		(net 3)
	)
	(via
		(at 115.14 101.6)
		(size 0.45)
		(drill 0.2)
		(layers "F.Cu" "B.Cu")
		(remove_unused_layers yes)
		(keep_end_layers yes)
		(free yes)
		(zone_layer_connections "In6.Cu")
		(net 3)
	)
	(via
		(at 104.39 76.95)
		(size 0.45)
		(drill 0.2)
		(layers "F.Cu" "B.Cu")
		(remove_unused_layers yes)
		(keep_end_layers yes)
		(free yes)
		(zone_layer_connections "In6.Cu")
		(net 3)
	)
	(via
		(at 102.63 78.09)
		(size 0.45)
		(drill 0.2)
		(layers "F.Cu" "B.Cu")
		(remove_unused_layers yes)
		(keep_end_layers yes)
		(free yes)
		(zone_layer_connections "In6.Cu")
		(net 3)
	)
	(via
		(at 92.63 74.89)
		(size 0.45)
		(drill 0.2)
		(layers "F.Cu" "B.Cu")
		(remove_unused_layers yes)
		(keep_end_layers yes)
		(zone_layer_connections)
		(net 3)
	)
	(via
		(at 137.69 115.5)
		(size 0.45)
		(drill 0.2)
		(layers "F.Cu" "B.Cu")
		(remove_unused_layers yes)
		(keep_end_layers yes)
		(free yes)
		(zone_layer_connections "In6.Cu")
		(net 3)
	)
	(via
		(at 112.09 98.75)
		(size 0.45)
		(drill 0.2)
		(layers "F.Cu" "B.Cu")
		(remove_unused_layers yes)
		(keep_end_layers yes)
		(free yes)
		(zone_layer_connections "In6.Cu")
		(net 3)
	)
	(via
		(at 137.09 116.7)
		(size 0.45)
		(drill 0.2)
		(layers "F.Cu" "B.Cu")
		(remove_unused_layers yes)
		(keep_end_layers yes)
		(free yes)
		(zone_layer_connections "In6.Cu")
		(net 3)
	)
	(via
		(at 114.19 102.55)
		(size 0.45)
		(drill 0.2)
		(layers "F.Cu" "B.Cu")
		(remove_unused_layers yes)
		(keep_end_layers yes)
		(free yes)
		(zone_layer_connections "In6.Cu")
		(net 3)
	)
	(via
		(at 137.69 116.3)
		(size 0.45)
		(drill 0.2)
		(layers "F.Cu" "B.Cu")
		(remove_unused_layers yes)
		(keep_end_layers yes)
		(free yes)
		(zone_layer_connections "In6.Cu")
		(net 3)
	)
	(via
		(at 103.11 73.86)
		(size 0.45)
		(drill 0.2)
		(layers "F.Cu" "B.Cu")
		(remove_unused_layers yes)
		(keep_end_layers yes)
		(free yes)
		(zone_layer_connections "In6.Cu")
		(net 3)
	)
	(via
		(at 137.09 115.1)
		(size 0.45)
		(drill 0.2)
		(layers "F.Cu" "B.Cu")
		(remove_unused_layers yes)
		(keep_end_layers yes)
		(free yes)
		(zone_layer_connections "In6.Cu")
		(net 3)
	)
	(via
		(at 136.1 86)
		(size 0.45)
		(drill 0.2)
		(layers "F.Cu" "B.Cu")
		(net 3)
	)
	(via
		(at 92.69 75.79)
		(size 0.45)
		(drill 0.2)
		(layers "F.Cu" "B.Cu")
		(remove_unused_layers yes)
		(keep_end_layers yes)
		(zone_layer_connections)
		(net 3)
	)
	(via
		(at 96.6 75.9)
		(size 0.45)
		(drill 0.2)
		(layers "F.Cu" "B.Cu")
		(remove_unused_layers yes)
		(keep_end_layers yes)
		(zone_layer_connections)
		(net 3)
	)
	(via
		(at 111.64 99.5)
		(size 0.45)
		(drill 0.2)
		(layers "F.Cu" "B.Cu")
		(remove_unused_layers yes)
		(keep_end_layers yes)
		(free yes)
		(zone_layer_connections "In6.Cu")
		(net 3)
	)
	(via
		(at 92.720934 67.928672)
		(size 0.45)
		(drill 0.2)
		(layers "F.Cu" "B.Cu")
		(remove_unused_layers yes)
		(keep_end_layers yes)
		(zone_layer_connections)
		(net 3)
	)
	(via
		(at 111.14 98.75)
		(size 0.45)
		(drill 0.2)
		(layers "F.Cu" "B.Cu")
		(remove_unused_layers yes)
		(keep_end_layers yes)
		(free yes)
		(zone_layer_connections "In6.Cu")
		(net 3)
	)
	(via
		(at 96.6 78.9)
		(size 0.45)
		(drill 0.2)
		(layers "F.Cu" "B.Cu")
		(remove_unused_layers yes)
		(keep_end_layers yes)
		(zone_layer_connections)
		(net 3)
	)
	(via
		(at 104.39 76.15)
		(size 0.45)
		(drill 0.2)
		(layers "F.Cu" "B.Cu")
		(remove_unused_layers yes)
		(keep_end_layers yes)
		(free yes)
		(zone_layer_connections "In6.Cu")
		(net 3)
	)
	(via
		(at 103.59 75.85)
		(size 0.45)
		(drill 0.2)
		(layers "F.Cu" "B.Cu")
		(remove_unused_layers yes)
		(keep_end_layers yes)
		(free yes)
		(zone_layer_connections "In6.Cu")
		(net 3)
	)
	(via
		(at 137.09 115.9)
		(size 0.45)
		(drill 0.2)
		(layers "F.Cu" "B.Cu")
		(remove_unused_layers yes)
		(keep_end_layers yes)
		(free yes)
		(zone_layer_connections "In6.Cu")
		(net 3)
	)
	(via
		(at 128.7 86.3)
		(size 0.45)
		(drill 0.2)
		(layers "F.Cu" "B.Cu")
		(remove_unused_layers yes)
		(keep_end_layers yes)
		(zone_layer_connections)
		(net 3)
	)
	(via
		(at 103.19 77.5)
		(size 0.45)
		(drill 0.2)
		(layers "F.Cu" "B.Cu")
		(remove_unused_layers yes)
		(keep_end_layers yes)
		(free yes)
		(zone_layer_connections "In6.Cu")
		(net 3)
	)
	(via
		(at 109.79 98)
		(size 0.45)
		(drill 0.2)
		(layers "F.Cu" "B.Cu")
		(remove_unused_layers yes)
		(keep_end_layers yes)
		(free yes)
		(zone_layer_connections "In6.Cu")
		(net 3)
	)
	(via
		(at 115.14 103.6)
		(size 0.45)
		(drill 0.2)
		(layers "F.Cu" "B.Cu")
		(remove_unused_layers yes)
		(keep_end_layers yes)
		(free yes)
		(zone_layer_connections "In6.Cu")
		(net 3)
	)
	(segment
		(start 128.7 86.25)
		(end 128.196274 85.746274)
		(width 0.3)
		(layer "B.Cu")
		(net 3)
	)
	(segment
		(start 93.65 76.275)
		(end 93.175 76.275)
		(width 0.5)
		(layer "B.Cu")
		(net 3)
	)
	(segment
		(start 92.35 67.4)
		(end 91.45 67.4)
		(width 0.3)
		(layer "B.Cu")
		(net 3)
	)
	(segment
		(start 93.175 76.275)
		(end 92.69 75.79)
		(width 0.5)
		(layer "B.Cu")
		(net 3)
	)
	(segment
		(start 92.615 74.875)
		(end 91.58 74.875)
		(width 0.5)
		(layer "B.Cu")
		(net 3)
	)
	(segment
		(start 92.595 73.295)
		(end 92.595 74.06)
		(width 0.3)
		(layer "B.Cu")
		(net 3)
	)
	(segment
		(start 93.65 76.24)
		(end 93.65 76.275)
		(width 0.5)
		(layer "B.Cu")
		(net 3)
	)
	(segment
		(start 92.720934 67.928672)
		(end 92.720934 67.770934)
		(width 0.3)
		(layer "B.Cu")
		(net 3)
	)
	(segment
		(start 156.03 95.15)
		(end 154.7175 95.15)
		(width 0.15)
		(layer "B.Cu")
		(net 3)
	)
	(segment
		(start 91.13 67.72)
		(end 91.13 69.32)
		(width 0.3)
		(layer "B.Cu")
		(net 3)
	)
	(segment
		(start 129.042548 84.9)
		(end 130.5 84.9)
		(width 0.3)
		(layer "B.Cu")
		(net 3)
	)
	(segment
		(start 92.720934 67.770934)
		(end 92.35 67.4)
		(width 0.3)
		(layer "B.Cu")
		(net 3)
	)
	(segment
		(start 94.6 75.9)
		(end 94.56 75.94)
		(width 0.5)
		(layer "B.Cu")
		(net 3)
	)
	(segment
		(start 94.655 75.845)
		(end 94.6 75.9)
		(width 0.1)
		(layer "B.Cu")
		(net 3)
	)
	(segment
		(start 93.13 72.76)
		(end 92.595 73.295)
		(width 0.3)
		(layer "B.Cu")
		(net 3)
	)
	(segment
		(start 92.63 74.89)
		(end 92.615 74.875)
		(width 0.5)
		(layer "B.Cu")
		(net 3)
	)
	(segment
		(start 94.6 75.9)
		(end 94.945 75.555)
		(width 0.5)
		(layer "B.Cu")
		(net 3)
	)
	(segment
		(start 129.042548 84.9)
		(end 128.196274 85.746274)
		(width 0.3)
		(layer "B.Cu")
		(net 3)
	)
	(segment
		(start 131.35 85.75)
		(end 132.55 85.75)
		(width 0.3)
		(layer "B.Cu")
		(net 3)
	)
	(segment
		(start 97.125 79.425)
		(end 96.6 78.9)
		(width 0.5)
		(layer "B.Cu")
		(net 3)
	)
	(segment
		(start 94.56 75.94)
		(end 93.95 75.94)
		(width 0.5)
		(layer "B.Cu")
		(net 3)
	)
	(segment
		(start 91.13 69.32)
		(end 93.13 71.32)
		(width 0.3)
		(layer "B.Cu")
		(net 3)
	)
	(segment
		(start 92.595 74.855)
		(end 92.595 74.06)
		(width 0.5)
		(layer "B.Cu")
		(net 3)
	)
	(segment
		(start 96.255 75.555)
		(end 96.6 75.9)
		(width 0.5)
		(layer "B.Cu")
		(net 3)
	)
	(segment
		(start 94.945 75.555)
		(end 96.255 75.555)
		(width 0.5)
		(layer "B.Cu")
		(net 3)
	)
	(segment
		(start 97.355 75.145)
		(end 96.6 75.9)
		(width 0.5)
		(layer "B.Cu")
		(net 3)
	)
	(segment
		(start 92.69 74.95)
		(end 92.63 74.89)
		(width 0.5)
		(layer "B.Cu")
		(net 3)
	)
	(segment
		(start 92.69 75.79)
		(end 92.69 74.95)
		(width 0.5)
		(layer "B.Cu")
		(net 3)
	)
	(segment
		(start 93.13 71.32)
		(end 93.13 72.76)
		(width 0.3)
		(layer "B.Cu")
		(net 3)
	)
	(segment
		(start 91.45 67.4)
		(end 91.13 67.72)
		(width 0.3)
		(layer "B.Cu")
		(net 3)
	)
	(segment
		(start 93.95 75.94)
		(end 93.65 76.24)
		(width 0.5)
		(layer "B.Cu")
		(net 3)
	)
	(segment
		(start 92.63 74.89)
		(end 92.595 74.855)
		(width 0.5)
		(layer "B.Cu")
		(net 3)
	)
	(segment
		(start 128.7 86.3)
		(end 128.7 86.25)
		(width 0.3)
		(layer "B.Cu")
		(net 3)
	)
	(segment
		(start 132.55 85.75)
		(end 132.8 86)
		(width 0.3)
		(layer "B.Cu")
		(net 3)
	)
	(segment
		(start 132.8 86)
		(end 136.1 86)
		(width 0.3)
		(layer "B.Cu")
		(net 3)
	)
	(segment
		(start 130.5 84.9)
		(end 131.35 85.75)
		(width 0.3)
		(layer "B.Cu")
		(net 3)
	)
	(segment
		(start 140.83 117.75)
		(end 139.38 116.3)
		(width 0.15)
		(layer "In2.Cu")
		(net 3)
	)
	(segment
		(start 156.03 111.55)
		(end 149.83 117.75)
		(width 0.15)
		(layer "In2.Cu")
		(net 3)
	)
	(segment
		(start 149.83 117.75)
		(end 140.83 117.75)
		(width 0.15)
		(layer "In2.Cu")
		(net 3)
	)
	(segment
		(start 156.03 95.15)
		(end 156.03 111.55)
		(width 0.15)
		(layer "In2.Cu")
		(net 3)
	)
	(segment
		(start 139.38 116.3)
		(end 137.69 116.3)
		(width 0.15)
		(layer "In2.Cu")
		(net 3)
	)
	(segment
		(start 97.14 78.36)
		(end 97.14 76.44)
		(width 0.3)
		(layer "In6.Cu")
		(net 3)
	)
	(segment
		(start 96.6 78.9)
		(end 97.14 78.36)
		(width 0.3)
		(layer "In6.Cu")
		(net 3)
	)
	(segment
		(start 97.14 76.44)
		(end 96.6 75.9)
		(width 0.3)
		(layer "In6.Cu")
		(net 3)
	)
	(segment
		(start 127.1 91.1)
		(end 127.5 90.7)
		(width 0.3)
		(layer "F.Cu")
		(net 4)
	)
	(segment
		(start 125.1 89.9)
		(end 124.7 90.3)
		(width 0.3)
		(layer "F.Cu")
		(net 4)
	)
	(segment
		(start 127.9 93.5)
		(end 127.5 93.9)
		(width 0.3)
		(layer "F.Cu")
		(net 4)
	)
	(segment
		(start 125.5 89.5)
		(end 125.1 89.9)
		(width 0.3)
		(layer "F.Cu")
		(net 4)
	)
	(segment
		(start 125.9 93.9)
		(end 125.5 94.3)
		(width 0.3)
		(layer "F.Cu")
		(net 4)
	)
	(segment
		(start 150.2892 71.7)
		(end 150.2892 72.7008)
		(width 0.15)
		(layer "F.Cu")
		(net 4)
	)
	(segment
		(start 125.5 89.5)
		(end 125.9 89.1)
		(width 0.3)
		(layer "F.Cu")
		(net 4)
	)
	(via
		(at 133.08 100.76)
		(size 0.45)
		(drill 0.2)
		(layers "F.Cu" "B.Cu")
		(remove_unused_layers yes)
		(keep_end_layers yes)
		(free yes)
		(zone_layer_connections "In6.Cu")
		(net 4)
	)
	(via
		(at 132.28 100.76)
		(size 0.45)
		(drill 0.2)
		(layers "F.Cu" "B.Cu")
		(remove_unused_layers yes)
		(keep_end_layers yes)
		(free yes)
		(zone_layer_connections "In6.Cu")
		(net 4)
	)
	(via
		(at 131.89 101.3)
		(size 0.45)
		(drill 0.2)
		(layers "F.Cu" "B.Cu")
		(remove_unused_layers yes)
		(keep_end_layers yes)
		(free yes)
		(zone_layer_connections "In6.Cu")
		(net 4)
	)
	(via
		(at 132.69 102.5)
		(size 0.45)
		(drill 0.2)
		(layers "F.Cu" "B.Cu")
		(remove_unused_layers yes)
		(keep_end_layers yes)
		(free yes)
		(zone_layer_connections "In6.Cu")
		(net 4)
	)
	(via
		(at 131.48 100.76)
		(size 0.45)
		(drill 0.2)
		(layers "F.Cu" "B.Cu")
		(remove_unused_layers yes)
		(keep_end_layers yes)
		(free yes)
		(zone_layer_connections "In6.Cu")
		(net 4)
	)
	(via
		(at 131.49 101.9)
		(size 0.45)
		(drill 0.2)
		(layers "F.Cu" "B.Cu")
		(remove_unused_layers yes)
		(keep_end_layers yes)
		(free yes)
		(zone_layer_connections "In6.Cu")
		(net 4)
	)
	(via
		(at 124.7 90.3)
		(size 0.45)
		(drill 0.2)
		(layers "F.Cu" "B.Cu")
		(remove_unused_layers yes)
		(keep_end_layers yes)
		(zone_layer_connections "In6.Cu")
		(net 4)
	)
	(via
		(at 152.43 108.35)
		(size 0.45)
		(drill 0.2)
		(layers "F.Cu" "B.Cu")
		(remove_unused_layers yes)
		(keep_end_layers yes)
		(zone_layer_connections)
		(net 4)
	)
	(via
		(at 124.58 98.0005)
		(size 0.45)
		(drill 0.2)
		(layers "F.Cu" "B.Cu")
		(remove_unused_layers yes)
		(keep_end_layers yes)
		(zone_layer_connections "In6.Cu")
		(net 4)
	)
	(via
		(at 127.9 93.5)
		(size 0.45)
		(drill 0.2)
		(layers "F.Cu" "B.Cu")
		(remove_unused_layers yes)
		(keep_end_layers yes)
		(zone_layer_connections "In6.Cu")
		(net 4)
	)
	(via
		(at 127.1 91.1)
		(size 0.45)
		(drill 0.2)
		(layers "F.Cu" "B.Cu")
		(remove_unused_layers yes)
		(keep_end_layers yes)
		(zone_layer_connections "In6.Cu")
		(net 4)
	)
	(via
		(at 132.29 101.9)
		(size 0.45)
		(drill 0.2)
		(layers "F.Cu" "B.Cu")
		(remove_unused_layers yes)
		(keep_end_layers yes)
		(free yes)
		(zone_layer_connections "In6.Cu")
		(net 4)
	)
	(via
		(at 125.5 94.3)
		(size 0.45)
		(drill 0.2)
		(layers "F.Cu" "B.Cu")
		(remove_unused_layers yes)
		(keep_end_layers yes)
		(zone_layer_connections "In6.Cu")
		(net 4)
	)
	(via
		(at 125.5 89.5)
		(size 0.45)
		(drill 0.2)
		(layers "F.Cu" "B.Cu")
		(remove_unused_layers yes)
		(keep_end_layers yes)
		(zone_layer_connections "In6.Cu")
		(net 4)
	)
	(via
		(at 133.09 101.9)
		(size 0.45)
		(drill 0.2)
		(layers "F.Cu" "B.Cu")
		(remove_unused_layers yes)
		(keep_end_layers yes)
		(free yes)
		(zone_layer_connections "In6.Cu")
		(net 4)
	)
	(via
		(at 131.89 102.5)
		(size 0.45)
		(drill 0.2)
		(layers "F.Cu" "B.Cu")
		(remove_unused_layers yes)
		(keep_end_layers yes)
		(free yes)
		(zone_layer_connections "In6.Cu")
		(net 4)
	)
	(via
		(at 132.69 101.3)
		(size 0.45)
		(drill 0.2)
		(layers "F.Cu" "B.Cu")
		(remove_unused_layers yes)
		(keep_end_layers yes)
		(free yes)
		(zone_layer_connections "In6.Cu")
		(net 4)
	)
	(segment
		(start 155.63 108.35)
		(end 152.43 108.35)
		(width 0.15)
		(layer "B.Cu")
		(net 4)
	)
	(segment
		(start 155.63 108.35)
		(end 158.68 105.3)
		(width 0.15)
		(layer "B.Cu")
		(net 4)
	)
	(segment
		(start 160.3925 105.3)
		(end 158.68 105.3)
		(width 0.15)
		(layer "B.Cu")
		(net 4)
	)
	(segment
		(start 124.53 98.5)
		(end 124.53 98.0505)
		(width 0.5)
		(layer "B.Cu")
		(net 4)
	)
	(segment
		(start 152.43 106.75)
		(end 149.23 103.55)
		(width 0.15)
		(layer "In2.Cu")
		(net 4)
	)
	(segment
		(start 143.63 103.55)
		(end 141.98 101.9)
		(width 0.15)
		(layer "In2.Cu")
		(net 4)
	)
	(segment
		(start 149.23 103.55)
		(end 143.63 103.55)
		(width 0.15)
		(layer "In2.Cu")
		(net 4)
	)
	(segment
		(start 152.43 108.35)
		(end 152.43 106.75)
		(width 0.15)
		(layer "In2.Cu")
		(net 4)
	)
	(segment
		(start 141.98 101.9)
		(end 133.09 101.9)
		(width 0.15)
		(layer "In2.Cu")
		(net 4)
	)
	(segment
		(start 136.23 57.65)
		(end 138.08 55.8)
		(width 0.3)
		(layer "F.Cu")
		(net 5)
	)
	(segment
		(start 133.47 83.93)
		(end 132.3 85.1)
		(width 0.3)
		(layer "F.Cu")
		(net 5)
	)
	(segment
		(start 123.83 59.4)
		(end 125.58 57.65)
		(width 0.3)
		(layer "F.Cu")
		(net 5)
	)
	(segment
		(start 131.08 57.65)
		(end 131.48 57.65)
		(width 0.3)
		(layer "F.Cu")
		(net 5)
	)
	(segment
		(start 123.83 61.55)
		(end 123.28 62.1)
		(width 0.3)
		(layer "F.Cu")
		(net 5)
	)
	(segment
		(start 121.86 62.54)
		(end 121.46 62.14)
		(width 0.3)
		(layer "F.Cu")
		(net 5)
	)
	(segment
		(start 122.3 62.1)
		(end 122.53 62.1)
		(width 0.2)
		(layer "F.Cu")
		(net 5)
	)
	(segment
		(start 122.965 62.115)
		(end 122.53 62.115)
		(width 0.2)
		(layer "F.Cu")
		(net 5)
	)
	(segment
		(start 123.83 59.4)
		(end 123.83 61.55)
		(width 0.3)
		(layer "F.Cu")
		(net 5)
	)
	(segment
		(start 128.38 65.288248)
		(end 128.38 65.15)
		(width 0.3)
		(layer "F.Cu")
		(net 5)
	)
	(segment
		(start 131.03 57.7)
		(end 131.08 57.65)
		(width 0.3)
		(layer "F.Cu")
		(net 5)
	)
	(segment
		(start 128.38 64.835)
		(end 129.48 63.735)
		(width 0.3)
		(layer "F.Cu")
		(net 5)
	)
	(segment
		(start 131.48 57.65)
		(end 125.58 57.65)
		(width 0.3)
		(layer "F.Cu")
		(net 5)
	)
	(segment
		(start 129.995 63.735)
		(end 131.03 62.7)
		(width 0.3)
		(layer "F.Cu")
		(net 5)
	)
	(segment
		(start 122.98 62.1)
		(end 122.965 62.115)
		(width 0.2)
		(layer "F.Cu")
		(net 5)
	)
	(segment
		(start 129.33 66.4)
		(end 129.03 66.1)
		(width 0.3)
		(layer "F.Cu")
		(net 5)
	)
	(segment
		(start 129.03 66.1)
		(end 129.03 65.938248)
		(width 0.3)
		(layer "F.Cu")
		(net 5)
	)
	(segment
		(start 129.48 63.735)
		(end 129.995 63.735)
		(width 0.3)
		(layer "F.Cu")
		(net 5)
	)
	(segment
		(start 131.03 62.7)
		(end 131.03 57.7)
		(width 0.3)
		(layer "F.Cu")
		(net 5)
	)
	(segment
		(start 124.31 85.1)
		(end 124.7 85.49)
		(width 0.2)
		(layer "F.Cu")
		(net 5)
	)
	(segment
		(start 129.03 65.938248)
		(end 128.38 65.288248)
		(width 0.3)
		(layer "F.Cu")
		(net 5)
	)
	(segment
		(start 124.7 85.49)
		(end 124.7 85.5)
		(width 0.2)
		(layer "F.Cu")
		(net 5)
	)
	(segment
		(start 121.86 62.54)
		(end 122.3 62.1)
		(width 0.2)
		(layer "F.Cu")
		(net 5)
	)
	(segment
		(start 133.71 83.93)
		(end 133.47 83.93)
		(width 0.3)
		(layer "F.Cu")
		(net 5)
	)
	(segment
		(start 127.79 65.74)
		(end 128.38 65.15)
		(width 0.3)
		(layer "F.Cu")
		(net 5)
	)
	(segment
		(start 123.28 62.1)
		(end 122.98 62.1)
		(width 0.3)
		(layer "F.Cu")
		(net 5)
	)
	(segment
		(start 128.38 65.15)
		(end 128.38 64.835)
		(width 0.3)
		(layer "F.Cu")
		(net 5)
	)
	(segment
		(start 127.46 65.74)
		(end 127.79 65.74)
		(width 0.3)
		(layer "F.Cu")
		(net 5)
	)
	(segment
		(start 131.48 57.65)
		(end 136.23 57.65)
		(width 0.3)
		(layer "F.Cu")
		(net 5)
	)
	(via
		(at 124.7 85.5)
		(size 0.45)
		(drill 0.2)
		(layers "F.Cu" "B.Cu")
		(remove_unused_layers yes)
		(keep_end_layers yes)
		(zone_layer_connections)
		(net 5)
	)
	(via
		(at 121.46 62.14)
		(size 0.45)
		(drill 0.2)
		(layers "F.Cu" "B.Cu")
		(remove_unused_layers yes)
		(keep_end_layers yes)
		(zone_layer_connections)
		(net 5)
	)
	(via
		(at 133.71 83.93)
		(size 0.45)
		(drill 0.2)
		(layers "F.Cu" "B.Cu")
		(remove_unused_layers yes)
		(keep_end_layers yes)
		(zone_layer_connections)
		(net 5)
	)
	(via
		(at 138.08 55.8)
		(size 0.45)
		(drill 0.2)
		(layers "F.Cu" "B.Cu")
		(remove_unused_layers yes)
		(keep_end_layers yes)
		(zone_layer_connections)
		(net 5)
	)
	(via
		(at 131.03 62.75)
		(size 0.45)
		(drill 0.2)
		(layers "F.Cu" "B.Cu")
		(remove_unused_layers yes)
		(keep_end_layers yes)
		(zone_layer_connections)
		(net 5)
	)
	(segment
		(start 135.93 55.8)
		(end 138.08 55.8)
		(width 0.3)
		(layer "B.Cu")
		(net 5)
	)
	(segment
		(start 133.4 85.2)
		(end 131.7 85.2)
		(width 0.3)
		(layer "B.Cu")
		(net 5)
	)
	(segment
		(start 131.33 62.75)
		(end 131.03 62.75)
		(width 0.3)
		(layer "B.Cu")
		(net 5)
	)
	(segment
		(start 135.535 56.195)
		(end 135.93 55.8)
		(width 0.3)
		(layer "B.Cu")
		(net 5)
	)
	(segment
		(start 132.135 61.645)
		(end 132.135 61.945)
		(width 0.3)
		(layer "B.Cu")
		(net 5)
	)
	(segment
		(start 133.71 83.93)
		(end 133.71 84.89)
		(width 0.3)
		(layer "B.Cu")
		(net 5)
	)
	(segment
		(start 131.7 85.2)
		(end 130.7 84.2)
		(width 0.3)
		(layer "B.Cu")
		(net 5)
	)
	(segment
		(start 124.7 84.9)
		(end 124.7 85.5)
		(width 0.3)
		(layer "B.Cu")
		(net 5)
	)
	(segment
		(start 133.526274 84.113726)
		(end 133.71 83.93)
		(width 0.3)
		(layer "B.Cu")
		(net 5)
	)
	(segment
		(start 133.72 83.92)
		(end 133.71 83.93)
		(width 0.3)
		(layer "B.Cu")
		(net 5)
	)
	(segment
		(start 120.805 61.485)
		(end 121.46 62.14)
		(width 0.3)
		(layer "B.Cu")
		(net 5)
	)
	(segment
		(start 130.7 84.2)
		(end 125.4 84.2)
		(width 0.3)
		(layer "B.Cu")
		(net 5)
	)
	(segment
		(start 125.4 84.2)
		(end 124.7 84.9)
		(width 0.3)
		(layer "B.Cu")
		(net 5)
	)
	(segment
		(start 135.535 56.37)
		(end 135.535 56.195)
		(width 0.3)
		(layer "B.Cu")
		(net 5)
	)
	(segment
		(start 132.135 61.945)
		(end 131.33 62.75)
		(width 0.3)
		(layer "B.Cu")
		(net 5)
	)
	(segment
		(start 124.7 85.5)
		(end 123.68 85.5)
		(width 0.3)
		(layer "B.Cu")
		(net 5)
	)
	(segment
		(start 133.71 84.89)
		(end 133.4 85.2)
		(width 0.3)
		(layer "B.Cu")
		(net 5)
	)
	(segment
		(start 121.46 62.14)
		(end 121.46 62.355)
		(width 0.3)
		(layer "B.Cu")
		(net 5)
	)
	(segment
		(start 133.72 83.3)
		(end 133.72 83.92)
		(width 0.3)
		(layer "B.Cu")
		(net 5)
	)
	(segment
		(start 131.03 71.15)
		(end 131.03 62.75)
		(width 0.5)
		(layer "In6.Cu")
		(net 5)
	)
	(segment
		(start 133.93 83.71)
		(end 133.93 72.05)
		(width 0.5)
		(layer "In6.Cu")
		(net 5)
	)
	(segment
		(start 133.43 71.55)
		(end 131.43 71.55)
		(width 0.5)
		(layer "In6.Cu")
		(net 5)
	)
	(segment
		(start 131.43 71.55)
		(end 131.03 71.15)
		(width 0.5)
		(layer "In6.Cu")
		(net 5)
	)
	(segment
		(start 133.93 72.05)
		(end 133.43 71.55)
		(width 0.5)
		(layer "In6.Cu")
		(net 5)
	)
	(via
		(at 129.23 55.875)
		(size 0.45)
		(drill 0.2)
		(layers "F.Cu" "B.Cu")
		(remove_unused_layers yes)
		(keep_end_layers yes)
		(free yes)
		(zone_layer_connections)
		(net 6)
	)
	(via
		(at 161.83 95.55)
		(size 0.45)
		(drill 0.2)
		(layers "F.Cu" "B.Cu")
		(remove_unused_layers yes)
		(keep_end_layers yes)
		(zone_layer_connections)
		(net 6)
	)
	(segment
		(start 122.98 58.21)
		(end 122.98 57.3)
		(width 0.2)
		(layer "B.Cu")
		(net 6)
	)
	(segment
		(start 124.31 59.53)
		(end 123.78 59)
		(width 0.2)
		(layer "B.Cu")
		(net 6)
	)
	(segment
		(start 123.77 59)
		(end 122.98 58.21)
		(width 0.2)
		(layer "B.Cu")
		(net 6)
	)
	(segment
		(start 161.53 95.85)
		(end 161.83 95.55)
		(width 0.3)
		(layer "B.Cu")
		(net 6)
	)
	(segment
		(start 123.78 59)
		(end 123.77 59)
		(width 0.2)
		(layer "B.Cu")
		(net 6)
	)
	(segment
		(start 160.3925 95.85)
		(end 161.53 95.85)
		(width 0.3)
		(layer "B.Cu")
		(net 6)
	)
	(segment
		(start 161.83 91.95)
		(end 161.83 95.55)
		(width 0.15)
		(layer "In2.Cu")
		(net 6)
	)
	(segment
		(start 155.93 60.47)
		(end 155.93 62.23)
		(width 0.15)
		(layer "In2.Cu")
		(net 6)
	)
	(segment
		(start 155.38 59.92)
		(end 155.93 60.47)
		(width 0.15)
		(layer "In2.Cu")
		(net 6)
	)
	(segment
		(start 155.93 62.23)
		(end 157.13 63.43)
		(width 0.15)
		(layer "In2.Cu")
		(net 6)
	)
	(segment
		(start 158.88 63.43)
		(end 159.45 64)
		(width 0.15)
		(layer "In2.Cu")
		(net 6)
	)
	(segment
		(start 146.98 59.92)
		(end 155.38 59.92)
		(width 0.15)
		(layer "In2.Cu")
		(net 6)
	)
	(segment
		(start 157.13 63.43)
		(end 158.88 63.43)
		(width 0.15)
		(layer "In2.Cu")
		(net 6)
	)
	(segment
		(start 130.905 57.55)
		(end 144.58 57.55)
		(width 0.15)
		(layer "In2.Cu")
		(net 6)
	)
	(segment
		(start 157.23 87.35)
		(end 161.83 91.95)
		(width 0.15)
		(layer "In2.Cu")
		(net 6)
	)
	(segment
		(start 144.58 57.55)
		(end 146.965 59.935)
		(width 0.15)
		(layer "In2.Cu")
		(net 6)
	)
	(segment
		(start 159.45 70.57)
		(end 157.23 72.79)
		(width 0.15)
		(layer "In2.Cu")
		(net 6)
	)
	(segment
		(start 146.965 59.935)
		(end 146.98 59.92)
		(width 0.15)
		(layer "In2.Cu")
		(net 6)
	)
	(segment
		(start 129.23 55.875)
		(end 130.905 57.55)
		(width 0.15)
		(layer "In2.Cu")
		(net 6)
	)
	(segment
		(start 157.23 72.79)
		(end 157.23 87.35)
		(width 0.15)
		(layer "In2.Cu")
		(net 6)
	)
	(segment
		(start 159.45 64)
		(end 159.45 70.57)
		(width 0.15)
		(layer "In2.Cu")
		(net 6)
	)
	(segment
		(start 90.999999 75.299999)
		(end 91.1 75.4)
		(width 0.4)
		(layer "F.Cu")
		(net 7)
	)
	(segment
		(start 88.985 75.4)
		(end 89.085001 75.299999)
		(width 0.4)
		(layer "F.Cu")
		(net 7)
	)
	(segment
		(start 89.085001 75.299999)
		(end 90.999999 75.299999)
		(width 0.4)
		(layer "F.Cu")
		(net 7)
	)
	(segment
		(start 89.085001 76.500001)
		(end 90.999999 76.500001)
		(width 0.4)
		(layer "F.Cu")
		(net 8)
	)
	(segment
		(start 90.999999 76.500001)
		(end 91.1 76.4)
		(width 0.4)
		(layer "F.Cu")
		(net 8)
	)
	(segment
		(start 88.985 76.4)
		(end 89.085001 76.500001)
		(width 0.4)
		(layer "F.Cu")
		(net 8)
	)
	(segment
		(start 128.3 87.5)
		(end 128.7 87.9)
		(width 0.3)
		(layer "F.Cu")
		(net 9)
	)
	(segment
		(start 127.1 91.926262)
		(end 126.726262 92.3)
		(width 0.3)
		(layer "F.Cu")
		(net 9)
	)
	(segment
		(start 127.5 91.5)
		(end 127.9 91.9)
		(width 0.3)
		(layer "F.Cu")
		(net 9)
	)
	(segment
		(start 126.54 89.26)
		(end 126.3 89.5)
		(width 0.3)
		(layer "F.Cu")
		(net 9)
	)
	(segment
		(start 124.7 89.49)
		(end 124.71 89.49)
		(width 0.3)
		(layer "F.Cu")
		(net 9)
	)
	(segment
		(start 126.54 89.26)
		(end 126.7 89.1)
		(width 0.1)
		(layer "F.Cu")
		(net 9)
	)
	(segment
		(start 127.1 91.9)
		(end 127.1 91.926262)
		(width 0.3)
		(layer "F.Cu")
		(net 9)
	)
	(segment
		(start 124.71 89.49)
		(end 125.1 89.1)
		(width 0.3)
		(layer "F.Cu")
		(net 9)
	)
	(via
		(at 126.3 89.5)
		(size 0.45)
		(drill 0.2)
		(layers "F.Cu" "B.Cu")
		(remove_unused_layers yes)
		(keep_end_layers yes)
		(zone_layer_connections "In6.Cu")
		(net 9)
	)
	(via
		(at 128.99 81.9)
		(size 0.45)
		(drill 0.2)
		(layers "F.Cu" "B.Cu")
		(remove_unused_layers yes)
		(keep_end_layers yes)
		(zone_layer_connections "In6.Cu")
		(net 9)
	)
	(via
		(at 127.9 91.9)
		(size 0.45)
		(drill 0.2)
		(layers "F.Cu" "B.Cu")
		(remove_unused_layers yes)
		(keep_end_layers yes)
		(zone_layer_connections "In6.Cu")
		(net 9)
	)
	(via
		(at 128.99 81.4)
		(size 0.45)
		(drill 0.2)
		(layers "F.Cu" "B.Cu")
		(remove_unused_layers yes)
		(keep_end_layers yes)
		(zone_layer_connections "In6.Cu")
		(net 9)
	)
	(via
		(at 128.99 80.9)
		(size 0.45)
		(drill 0.2)
		(layers "F.Cu" "B.Cu")
		(remove_unused_layers yes)
		(keep_end_layers yes)
		(zone_layer_connections "In6.Cu")
		(net 9)
	)
	(via
		(at 127.1 91.9)
		(size 0.45)
		(drill 0.2)
		(layers "F.Cu" "B.Cu")
		(remove_unused_layers yes)
		(keep_end_layers yes)
		(zone_layer_connections "In6.Cu")
		(net 9)
	)
	(via
		(at 124.7 89.49)
		(size 0.45)
		(drill 0.2)
		(layers "F.Cu" "B.Cu")
		(remove_unused_layers yes)
		(keep_end_layers yes)
		(zone_layer_connections "In6.Cu")
		(net 9)
	)
	(via
		(at 128.7 87.9)
		(size 0.45)
		(drill 0.2)
		(layers "F.Cu" "B.Cu")
		(remove_unused_layers yes)
		(keep_end_layers yes)
		(zone_layer_connections "In6.Cu")
		(net 9)
	)
	(segment
		(start 124.7 89.02)
		(end 124.7 89.49)
		(width 0.3)
		(layer "B.Cu")
		(net 9)
	)
	(segment
		(start 128.3 91.5)
		(end 127.9 91.9)
		(width 0.15)
		(layer "B.Cu")
		(net 9)
	)
	(segment
		(start 127.77 90.3)
		(end 127.5 90.57)
		(width 0.15)
		(layer "B.Cu")
		(net 9)
	)
	(segment
		(start 128.3 90.65)
		(end 128.3 91.5)
		(width 0.15)
		(layer "B.Cu")
		(net 9)
	)
	(segment
		(start 127.5 90.57)
		(end 127.5 91.5)
		(width 0.15)
		(layer "B.Cu")
		(net 9)
	)
	(segment
		(start 127.95 90.3)
		(end 128.3 90.65)
		(width 0.15)
		(layer "B.Cu")
		(net 9)
	)
	(segment
		(start 127.9 91.9)
		(end 127.1 91.9)
		(width 0.15)
		(layer "B.Cu")
		(net 9)
	)
	(segment
		(start 127.5 91.5)
		(end 127.9 91.9)
		(width 0.15)
		(layer "B.Cu")
		(net 9)
	)
	(segment
		(start 127.77 90.3)
		(end 127.95 90.3)
		(width 0.15)
		(layer "B.Cu")
		(net 9)
	)
	(segment
		(start 127.9 92.7)
		(end 127.5 92.3)
		(width 0.3)
		(layer "F.Cu")
		(net 10)
	)
	(via
		(at 135.53 91.46)
		(size 0.45)
		(drill 0.2)
		(layers "F.Cu" "B.Cu")
		(remove_unused_layers yes)
		(keep_end_layers yes)
		(free yes)
		(zone_layer_connections "In6.Cu")
		(net 10)
	)
	(via
		(at 127.9 92.7)
		(size 0.45)
		(drill 0.2)
		(layers "F.Cu" "B.Cu")
		(remove_unused_layers yes)
		(keep_end_layers yes)
		(zone_layer_connections "In6.Cu")
		(net 10)
	)
	(via
		(at 136.13 91.42)
		(size 0.45)
		(drill 0.2)
		(layers "F.Cu" "B.Cu")
		(remove_unused_layers yes)
		(keep_end_layers yes)
		(free yes)
		(zone_layer_connections "In6.Cu")
		(net 10)
	)
	(segment
		(start 127.5 94.7)
		(end 127.9 95.1)
		(width 0.3)
		(layer "F.Cu")
		(net 11)
	)
	(segment
		(start 129.9 94.7)
		(end 130.3 95.1)
		(width 0.3)
		(layer "F.Cu")
		(net 11)
	)
	(via
		(at 128.15033 99.23033)
		(size 0.45)
		(drill 0.2)
		(layers "F.Cu" "B.Cu")
		(remove_unused_layers yes)
		(keep_end_layers yes)
		(free yes)
		(zone_layer_connections "In6.Cu")
		(net 11)
	)
	(via
		(at 128.2425 99.89)
		(size 0.45)
		(drill 0.2)
		(layers "F.Cu" "B.Cu")
		(remove_unused_layers yes)
		(keep_end_layers yes)
		(free yes)
		(zone_layer_connections "In6.Cu")
		(net 11)
	)
	(via
		(at 127.58 100.03)
		(size 0.45)
		(drill 0.2)
		(layers "F.Cu" "B.Cu")
		(remove_unused_layers yes)
		(keep_end_layers yes)
		(free yes)
		(zone_layer_connections "In6.Cu")
		(net 11)
	)
	(via
		(at 130.3 95.1)
		(size 0.45)
		(drill 0.2)
		(layers "F.Cu" "B.Cu")
		(remove_unused_layers yes)
		(keep_end_layers yes)
		(zone_layer_connections "In6.Cu")
		(net 11)
	)
	(via
		(at 127.9 95.1)
		(size 0.45)
		(drill 0.2)
		(layers "F.Cu" "B.Cu")
		(remove_unused_layers yes)
		(keep_end_layers yes)
		(zone_layer_connections "In6.Cu")
		(net 11)
	)
	(segment
		(start 130.38 95.18)
		(end 130.3 95.1)
		(width 0.2)
		(layer "B.Cu")
		(net 11)
	)
	(segment
		(start 130.38 95.588)
		(end 130.38 95.18)
		(width 0.2)
		(layer "B.Cu")
		(net 11)
	)
	(segment
		(start 126.3 95.1)
		(end 126.7 94.7)
		(width 0.3)
		(layer "F.Cu")
		(net 12)
	)
	(segment
		(start 131.1 92.7)
		(end 130.7 93.1)
		(width 0.3)
		(layer "F.Cu")
		(net 12)
	)
	(via
		(at 131.1 92.7)
		(size 0.45)
		(drill 0.2)
		(layers "F.Cu" "B.Cu")
		(remove_unused_layers yes)
		(keep_end_layers yes)
		(zone_layer_connections "In6.Cu")
		(net 12)
	)
	(via
		(at 135.24 96.31)
		(size 0.45)
		(drill 0.2)
		(layers "F.Cu" "B.Cu")
		(remove_unused_layers yes)
		(keep_end_layers yes)
		(free yes)
		(zone_layer_connections "In6.Cu")
		(net 12)
	)
	(via
		(at 135.66 96.75)
		(size 0.45)
		(drill 0.2)
		(layers "F.Cu" "B.Cu")
		(remove_unused_layers yes)
		(keep_end_layers yes)
		(free yes)
		(zone_layer_connections "In6.Cu")
		(net 12)
	)
	(via
		(at 126.3 95.1)
		(size 0.45)
		(drill 0.2)
		(layers "F.Cu" "B.Cu")
		(remove_unused_layers yes)
		(keep_end_layers yes)
		(zone_layer_connections "In6.Cu")
		(net 12)
	)
	(segment
		(start 135.24 96.31)
		(end 135.24 95.64)
		(width 0.5)
		(layer "B.Cu")
		(net 12)
	)
	(segment
		(start 135.24 95.64)
		(end 135.1 95.5)
		(width 0.5)
		(layer "B.Cu")
		(net 12)
	)
	(segment
		(start 131.5 96.8955)
		(end 131.5045 96.9)
		(width 0.3)
		(layer "F.Cu")
		(net 13)
	)
	(segment
		(start 129.5 95.1)
		(end 129.1 94.7)
		(width 0.3)
		(layer "F.Cu")
		(net 13)
	)
	(segment
		(start 131.5 96.3)
		(end 131.5 96.8955)
		(width 0.3)
		(layer "F.Cu")
		(net 13)
	)
	(via
		(at 129.5 95.1)
		(size 0.45)
		(drill 0.2)
		(layers "F.Cu" "B.Cu")
		(remove_unused_layers yes)
		(keep_end_layers yes)
		(zone_layer_connections)
		(net 13)
	)
	(via
		(at 131.5045 96.9)
		(size 0.45)
		(drill 0.2)
		(layers "F.Cu" "B.Cu")
		(remove_unused_layers yes)
		(keep_end_layers yes)
		(zone_layer_connections)
		(net 13)
	)
	(segment
		(start 152.495 80.715)
		(end 152.495 75.585)
		(width 0.3)
		(layer "F.Cu")
		(net 14)
	)
	(segment
		(start 157.48 85.7)
		(end 155.28 83.5)
		(width 0.3)
		(layer "F.Cu")
		(net 14)
	)
	(segment
		(start 153.5 88.68)
		(end 153.518517 88.661483)
		(width 0.3)
		(layer "F.Cu")
		(net 14)
	)
	(segment
		(start 161.38 85.7)
		(end 157.48 85.7)
		(width 0.3)
		(layer "F.Cu")
		(net 14)
	)
	(segment
		(start 153.518517 88.661483)
		(end 153.518517 85.261483)
		(width 0.3)
		(layer "F.Cu")
		(net 14)
	)
	(segment
		(start 153.518517 85.261483)
		(end 155.28 83.5)
		(width 0.3)
		(layer "F.Cu")
		(net 14)
	)
	(segment
		(start 155.28 83.5)
		(end 152.495 80.715)
		(width 0.3)
		(layer "F.Cu")
		(net 14)
	)
	(segment
		(start 152.495 75.585)
		(end 152.53 75.55)
		(width 0.3)
		(layer "F.Cu")
		(net 14)
	)
	(segment
		(start 161.43 84.15)
		(end 161.43 85.65)
		(width 0.3)
		(layer "F.Cu")
		(net 14)
	)
	(via
		(at 153.5 88.68)
		(size 0.45)
		(drill 0.2)
		(layers "F.Cu" "B.Cu")
		(remove_unused_layers yes)
		(keep_end_layers yes)
		(zone_layer_connections)
		(net 14)
	)
	(segment
		(start 154.6675 97.8)
		(end 153.065 97.8)
		(width 0.3)
		(layer "B.Cu")
		(net 14)
	)
	(segment
		(start 157.63 97.15)
		(end 160.3925 97.15)
		(width 0.3)
		(layer "B.Cu")
		(net 14)
	)
	(segment
		(start 161.63 100.75)
		(end 161.63 97.55)
		(width 0.3)
		(layer "B.Cu")
		(net 14)
	)
	(segment
		(start 162.315 101.435)
		(end 161.63 100.75)
		(width 0.3)
		(layer "B.Cu")
		(net 14)
	)
	(segment
		(start 160.3925 102.7)
		(end 161.28 102.7)
		(width 0.3)
		(layer "B.Cu")
		(net 14)
	)
	(segment
		(start 151.83 91.15)
		(end 151.83 97.15)
		(width 0.3)
		(layer "B.Cu")
		(net 14)
	)
	(segment
		(start 161.63 97.55)
		(end 161.23 97.15)
		(width 0.3)
		(layer "B.Cu")
		(net 14)
	)
	(segment
		(start 154.6675 97.8)
		(end 156.98 97.8)
		(width 0.3)
		(layer "B.Cu")
		(net 14)
	)
	(segment
		(start 156.98 97.8)
		(end 157.63 97.15)
		(width 0.3)
		(layer "B.Cu")
		(net 14)
	)
	(segment
		(start 161.63 102.35)
		(end 162.4 102.35)
		(width 0.3)
		(layer "B.Cu")
		(net 14)
	)
	(segment
		(start 151.83 97.15)
		(end 152.515 97.835)
		(width 0.3)
		(layer "B.Cu")
		(net 14)
	)
	(segment
		(start 153.5 89.48)
		(end 151.83 91.15)
		(width 0.3)
		(layer "B.Cu")
		(net 14)
	)
	(segment
		(start 161.28 102.7)
		(end 161.63 102.35)
		(width 0.3)
		(layer "B.Cu")
		(net 14)
	)
	(segment
		(start 161.23 97.15)
		(end 160.3925 97.15)
		(width 0.3)
		(layer "B.Cu")
		(net 14)
	)
	(segment
		(start 152.515 97.835)
		(end 153.03 97.835)
		(width 0.3)
		(layer "B.Cu")
		(net 14)
	)
	(segment
		(start 153.5 88.68)
		(end 153.5 89.48)
		(width 0.3)
		(layer "B.Cu")
		(net 14)
	)
	(segment
		(start 162.43 102.38)
		(end 162.43 101.435)
		(width 0.3)
		(layer "B.Cu")
		(net 14)
	)
	(segment
		(start 122.515 108.65)
		(end 122.765 108.9)
		(width 0.15)
		(layer "F.Cu")
		(net 15)
	)
	(segment
		(start 124.69 106.71)
		(end 124.06 106.71)
		(width 0.15)
		(layer "F.Cu")
		(net 15)
	)
	(segment
		(start 124.73 106.75)
		(end 126.5392 106.75)
		(width 0.15)
		(layer "F.Cu")
		(net 15)
	)
	(segment
		(start 123.36 107.65)
		(end 122.52 107.65)
		(width 0.15)
		(layer "F.Cu")
		(net 15)
	)
	(segment
		(start 122.765 108.9)
		(end 124.03 108.9)
		(width 0.15)
		(layer "F.Cu")
		(net 15)
	)
	(segment
		(start 124.31 93.9)
		(end 124.7 93.5)
		(width 0.15)
		(layer "F.Cu")
		(net 15)
	)
	(segment
		(start 124.045 106.725)
		(end 124.045 106.965)
		(width 0.15)
		(layer "F.Cu")
		(net 15)
	)
	(segment
		(start 124.045 106.965)
		(end 123.36 107.65)
		(width 0.15)
		(layer "F.Cu")
		(net 15)
	)
	(segment
		(start 122.52 107.65)
		(end 122.52 108.645)
		(width 0.15)
		(layer "F.Cu")
		(net 15)
	)
	(segment
		(start 124.06 106.71)
		(end 124.045 106.725)
		(width 0.15)
		(layer "F.Cu")
		(net 15)
	)
	(segment
		(start 122.515 109.65)
		(end 122.515 108.65)
		(width 0.15)
		(layer "F.Cu")
		(net 15)
	)
	(segment
		(start 124.69 106.71)
		(end 124.73 106.75)
		(width 0.15)
		(layer "F.Cu")
		(net 15)
	)
	(segment
		(start 126.5392 106.75)
		(end 126.89 106.3992)
		(width 0.15)
		(layer "F.Cu")
		(net 15)
	)
	(via
		(at 124.69 106.71)
		(size 0.45)
		(drill 0.2)
		(layers "F.Cu" "B.Cu")
		(remove_unused_layers yes)
		(keep_end_layers yes)
		(zone_layer_connections)
		(net 15)
	)
	(via
		(at 124.7 93.5)
		(size 0.45)
		(drill 0.2)
		(layers "F.Cu" "B.Cu")
		(remove_unused_layers yes)
		(keep_end_layers yes)
		(free yes)
		(zone_layer_connections)
		(net 15)
	)
	(segment
		(start 121.6 99.5)
		(end 121.6 104.675021)
		(width 0.125)
		(layer "In6.Cu")
		(net 15)
	)
	(segment
		(start 123.634979 106.71)
		(end 122.83 105.905021)
		(width 0.15)
		(layer "In6.Cu")
		(net 15)
	)
	(segment
		(start 124.69 106.71)
		(end 123.634979 106.71)
		(width 0.15)
		(layer "In6.Cu")
		(net 15)
	)
	(segment
		(start 121.6 104.675021)
		(end 122.83 105.905021)
		(width 0.125)
		(layer "In6.Cu")
		(net 15)
	)
	(segment
		(start 124 93.5)
		(end 123.5 94)
		(width 0.125)
		(layer "In6.Cu")
		(net 15)
	)
	(segment
		(start 123.5 97.6)
		(end 121.6 99.5)
		(width 0.125)
		(layer "In6.Cu")
		(net 15)
	)
	(segment
		(start 124.7 93.5)
		(end 124 93.5)
		(width 0.125)
		(layer "In6.Cu")
		(net 15)
	)
	(segment
		(start 123.5 94)
		(end 123.5 97.6)
		(width 0.125)
		(layer "In6.Cu")
		(net 15)
	)
	(segment
		(start 163.68 85.7)
		(end 165.08 85.7)
		(width 0.5)
		(layer "F.Cu")
		(net 16)
	)
	(segment
		(start 165.33 85.45)
		(end 167.03 85.45)
		(width 0.5)
		(layer "F.Cu")
		(net 16)
	)
	(segment
		(start 167.03 85.45)
		(end 168.33 85.45)
		(width 0.5)
		(layer "F.Cu")
		(net 16)
	)
	(segment
		(start 167.03 85.45)
		(end 167.03 83.35)
		(width 0.2)
		(layer "F.Cu")
		(net 16)
	)
	(segment
		(start 167.03 83.35)
		(end 167.83 82.55)
		(width 0.2)
		(layer "F.Cu")
		(net 16)
	)
	(segment
		(start 168.63 85.75)
		(end 168.63 87.75)
		(width 0.5)
		(layer "F.Cu")
		(net 16)
	)
	(segment
		(start 167.83 82.55)
		(end 169.13 82.55)
		(width 0.2)
		(layer "F.Cu")
		(net 16)
	)
	(segment
		(start 168.43 85.55)
		(end 168.63 85.75)
		(width 0.5)
		(layer "F.Cu")
		(net 16)
	)
	(segment
		(start 168.63 87.75)
		(end 169.03 88.15)
		(width 0.5)
		(layer "F.Cu")
		(net 16)
	)
	(segment
		(start 168.33 85.45)
		(end 168.43 85.55)
		(width 0.5)
		(layer "F.Cu")
		(net 16)
	)
	(segment
		(start 165.08 85.7)
		(end 165.33 85.45)
		(width 0.5)
		(layer "F.Cu")
		(net 16)
	)
	(segment
		(start 169.03 88.15)
		(end 169.83 88.15)
		(width 0.5)
		(layer "F.Cu")
		(net 16)
	)
	(segment
		(start 169.13 80.968952)
		(end 169.148952 80.95)
		(width 0.2)
		(layer "F.Cu")
		(net 17)
	)
	(segment
		(start 173.63 87.75)
		(end 172.23 89.15)
		(width 0.2)
		(layer "F.Cu")
		(net 17)
	)
	(segment
		(start 173.03 83.95)
		(end 173.63 84.55)
		(width 0.2)
		(layer "F.Cu")
		(net 17)
	)
	(segment
		(start 169.43 80.95)
		(end 169.83 81.35)
		(width 0.2)
		(layer "F.Cu")
		(net 17)
	)
	(segment
		(start 170.03 83.95)
		(end 173.03 83.95)
		(width 0.2)
		(layer "F.Cu")
		(net 17)
	)
	(segment
		(start 173.63 84.55)
		(end 173.63 87.75)
		(width 0.2)
		(layer "F.Cu")
		(net 17)
	)
	(segment
		(start 169.83 83.75)
		(end 170.03 83.95)
		(width 0.2)
		(layer "F.Cu")
		(net 17)
	)
	(segment
		(start 169.83 81.35)
		(end 169.83 83.75)
		(width 0.2)
		(layer "F.Cu")
		(net 17)
	)
	(segment
		(start 172.23 89.15)
		(end 169.78 89.15)
		(width 0.2)
		(layer "F.Cu")
		(net 17)
	)
	(segment
		(start 169.148952 80.95)
		(end 169.43 80.95)
		(width 0.2)
		(layer "F.Cu")
		(net 17)
	)
	(segment
		(start 136.18 119.25)
		(end 136.08 119.15)
		(width 0.3)
		(layer "F.Cu")
		(net 18)
	)
	(segment
		(start 135.68 119.25)
		(end 135.68 120.125)
		(width 0.3)
		(layer "F.Cu")
		(net 18)
	)
	(segment
		(start 136.18 120.125)
		(end 136.18 119.25)
		(width 0.3)
		(layer "F.Cu")
		(net 18)
	)
	(segment
		(start 136.08 119.15)
		(end 135.78 119.15)
		(width 0.3)
		(layer "F.Cu")
		(net 18)
	)
	(segment
		(start 135.78 119.15)
		(end 135.68 119.25)
		(width 0.3)
		(layer "F.Cu")
		(net 18)
	)
	(segment
		(start 97.01 91.42)
		(end 99.09 93.5)
		(width 0.15)
		(layer "F.Cu")
		(net 20)
	)
	(segment
		(start 93.95 82.93)
		(end 93 83.88)
		(width 0.15)
		(layer "F.Cu")
		(net 20)
	)
	(segment
		(start 91.54 121.735)
		(end 91.54 117.665)
		(width 0.15)
		(layer "F.Cu")
		(net 20)
	)
	(segment
		(start 93 89.92)
		(end 94.5 91.42)
		(width 0.15)
		(layer "F.Cu")
		(net 20)
	)
	(segment
		(start 91.49 115.5)
		(end 91.54 115.55)
		(width 0.15)
		(layer "F.Cu")
		(net 20)
	)
	(segment
		(start 91.54 115.55)
		(end 91.54 117.665)
		(width 0.15)
		(layer "F.Cu")
		(net 20)
	)
	(segment
		(start 94.1 81.4)
		(end 94.56 81.86)
		(width 0.15)
		(layer "F.Cu")
		(net 20)
	)
	(segment
		(start 94.56 81.86)
		(end 94.56 82.62)
		(width 0.15)
		(layer "F.Cu")
		(net 20)
	)
	(segment
		(start 94.5 91.42)
		(end 97.01 91.42)
		(width 0.15)
		(layer "F.Cu")
		(net 20)
	)
	(segment
		(start 93 83.88)
		(end 93 89.92)
		(width 0.15)
		(layer "F.Cu")
		(net 20)
	)
	(segment
		(start 94.56 82.62)
		(end 94.25 82.93)
		(width 0.15)
		(layer "F.Cu")
		(net 20)
	)
	(segment
		(start 99.09 93.5)
		(end 99.09 111.3)
		(width 0.15)
		(layer "F.Cu")
		(net 20)
	)
	(segment
		(start 99.09 111.3)
		(end 94.29 116.1)
		(width 0.15)
		(layer "F.Cu")
		(net 20)
	)
	(segment
		(start 94.25 82.93)
		(end 93.95 82.93)
		(width 0.15)
		(layer "F.Cu")
		(net 20)
	)
	(via
		(at 91.49 115.5)
		(size 0.45)
		(drill 0.2)
		(layers "F.Cu" "B.Cu")
		(remove_unused_layers yes)
		(keep_end_layers yes)
		(zone_layer_connections)
		(net 20)
	)
	(via
		(at 94.29 116.1)
		(size 0.45)
		(drill 0.2)
		(layers "F.Cu" "B.Cu")
		(remove_unused_layers yes)
		(keep_end_layers yes)
		(zone_layer_connections)
		(net 20)
	)
	(segment
		(start 92.09 116.1)
		(end 91.49 115.5)
		(width 0.15)
		(layer "B.Cu")
		(net 20)
	)
	(segment
		(start 94.29 116.1)
		(end 92.09 116.1)
		(width 0.15)
		(layer "B.Cu")
		(net 20)
	)
	(segment
		(start 94.19 92.82)
		(end 96.21 92.82)
		(width 0.15)
		(layer "F.Cu")
		(net 21)
	)
	(segment
		(start 96.21 92.82)
		(end 97.89 94.5)
		(width 0.15)
		(layer "F.Cu")
		(net 21)
	)
	(segment
		(start 90.27 115.44)
		(end 90.27 117.665)
		(width 0.15)
		(layer "F.Cu")
		(net 21)
	)
	(segment
		(start 90.27 121.735)
		(end 90.27 117.665)
		(width 0.15)
		(layer "F.Cu")
		(net 21)
	)
	(segment
		(start 92.13 90.76)
		(end 94.19 92.82)
		(width 0.15)
		(layer "F.Cu")
		(net 21)
	)
	(segment
		(start 93.62 80.88)
		(end 93.62 82.51)
		(width 0.15)
		(layer "F.Cu")
		(net 21)
	)
	(segment
		(start 97.89 110.27)
		(end 93.93 114.23)
		(width 0.15)
		(layer "F.Cu")
		(net 21)
	)
	(segment
		(start 93.62 82.51)
		(end 92.13 84)
		(width 0.15)
		(layer "F.Cu")
		(net 21)
	)
	(segment
		(start 94.1 80.4)
		(end 93.62 80.88)
		(width 0.15)
		(layer "F.Cu")
		(net 21)
	)
	(segment
		(start 97.89 94.5)
		(end 97.89 110.27)
		(width 0.15)
		(layer "F.Cu")
		(net 21)
	)
	(segment
		(start 92.13 84)
		(end 92.13 90.76)
		(width 0.15)
		(layer "F.Cu")
		(net 21)
	)
	(segment
		(start 90.23 115.4)
		(end 90.27 115.44)
		(width 0.15)
		(layer "F.Cu")
		(net 21)
	)
	(segment
		(start 93.93 114.23)
		(end 93.87 114.23)
		(width 0.15)
		(layer "F.Cu")
		(net 21)
	)
	(via
		(at 90.23 115.4)
		(size 0.45)
		(drill 0.2)
		(layers "F.Cu" "B.Cu")
		(remove_unused_layers yes)
		(keep_end_layers yes)
		(zone_layer_connections)
		(net 21)
	)
	(via
		(at 93.87 114.23)
		(size 0.45)
		(drill 0.2)
		(layers "F.Cu" "B.Cu")
		(remove_unused_layers yes)
		(keep_end_layers yes)
		(zone_layer_connections)
		(net 21)
	)
	(segment
		(start 91.4 114.23)
		(end 90.23 115.4)
		(width 0.15)
		(layer "B.Cu")
		(net 21)
	)
	(segment
		(start 93.87 114.23)
		(end 91.4 114.23)
		(width 0.15)
		(layer "B.Cu")
		(net 21)
	)
	(segment
		(start 96.69 95.7)
		(end 96.69 107.5)
		(width 0.15)
		(layer "F.Cu")
		(net 22)
	)
	(segment
		(start 96.69 107.5)
		(end 89 115.19)
		(width 0.15)
		(layer "F.Cu")
		(net 22)
	)
	(segment
		(start 91.29 84.02)
		(end 91.29 91.95)
		(width 0.15)
		(layer "F.Cu")
		(net 22)
	)
	(segment
		(start 95.17 94.18)
		(end 96.69 95.7)
		(width 0.15)
		(layer "F.Cu")
		(net 22)
	)
	(segment
		(start 93.52 94.18)
		(end 95.17 94.18)
		(width 0.15)
		(layer "F.Cu")
		(net 22)
	)
	(segment
		(start 92.58 82.73)
		(end 91.29 84.02)
		(width 0.15)
		(layer "F.Cu")
		(net 22)
	)
	(segment
		(start 93.1 81.4)
		(end 93.1 81.765686)
		(width 0.15)
		(layer "F.Cu")
		(net 22)
	)
	(segment
		(start 91.29 91.95)
		(end 93.52 94.18)
		(width 0.15)
		(layer "F.Cu")
		(net 22)
	)
	(segment
		(start 92.58 82.285686)
		(end 92.58 82.73)
		(width 0.15)
		(layer "F.Cu")
		(net 22)
	)
	(segment
		(start 93.1 81.765686)
		(end 92.58 82.285686)
		(width 0.15)
		(layer "F.Cu")
		(net 22)
	)
	(segment
		(start 89 115.19)
		(end 89 117.665)
		(width 0.15)
		(layer "F.Cu")
		(net 22)
	)
	(segment
		(start 100.49 104.55)
		(end 100.49 111.67)
		(width 0.15)
		(layer "F.Cu")
		(net 23)
	)
	(segment
		(start 100.08 104.14)
		(end 100.49 104.55)
		(width 0.15)
		(layer "F.Cu")
		(net 23)
	)
	(segment
		(start 94.635914 90.4)
		(end 98.11 90.4)
		(width 0.15)
		(layer "F.Cu")
		(net 23)
	)
	(segment
		(start 100.34 92.63)
		(end 100.34 98.65)
		(width 0.15)
		(layer "F.Cu")
		(net 23)
	)
	(segment
		(start 95.63 82.86)
		(end 93.86 84.63)
		(width 0.15)
		(layer "F.Cu")
		(net 23)
	)
	(segment
		(start 89 121.735)
		(end 89 123.26)
		(width 0.15)
		(layer "F.Cu")
		(net 23)
	)
	(segment
		(start 93.850986 89.615072)
		(end 94.635914 90.4)
		(width 0.15)
		(layer "F.Cu")
		(net 23)
	)
	(segment
		(start 93.86 89.163097)
		(end 93.850986 89.172111)
		(width 0.15)
		(layer "F.Cu")
		(net 23)
	)
	(segment
		(start 100.34 100.4)
		(end 100.34 101.34)
		(width 0.15)
		(layer "F.Cu")
		(net 23)
	)
	(segment
		(start 99.98 99.01)
		(end 99.98 100.04)
		(width 0.15)
		(layer "F.Cu")
		(net 23)
	)
	(segment
		(start 100.34 98.65)
		(end 99.98 99.01)
		(width 0.15)
		(layer "F.Cu")
		(net 23)
	)
	(segment
		(start 99.98 100.04)
		(end 100.34 100.4)
		(width 0.15)
		(layer "F.Cu")
		(net 23)
	)
	(segment
		(start 95.63 82.22)
		(end 95.63 82.86)
		(width 0.15)
		(layer "F.Cu")
		(net 23)
	)
	(segment
		(start 95.1 81.69)
		(end 95.63 82.22)
		(width 0.15)
		(layer "F.Cu")
		(net 23)
	)
	(segment
		(start 93.86 84.63)
		(end 93.86 89.163097)
		(width 0.15)
		(layer "F.Cu")
		(net 23)
	)
	(segment
		(start 100.08 101.6)
		(end 100.08 104.14)
		(width 0.15)
		(layer "F.Cu")
		(net 23)
	)
	(segment
		(start 95.1 81.4)
		(end 95.1 81.69)
		(width 0.15)
		(layer "F.Cu")
		(net 23)
	)
	(segment
		(start 93.850986 89.172111)
		(end 93.850986 89.615072)
		(width 0.15)
		(layer "F.Cu")
		(net 23)
	)
	(segment
		(start 98.11 90.4)
		(end 100.34 92.63)
		(width 0.15)
		(layer "F.Cu")
		(net 23)
	)
	(segment
		(start 100.34 101.34)
		(end 100.08 101.6)
		(width 0.15)
		(layer "F.Cu")
		(net 23)
	)
	(segment
		(start 89 123.26)
		(end 89.4 123.66)
		(width 0.15)
		(layer "F.Cu")
		(net 23)
	)
	(segment
		(start 95.18 116.98)
		(end 95.18 123.41)
		(width 0.15)
		(layer "F.Cu")
		(net 23)
	)
	(segment
		(start 100.49 111.67)
		(end 95.18 116.98)
		(width 0.15)
		(layer "F.Cu")
		(net 23)
	)
	(via
		(at 89.4 123.66)
		(size 0.45)
		(drill 0.2)
		(layers "F.Cu" "B.Cu")
		(remove_unused_layers yes)
		(keep_end_layers yes)
		(zone_layer_connections)
		(net 23)
	)
	(via
		(at 95.18 123.41)
		(size 0.45)
		(drill 0.2)
		(layers "F.Cu" "B.Cu")
		(remove_unused_layers yes)
		(keep_end_layers yes)
		(zone_layer_connections)
		(net 23)
	)
	(segment
		(start 94.93 123.66)
		(end 95.18 123.41)
		(width 0.15)
		(layer "B.Cu")
		(net 23)
	)
	(segment
		(start 89.4 123.66)
		(end 94.93 123.66)
		(width 0.15)
		(layer "B.Cu")
		(net 23)
	)
	(segment
		(start 93.1 82.63)
		(end 91.67 84.06)
		(width 0.15)
		(layer "F.Cu")
		(net 24)
	)
	(segment
		(start 97.29 108.9)
		(end 92.97 113.22)
		(width 0.15)
		(layer "F.Cu")
		(net 24)
	)
	(segment
		(start 91.67 91.2)
		(end 93.93 93.46)
		(width 0.15)
		(layer "F.Cu")
		(net 24)
	)
	(segment
		(start 85.3 120.3)
		(end 86.1 119.5)
		(width 0.15)
		(layer "F.Cu")
		(net 24)
	)
	(segment
		(start 92.97 113.22)
		(end 92.97 123.07)
		(width 0.15)
		(layer "F.Cu")
		(net 24)
	)
	(segment
		(start 86.23 124.3)
		(end 85.3 123.37)
		(width 0.15)
		(layer "F.Cu")
		(net 24)
	)
	(segment
		(start 87.49 119.5)
		(end 87.73 119.26)
		(width 0.15)
		(layer "F.Cu")
		(net 24)
	)
	(segment
		(start 95.75 93.46)
		(end 97.29 95)
		(width 0.15)
		(layer "F.Cu")
		(net 24)
	)
	(segment
		(start 97.29 95)
		(end 97.29 108.9)
		(width 0.15)
		(layer "F.Cu")
		(net 24)
	)
	(segment
		(start 87.73 119.26)
		(end 87.73 117.665)
		(width 0.15)
		(layer "F.Cu")
		(net 24)
	)
	(segment
		(start 91.74 124.3)
		(end 86.23 124.3)
		(width 0.15)
		(layer "F.Cu")
		(net 24)
	)
	(segment
		(start 93.93 93.46)
		(end 95.75 93.46)
		(width 0.15)
		(layer "F.Cu")
		(net 24)
	)
	(segment
		(start 93.1 82.4)
		(end 93.1 82.63)
		(width 0.15)
		(layer "F.Cu")
		(net 24)
	)
	(segment
		(start 86.1 119.5)
		(end 87.49 119.5)
		(width 0.15)
		(layer "F.Cu")
		(net 24)
	)
	(segment
		(start 91.67 84.06)
		(end 91.67 91.2)
		(width 0.15)
		(layer "F.Cu")
		(net 24)
	)
	(segment
		(start 85.3 123.37)
		(end 85.3 120.3)
		(width 0.15)
		(layer "F.Cu")
		(net 24)
	)
	(segment
		(start 92.97 123.07)
		(end 91.74 124.3)
		(width 0.15)
		(layer "F.Cu")
		(net 24)
	)
	(segment
		(start 93.42 83.89)
		(end 93.42 89.74)
		(width 0.15)
		(layer "F.Cu")
		(net 25)
	)
	(segment
		(start 97.49 90.9)
		(end 99.69 93.1)
		(width 0.15)
		(layer "F.Cu")
		(net 25)
	)
	(segment
		(start 87.73 123.66)
		(end 87.73 121.735)
		(width 0.15)
		(layer "F.Cu")
		(net 25)
	)
	(segment
		(start 87.69 123.7)
		(end 87.73 123.66)
		(width 0.15)
		(layer "F.Cu")
		(net 25)
	)
	(segment
		(start 94.49 116.9)
		(end 94.49 123.1)
		(width 0.15)
		(layer "F.Cu")
		(net 25)
	)
	(segment
		(start 99.69 111.7)
		(end 94.49 116.9)
		(width 0.15)
		(layer "F.Cu")
		(net 25)
	)
	(segment
		(start 94.58 90.9)
		(end 97.49 90.9)
		(width 0.15)
		(layer "F.Cu")
		(net 25)
	)
	(segment
		(start 94.49 123.1)
		(end 93.49 124.1)
		(width 0.15)
		(layer "F.Cu")
		(net 25)
	)
	(segment
		(start 93.42 89.74)
		(end 94.58 90.9)
		(width 0.15)
		(layer "F.Cu")
		(net 25)
	)
	(segment
		(start 94.08 83.23)
		(end 93.42 83.89)
		(width 0.15)
		(layer "F.Cu")
		(net 25)
	)
	(segment
		(start 94.41 83.23)
		(end 94.08 83.23)
		(width 0.15)
		(layer "F.Cu")
		(net 25)
	)
	(segment
		(start 99.69 93.1)
		(end 99.69 111.7)
		(width 0.15)
		(layer "F.Cu")
		(net 25)
	)
	(segment
		(start 95.1 82.54)
		(end 94.41 83.23)
		(width 0.15)
		(layer "F.Cu")
		(net 25)
	)
	(via
		(at 87.69 123.7)
		(size 0.45)
		(drill 0.2)
		(layers "F.Cu" "B.Cu")
		(remove_unused_layers yes)
		(keep_end_layers yes)
		(zone_layer_connections)
		(net 25)
	)
	(via
		(at 93.49 124.1)
		(size 0.45)
		(drill 0.2)
		(layers "F.Cu" "B.Cu")
		(remove_unused_layers yes)
		(keep_end_layers yes)
		(zone_layer_connections)
		(net 25)
	)
	(segment
		(start 93.49 124.1)
		(end 88.09 124.1)
		(width 0.15)
		(layer "B.Cu")
		(net 25)
	)
	(segment
		(start 88.09 124.1)
		(end 87.69 123.7)
		(width 0.15)
		(layer "B.Cu")
		(net 25)
	)
	(segment
		(start 94.1 82.4)
		(end 92.58 83.92)
		(width 0.15)
		(layer "F.Cu")
		(net 26)
	)
	(segment
		(start 87.89 119.9)
		(end 87.27 119.9)
		(width 0.15)
		(layer "F.Cu")
		(net 26)
	)
	(segment
		(start 96.77 92.18)
		(end 98.49 93.9)
		(width 0.15)
		(layer "F.Cu")
		(net 26)
	)
	(segment
		(start 93.69 115.7)
		(end 93.69 119.7)
		(width 0.15)
		(layer "F.Cu")
		(net 26)
	)
	(segment
		(start 92.58 83.92)
		(end 92.58 90.16)
		(width 0.15)
		(layer "F.Cu")
		(net 26)
	)
	(segment
		(start 94.6 92.18)
		(end 96.77 92.18)
		(width 0.15)
		(layer "F.Cu")
		(net 26)
	)
	(segment
		(start 87.27 119.9)
		(end 86.46 120.71)
		(width 0.15)
		(layer "F.Cu")
		(net 26)
	)
	(segment
		(start 98.49 110.9)
		(end 93.69 115.7)
		(width 0.15)
		(layer "F.Cu")
		(net 26)
	)
	(segment
		(start 98.49 93.9)
		(end 98.49 110.9)
		(width 0.15)
		(layer "F.Cu")
		(net 26)
	)
	(segment
		(start 92.58 90.16)
		(end 94.6 92.18)
		(width 0.15)
		(layer "F.Cu")
		(net 26)
	)
	(via
		(at 93.69 119.7)
		(size 0.45)
		(drill 0.2)
		(layers "F.Cu" "B.Cu")
		(remove_unused_layers yes)
		(keep_end_layers yes)
		(zone_layer_connections)
		(net 26)
	)
	(via
		(at 87.89 119.9)
		(size 0.45)
		(drill 0.2)
		(layers "F.Cu" "B.Cu")
		(remove_unused_layers yes)
		(keep_end_layers yes)
		(zone_layer_connections)
		(net 26)
	)
	(segment
		(start 88.09 119.7)
		(end 87.89 119.9)
		(width 0.15)
		(layer "B.Cu")
		(net 26)
	)
	(segment
		(start 93.69 119.7)
		(end 88.09 119.7)
		(width 0.15)
		(layer "B.Cu")
		(net 26)
	)
	(segment
		(start 122.55 97.85)
		(end 122.525 97.875)
		(width 0.15)
		(layer "F.Cu")
		(net 27)
	)
	(segment
		(start 123.5 93.9)
		(end 123.1 94.3)
		(width 0.15)
		(layer "F.Cu")
		(net 27)
	)
	(segment
		(start 106.48 97.26)
		(end 106.48 99.62)
		(width 0.15)
		(layer "F.Cu")
		(net 27)
	)
	(segment
		(start 106.7 95.3)
		(end 106.29 95.71)
		(width 0.15)
		(layer "F.Cu")
		(net 27)
	)
	(segment
		(start 106.29 95.71)
		(end 106.29 97.07)
		(width 0.15)
		(layer "F.Cu")
		(net 27)
	)
	(segment
		(start 123.1 94.3)
		(end 123.1 97.3)
		(width 0.15)
		(layer "F.Cu")
		(net 27)
	)
	(segment
		(start 111.8 98)
		(end 122.4 98)
		(width 0.15)
		(layer "F.Cu")
		(net 27)
	)
	(segment
		(start 106.475 97.255)
		(end 106.48 97.26)
		(width 0.15)
		(layer "F.Cu")
		(net 27)
	)
	(segment
		(start 122.525 97.875)
		(end 122.4 98)
		(width 0.15)
		(layer "F.Cu")
		(net 27)
	)
	(segment
		(start 106.48 99.62)
		(end 106.475 99.625)
		(width 0.15)
		(layer "F.Cu")
		(net 27)
	)
	(segment
		(start 123.1 97.3)
		(end 122.55 97.85)
		(width 0.15)
		(layer "F.Cu")
		(net 27)
	)
	(via
		(at 111.8 98)
		(size 0.45)
		(drill 0.2)
		(layers "F.Cu" "B.Cu")
		(net 27)
	)
	(via
		(at 106.7 95.3)
		(size 0.45)
		(drill 0.2)
		(layers "F.Cu" "B.Cu")
		(net 27)
	)
	(segment
		(start 106.7 95.3)
		(end 106.434314 95.3)
		(width 0.15)
		(layer "B.Cu")
		(net 27)
	)
	(segment
		(start 103.89 92.755686)
		(end 103.89 92.285)
		(width 0.15)
		(layer "B.Cu")
		(net 27)
	)
	(segment
		(start 106.434314 95.3)
		(end 103.89 92.755686)
		(width 0.15)
		(layer "B.Cu")
		(net 27)
	)
	(segment
		(start 110.8 97.3)
		(end 111.5 98)
		(width 0.15)
		(layer "In6.Cu")
		(net 27)
	)
	(segment
		(start 111.5 98)
		(end 111.8 98)
		(width 0.15)
		(layer "In6.Cu")
		(net 27)
	)
	(segment
		(start 109.4 97.7)
		(end 109.8 97.3)
		(width 0.15)
		(layer "In6.Cu")
		(net 27)
	)
	(segment
		(start 106.7 95.3)
		(end 109.1 97.7)
		(width 0.15)
		(layer "In6.Cu")
		(net 27)
	)
	(segment
		(start 109.1 97.7)
		(end 109.4 97.7)
		(width 0.15)
		(layer "In6.Cu")
		(net 27)
	)
	(segment
		(start 109.8 97.3)
		(end 110.8 97.3)
		(width 0.15)
		(layer "In6.Cu")
		(net 27)
	)
	(segment
		(start 112.7 94.3)
		(end 111.9 95.1)
		(width 0.15)
		(layer "F.Cu")
		(net 28)
	)
	(segment
		(start 120.7 94.3)
		(end 112.7 94.3)
		(width 0.15)
		(layer "F.Cu")
		(net 28)
	)
	(segment
		(start 105.02 92.14)
		(end 105.02 93.28)
		(width 0.15)
		(layer "F.Cu")
		(net 28)
	)
	(segment
		(start 105.02 93.28)
		(end 105 93.3)
		(width 0.15)
		(layer "F.Cu")
		(net 28)
	)
	(segment
		(start 121.1 93.9)
		(end 120.7 94.3)
		(width 0.15)
		(layer "F.Cu")
		(net 28)
	)
	(segment
		(start 105 90.4)
		(end 105 92.12)
		(width 0.15)
		(layer "F.Cu")
		(net 28)
	)
	(via
		(at 105 93.3)
		(size 0.45)
		(drill 0.2)
		(layers "F.Cu" "B.Cu")
		(net 28)
	)
	(via
		(at 111.9 95.1)
		(size 0.45)
		(drill 0.2)
		(layers "F.Cu" "B.Cu")
		(net 28)
	)
	(segment
		(start 111.9 94.7)
		(end 110.6 93.4)
		(width 0.15)
		(layer "B.Cu")
		(net 28)
	)
	(segment
		(start 110.551146 92.58454)
		(end 110.551146 92.253168)
		(width 0.15)
		(layer "B.Cu")
		(net 28)
	)
	(segment
		(start 105.375 91.8)
		(end 104.89 92.285)
		(width 0.15)
		(layer "B.Cu")
		(net 28)
	)
	(segment
		(start 110.6 92.633394)
		(end 110.551146 92.58454)
		(width 0.15)
		(layer "B.Cu")
		(net 28)
	)
	(segment
		(start 110.6 93.4)
		(end 110.6 92.633394)
		(width 0.15)
		(layer "B.Cu")
		(net 28)
	)
	(segment
		(start 105 93.3)
		(end 105 92.395)
		(width 0.15)
		(layer "B.Cu")
		(net 28)
	)
	(segment
		(start 106.5 91.8)
		(end 105.375 91.8)
		(width 0.15)
		(layer "B.Cu")
		(net 28)
	)
	(segment
		(start 110.6 92.204314)
		(end 110.6 91.3)
		(width 0.15)
		(layer "B.Cu")
		(net 28)
	)
	(segment
		(start 110.6 91.3)
		(end 110.4 91.1)
		(width 0.15)
		(layer "B.Cu")
		(net 28)
	)
	(segment
		(start 110.551146 92.253168)
		(end 110.6 92.204314)
		(width 0.15)
		(layer "B.Cu")
		(net 28)
	)
	(segment
		(start 111.9 95.1)
		(end 111.9 94.7)
		(width 0.15)
		(layer "B.Cu")
		(net 28)
	)
	(segment
		(start 107.2 91.1)
		(end 106.5 91.8)
		(width 0.15)
		(layer "B.Cu")
		(net 28)
	)
	(segment
		(start 110.4 91.1)
		(end 107.2 91.1)
		(width 0.15)
		(layer "B.Cu")
		(net 28)
	)
	(segment
		(start 109.4 96)
		(end 108.7 96)
		(width 0.15)
		(layer "F.Cu")
		(net 29)
	)
	(segment
		(start 104.2 100.8)
		(end 102.99 100.8)
		(width 0.15)
		(layer "F.Cu")
		(net 29)
	)
	(segment
		(start 108.7 96)
		(end 108.6 95.9)
		(width 0.15)
		(layer "F.Cu")
		(net 29)
	)
	(via
		(at 108.6 95.9)
		(size 0.45)
		(drill 0.2)
		(layers "F.Cu" "B.Cu")
		(net 29)
	)
	(via
		(at 104.2 100.8)
		(size 0.45)
		(drill 0.2)
		(layers "F.Cu" "B.Cu")
		(net 29)
	)
	(segment
		(start 104.2 100.8)
		(end 108.6 96.4)
		(width 0.15)
		(layer "B.Cu")
		(net 29)
	)
	(segment
		(start 108.6 95.9)
		(end 108.6 96.4)
		(width 0.15)
		(layer "B.Cu")
		(net 29)
	)
	(segment
		(start 137.019314 60.57)
		(end 138.07 61.620686)
		(width 0.15)
		(layer "B.Cu")
		(net 30)
	)
	(segment
		(start 139.23 58.537182)
		(end 139.23 58.715)
		(width 0.3)
		(layer "B.Cu")
		(net 30)
	)
	(segment
		(start 133.435 62.009314)
		(end 134.715686 63.29)
		(width 0.15)
		(layer "B.Cu")
		(net 30)
	)
	(segment
		(start 137.35 63.29)
		(end 134.715686 63.29)
		(width 0.15)
		(layer "B.Cu")
		(net 30)
	)
	(segment
		(start 136.35 60.57)
		(end 137.019314 60.57)
		(width 0.15)
		(layer "B.Cu")
		(net 30)
	)
	(segment
		(start 138.617818 57.925)
		(end 139.23 58.537182)
		(width 0.3)
		(layer "B.Cu")
		(net 30)
	)
	(segment
		(start 137.362182 57.925)
		(end 138.617818 57.925)
		(width 0.3)
		(layer "B.Cu")
		(net 30)
	)
	(segment
		(start 136.58 58.707182)
		(end 137.362182 57.925)
		(width 0.3)
		(layer "B.Cu")
		(net 30)
	)
	(segment
		(start 138.07 62.57)
		(end 137.35 63.29)
		(width 0.15)
		(layer "B.Cu")
		(net 30)
	)
	(segment
		(start 138.07 61.620686)
		(end 138.07 62.57)
		(width 0.15)
		(layer "B.Cu")
		(net 30)
	)
	(segment
		(start 136.575 58.715)
		(end 135.97 59.32)
		(width 0.15)
		(layer "B.Cu")
		(net 30)
	)
	(segment
		(start 135.97 60.19)
		(end 136.35 60.57)
		(width 0.15)
		(layer "B.Cu")
		(net 30)
	)
	(segment
		(start 135.97 59.32)
		(end 135.97 60.19)
		(width 0.15)
		(layer "B.Cu")
		(net 30)
	)
	(segment
		(start 101.3 104.6)
		(end 101.6 104.3)
		(width 0.15)
		(layer "F.Cu")
		(net 31)
	)
	(segment
		(start 100.5 102.1)
		(end 100.5 104.2)
		(width 0.15)
		(layer "F.Cu")
		(net 31)
	)
	(segment
		(start 101.975 103.425)
		(end 102.965 103.425)
		(width 0.15)
		(layer "F.Cu")
		(net 31)
	)
	(segment
		(start 101.6 103.8)
		(end 101.975 103.425)
		(width 0.15)
		(layer "F.Cu")
		(net 31)
	)
	(segment
		(start 101.29251 101.30749)
		(end 100.5 102.1)
		(width 0.15)
		(layer "F.Cu")
		(net 31)
	)
	(segment
		(start 100.9 104.6)
		(end 101.3 104.6)
		(width 0.15)
		(layer "F.Cu")
		(net 31)
	)
	(segment
		(start 111.1 94)
		(end 111.7 93.4)
		(width 0.15)
		(layer "F.Cu")
		(net 31)
	)
	(segment
		(start 111 95.2)
		(end 111.1 95.1)
		(width 0.15)
		(layer "F.Cu")
		(net 31)
	)
	(segment
		(start 101.6 104.3)
		(end 101.6 103.8)
		(width 0.15)
		(layer "F.Cu")
		(net 31)
	)
	(segment
		(start 100.5 104.2)
		(end 100.9 104.6)
		(width 0.15)
		(layer "F.Cu")
		(net 31)
	)
	(segment
		(start 101.29251 99.49251)
		(end 101.29251 101.30749)
		(width 0.15)
		(layer "F.Cu")
		(net 31)
	)
	(segment
		(start 111.1 95.1)
		(end 111.1 94)
		(width 0.15)
		(layer "F.Cu")
		(net 31)
	)
	(via
		(at 101.29251 99.49251)
		(size 0.45)
		(drill 0.2)
		(layers "F.Cu" "B.Cu")
		(net 31)
	)
	(via
		(at 111.7 93.4)
		(size 0.45)
		(drill 0.2)
		(layers "F.Cu" "B.Cu")
		(net 31)
	)
	(segment
		(start 110.3 90.6)
		(end 104.5 90.6)
		(width 0.15)
		(layer "B.Cu")
		(net 31)
	)
	(segment
		(start 101.2 99.4)
		(end 101.29251 99.49251)
		(width 0.15)
		(layer "B.Cu")
		(net 31)
	)
	(segment
		(start 104.5 90.6)
		(end 104.1955 90.2955)
		(width 0.15)
		(layer "B.Cu")
		(net 31)
	)
	(segment
		(start 102.0045 90.2955)
		(end 101.2 91.1)
		(width 0.15)
		(layer "B.Cu")
		(net 31)
	)
	(segment
		(start 111.7 93.4)
		(end 111.7 92)
		(width 0.15)
		(layer "B.Cu")
		(net 31)
	)
	(segment
		(start 102.0045 90.2955)
		(end 104.1955 90.2955)
		(width 0.15)
		(layer "B.Cu")
		(net 31)
	)
	(segment
		(start 101.2 91.1)
		(end 101.2 99.4)
		(width 0.15)
		(layer "B.Cu")
		(net 31)
	)
	(segment
		(start 110.3 90.6)
		(end 111.7 92)
		(width 0.15)
		(layer "B.Cu")
		(net 31)
	)
	(segment
		(start 110.95 96.4)
		(end 110.343022 96.4)
		(width 0.15)
		(layer "F.Cu")
		(net 32)
	)
	(segment
		(start 104.225 104.075)
		(end 102.965 104.075)
		(width 0.15)
		(layer "F.Cu")
		(net 32)
	)
	(segment
		(start 110.343022 96.4)
		(end 110.171511 96.228489)
		(width 0.15)
		(layer "F.Cu")
		(net 32)
	)
	(segment
		(start 105.1 103.2)
		(end 104.225 104.075)
		(width 0.15)
		(layer "F.Cu")
		(net 32)
	)
	(via
		(at 105.1 103.2)
		(size 0.45)
		(drill 0.2)
		(layers "F.Cu" "B.Cu")
		(net 32)
	)
	(via
		(at 110.171511 96.228489)
		(size 0.45)
		(drill 0.2)
		(layers "F.Cu" "B.Cu")
		(net 32)
	)
	(segment
		(start 110.171511 96.228489)
		(end 109.05 97.35)
		(width 0.15)
		(layer "B.Cu")
		(net 32)
	)
	(segment
		(start 104.6 100.9)
		(end 104.6 102.7)
		(width 0.15)
		(layer "B.Cu")
		(net 32)
	)
	(segment
		(start 109.05 97.35)
		(end 108.15 97.35)
		(width 0.15)
		(layer "B.Cu")
		(net 32)
	)
	(segment
		(start 104.6 102.7)
		(end 105.1 103.2)
		(width 0.15)
		(layer "B.Cu")
		(net 32)
	)
	(segment
		(start 104.6 100.9)
		(end 108.15 97.35)
		(width 0.15)
		(layer "B.Cu")
		(net 32)
	)
	(segment
		(start 109.6 94.6)
		(end 109.1 94.1)
		(width 0.15)
		(layer "F.Cu")
		(net 33)
	)
	(segment
		(start 107.5 95.1)
		(end 107.7 95.3)
		(width 0.15)
		(layer "F.Cu")
		(net 33)
	)
	(segment
		(start 107.7 94.1)
		(end 107.5 94.3)
		(width 0.15)
		(layer "F.Cu")
		(net 33)
	)
	(segment
		(start 107.4995 104.1)
		(end 108.59 104.1)
		(width 0.15)
		(layer "F.Cu")
		(net 33)
	)
	(segment
		(start 109.1 94.1)
		(end 107.7 94.1)
		(width 0.15)
		(layer "F.Cu")
		(net 33)
	)
	(segment
		(start 107.5 94.3)
		(end 107.5 95.1)
		(width 0.15)
		(layer "F.Cu")
		(net 33)
	)
	(via
		(at 107.4995 104.1)
		(size 0.45)
		(drill 0.2)
		(layers "F.Cu" "B.Cu")
		(net 33)
	)
	(via
		(at 107.7 95.3)
		(size 0.45)
		(drill 0.2)
		(layers "F.Cu" "B.Cu")
		(net 33)
	)
	(segment
		(start 103.5 102.4)
		(end 103.5 100.5)
		(width 0.15)
		(layer "B.Cu")
		(net 33)
	)
	(segment
		(start 107.7 96.551084)
		(end 107.7 95.3)
		(width 0.15)
		(layer "B.Cu")
		(net 33)
	)
	(segment
		(start 105.253814 98.3)
		(end 105.951084 98.3)
		(width 0.15)
		(layer "B.Cu")
		(net 33)
	)
	(segment
		(start 105.0195 98.9805)
		(end 105.0195 98.534314)
		(width 0.15)
		(layer "B.Cu")
		(net 33)
	)
	(segment
		(start 103.5 100.5)
		(end 105.0195 98.9805)
		(width 0.15)
		(layer "B.Cu")
		(net 33)
	)
	(segment
		(start 105.951084 98.3)
		(end 107.7 96.551084)
		(width 0.15)
		(layer "B.Cu")
		(net 33)
	)
	(segment
		(start 107.4995 104.1)
		(end 105.2 104.1)
		(width 0.15)
		(layer "B.Cu")
		(net 33)
	)
	(segment
		(start 105.2 104.1)
		(end 103.5 102.4)
		(width 0.15)
		(layer "B.Cu")
		(net 33)
	)
	(segment
		(start 105.0195 98.534314)
		(end 105.253814 98.3)
		(width 0.15)
		(layer "B.Cu")
		(net 33)
	)
	(segment
		(start 110.951146 92.418854)
		(end 112.318854 92.418854)
		(width 0.15)
		(layer "F.Cu")
		(net 34)
	)
	(segment
		(start 119.17 93.1)
		(end 120.2 93.1)
		(width 0.15)
		(layer "F.Cu")
		(net 34)
	)
	(segment
		(start 164.53 116.27)
		(end 164.53 119.72)
		(width 0.15)
		(layer "F.Cu")
		(net 34)
	)
	(segment
		(start 164.53 119.72)
		(end 164.5 119.75)
		(width 0.15)
		(layer "F.Cu")
		(net 34)
	)
	(segment
		(start 112.318854 92.418854)
		(end 112.86 92.96)
		(width 0.15)
		(layer "F.Cu")
		(net 34)
	)
	(segment
		(start 119.03 92.96)
		(end 119.17 93.1)
		(width 0.15)
		(layer "F.Cu")
		(net 34)
	)
	(segment
		(start 165.63 115.65)
		(end 165.15 115.65)
		(width 0.15)
		(layer "F.Cu")
		(net 34)
	)
	(segment
		(start 112.86 92.96)
		(end 119.03 92.96)
		(width 0.15)
		(layer "F.Cu")
		(net 34)
	)
	(segment
		(start 120.2 93.1)
		(end 120.25 93.15)
		(width 0.15)
		(layer "F.Cu")
		(net 34)
	)
	(segment
		(start 165.15 115.65)
		(end 164.53 116.27)
		(width 0.15)
		(layer "F.Cu")
		(net 34)
	)
	(via
		(at 110.951146 92.418854)
		(size 0.45)
		(drill 0.2)
		(layers "F.Cu" "B.Cu")
		(remove_unused_layers yes)
		(keep_end_layers yes)
		(zone_layer_connections)
		(net 34)
	)
	(via
		(at 164.5 119.75)
		(size 0.45)
		(drill 0.2)
		(layers "F.Cu" "B.Cu")
		(remove_unused_layers yes)
		(keep_end_layers yes)
		(zone_layer_connections)
		(net 34)
	)
	(segment
		(start 117.04 113.12)
		(end 115.82 111.9)
		(width 0.15)
		(layer "B.Cu")
		(net 34)
	)
	(segment
		(start 115.82 98.266446)
		(end 110.951146 93.397592)
		(width 0.15)
		(layer "B.Cu")
		(net 34)
	)
	(segment
		(start 117.04 115.85)
		(end 117.04 113.12)
		(width 0.15)
		(layer "B.Cu")
		(net 34)
	)
	(segment
		(start 125.81 124.62)
		(end 117.04 115.85)
		(width 0.15)
		(layer "B.Cu")
		(net 34)
	)
	(segment
		(start 115.82 111.9)
		(end 115.82 98.266446)
		(width 0.15)
		(layer "B.Cu")
		(net 34)
	)
	(segment
		(start 164.5 119.75)
		(end 164.5 121.47)
		(width 0.15)
		(layer "B.Cu")
		(net 34)
	)
	(segment
		(start 110.951146 93.397592)
		(end 110.951146 92.418854)
		(width 0.15)
		(layer "B.Cu")
		(net 34)
	)
	(segment
		(start 161.35 124.62)
		(end 125.81 124.62)
		(width 0.15)
		(layer "B.Cu")
		(net 34)
	)
	(segment
		(start 164.5 121.47)
		(end 161.35 124.62)
		(width 0.15)
		(layer "B.Cu")
		(net 34)
	)
	(segment
		(start 147 122.7)
		(end 147 120.75)
		(width 0.15)
		(layer "F.Cu")
		(net 35)
	)
	(segment
		(start 147 120.75)
		(end 147.5 120.25)
		(width 0.15)
		(layer "F.Cu")
		(net 35)
	)
	(segment
		(start 120.7 93.5)
		(end 121.1 93.1)
		(width 0.15)
		(layer "F.Cu")
		(net 35)
	)
	(segment
		(start 145.49 124.21)
		(end 147 122.7)
		(width 0.15)
		(layer "F.Cu")
		(net 35)
	)
	(segment
		(start 149.5 124.25)
		(end 152.75 124.25)
		(width 0.15)
		(layer "F.Cu")
		(net 35)
	)
	(segment
		(start 149 122.75)
		(end 149 123.75)
		(width 0.15)
		(layer "F.Cu")
		(net 35)
	)
	(segment
		(start 110.076146 92.10954)
		(end 110.78546 92.818854)
		(width 0.15)
		(layer "F.Cu")
		(net 35)
	)
	(segment
		(start 152.75 124.25)
		(end 154.5 122.5)
		(width 0.15)
		(layer "F.Cu")
		(net 35)
	)
	(segment
		(start 124.7 124.21)
		(end 145.49 124.21)
		(width 0.15)
		(layer "F.Cu")
		(net 35)
	)
	(segment
		(start 148.25 122)
		(end 149 122.75)
		(width 0.15)
		(layer "F.Cu")
		(net 35)
	)
	(segment
		(start 112.3653 92.818854)
		(end 113.046446 93.5)
		(width 0.15)
		(layer "F.Cu")
		(net 35)
	)
	(segment
		(start 148.25 120.75)
		(end 148.25 122)
		(width 0.15)
		(layer "F.Cu")
		(net 35)
	)
	(segment
		(start 110.076146 91.543854)
		(end 110.076146 92.10954)
		(width 0.15)
		(layer "F.Cu")
		(net 35)
	)
	(segment
		(start 110.78546 92.818854)
		(end 112.3653 92.818854)
		(width 0.15)
		(layer "F.Cu")
		(net 35)
	)
	(segment
		(start 124 123.51)
		(end 124.7 124.21)
		(width 0.15)
		(layer "F.Cu")
		(net 35)
	)
	(segment
		(start 148.25 120.684314)
		(end 148.25 120.75)
		(width 0.15)
		(layer "F.Cu")
		(net 35)
	)
	(segment
		(start 147.5 120.25)
		(end 147.815686 120.25)
		(width 0.15)
		(layer "F.Cu")
		(net 35)
	)
	(segment
		(start 113.046446 93.5)
		(end 120.7 93.5)
		(width 0.147)
		(layer "F.Cu")
		(net 35)
	)
	(segment
		(start 161.98 116.5)
		(end 162.73 115.75)
		(width 0.15)
		(layer "F.Cu")
		(net 35)
	)
	(segment
		(start 149 123.75)
		(end 149.5 124.25)
		(width 0.15)
		(layer "F.Cu")
		(net 35)
	)
	(segment
		(start 161.5 116.5)
		(end 161.98 116.5)
		(width 0.15)
		(layer "F.Cu")
		(net 35)
	)
	(segment
		(start 147.815686 120.25)
		(end 148.25 120.684314)
		(width 0.15)
		(layer "F.Cu")
		(net 35)
	)
	(via
		(at 110.076146 91.543854)
		(size 0.45)
		(drill 0.2)
		(layers "F.Cu" "B.Cu")
		(remove_unused_layers yes)
		(keep_end_layers yes)
		(zone_layer_connections)
		(net 35)
	)
	(via
		(at 154.5 122.5)
		(size 0.45)
		(drill 0.2)
		(layers "F.Cu" "B.Cu")
		(remove_unused_layers yes)
		(keep_end_layers yes)
		(zone_layer_connections)
		(net 35)
	)
	(via
		(at 161.5 116.5)
		(size 0.45)
		(drill 0.2)
		(layers "F.Cu" "B.Cu")
		(remove_unused_layers yes)
		(keep_end_layers yes)
		(zone_layer_connections)
		(net 35)
	)
	(via
		(at 124 123.51)
		(size 0.45)
		(drill 0.2)
		(layers "F.Cu" "B.Cu")
		(remove_unused_layers yes)
		(keep_end_layers yes)
		(zone_layer_connections)
		(net 35)
	)
	(segment
		(start 116.67 113.26)
		(end 115.55 112.14)
		(width 0.15)
		(layer "B.Cu")
		(net 35)
	)
	(segment
		(start 111.472348 97.493338)
		(end 111.472348 94.772348)
		(width 0.15)
		(layer "B.Cu")
		(net 35)
	)
	(segment
		(start 110.565686 98.4)
		(end 111.472348 97.493338)
		(width 0.15)
		(layer "B.Cu")
		(net 35)
	)
	(segment
		(start 107.87 102.08)
		(end 107.87 100.02)
		(width 0.15)
		(layer "B.Cu")
		(net 35)
	)
	(segment
		(start 108.45 98.484314)
		(end 108.834733 98.099581)
		(width 0.15)
		(layer "B.Cu")
		(net 35)
	)
	(segment
		(start 108.45 99.44)
		(end 108.45 98.484314)
		(width 0.15)
		(layer "B.Cu")
		(net 35)
	)
	(segment
		(start 124 123.51)
		(end 116.67 116.18)
		(width 0.15)
		(layer "B.Cu")
		(net 35)
	)
	(segment
		(start 109.624314 98.4)
		(end 110.565686 98.4)
		(width 0.15)
		(layer "B.Cu")
		(net 35)
	)
	(segment
		(start 161.5 120)
		(end 161.5 116.5)
		(width 0.15)
		(layer "B.Cu")
		(net 35)
	)
	(segment
		(start 116.67 116.18)
		(end 116.67 113.26)
		(width 0.15)
		(layer "B.Cu")
		(net 35)
	)
	(segment
		(start 109.323895 98.099581)
		(end 109.624314 98.4)
		(width 0.15)
		(layer "B.Cu")
		(net 35)
	)
	(segment
		(start 154.5 122.5)
		(end 159 122.5)
		(width 0.15)
		(layer "B.Cu")
		(net 35)
	)
	(segment
		(start 159 122.5)
		(end 161.5 120)
		(width 0.15)
		(layer "B.Cu")
		(net 35)
	)
	(segment
		(start 115.55 109.76)
		(end 107.87 102.08)
		(width 0.15)
		(layer "B.Cu")
		(net 35)
	)
	(segment
		(start 111.472348 94.772348)
		(end 110.076146 93.376146)
		(width 0.15)
		(layer "B.Cu")
		(net 35)
	)
	(segment
		(start 115.55 112.14)
		(end 115.55 109.76)
		(width 0.15)
		(layer "B.Cu")
		(net 35)
	)
	(segment
		(start 108.834733 98.099581)
		(end 109.323895 98.099581)
		(width 0.15)
		(layer "B.Cu")
		(net 35)
	)
	(segment
		(start 110.076146 93.376146)
		(end 110.076146 91.543854)
		(width 0.15)
		(layer "B.Cu")
		(net 35)
	)
	(segment
		(start 107.87 100.02)
		(end 108.45 99.44)
		(width 0.15)
		(layer "B.Cu")
		(net 35)
	)
	(segment
		(start 124.37 97.3)
		(end 125.496186 97.3)
		(width 0.15)
		(layer "F.Cu")
		(net 36)
	)
	(segment
		(start 123.5 94.7)
		(end 123.9 95.1)
		(width 0.15)
		(layer "F.Cu")
		(net 36)
	)
	(segment
		(start 123.9 96.83)
		(end 124.37 97.3)
		(width 0.15)
		(layer "F.Cu")
		(net 36)
	)
	(segment
		(start 125.9605 97.764314)
		(end 125.9605 98.1595)
		(width 0.15)
		(layer "F.Cu")
		(net 36)
	)
	(segment
		(start 125.496186 97.3)
		(end 125.9605 97.764314)
		(width 0.15)
		(layer "F.Cu")
		(net 36)
	)
	(segment
		(start 134.315 111.15)
		(end 134.315 109.15)
		(width 0.15)
		(layer "F.Cu")
		(net 36)
	)
	(segment
		(start 124.83 99.29)
		(end 124.83 102.95)
		(width 0.15)
		(layer "F.Cu")
		(net 36)
	)
	(segment
		(start 125.9605 98.1595)
		(end 124.83 99.29)
		(width 0.15)
		(layer "F.Cu")
		(net 36)
	)
	(segment
		(start 124.83 102.95)
		(end 124.63 103.15)
		(width 0.15)
		(layer "F.Cu")
		(net 36)
	)
	(segment
		(start 123.9 95.1)
		(end 123.9 96.83)
		(width 0.145)
		(layer "F.Cu")
		(net 36)
	)
	(segment
		(start 134.31251 107.83749)
		(end 134.31251 109.14751)
		(width 0.15)
		(layer "F.Cu")
		(net 36)
	)
	(segment
		(start 134.65 107.5)
		(end 134.31251 107.83749)
		(width 0.15)
		(layer "F.Cu")
		(net 36)
	)
	(via
		(at 134.65 107.5)
		(size 0.45)
		(drill 0.2)
		(layers "F.Cu" "B.Cu")
		(remove_unused_layers yes)
		(keep_end_layers yes)
		(zone_layer_connections)
		(net 36)
	)
	(via
		(at 124.63 103.15)
		(size 0.45)
		(drill 0.2)
		(layers "F.Cu" "B.Cu")
		(remove_unused_layers yes)
		(keep_end_layers yes)
		(zone_layer_connections)
		(net 36)
	)
	(segment
		(start 127.43 106.85)
		(end 124.63 104.05)
		(width 0.15)
		(layer "In2.Cu")
		(net 36)
	)
	(segment
		(start 124.63 104.05)
		(end 124.63 103.15)
		(width 0.15)
		(layer "In2.Cu")
		(net 36)
	)
	(segment
		(start 134 106.85)
		(end 127.43 106.85)
		(width 0.15)
		(layer "In2.Cu")
		(net 36)
	)
	(segment
		(start 134.65 107.5)
		(end 134 106.85)
		(width 0.15)
		(layer "In2.Cu")
		(net 36)
	)
	(segment
		(start 118.7 97.1)
		(end 112.8 97.1)
		(width 0.15)
		(layer "F.Cu")
		(net 37)
	)
	(segment
		(start 104.796446 100.65)
		(end 106.95 100.65)
		(width 0.15)
		(layer "F.Cu")
		(net 37)
	)
	(segment
		(start 106.95 100.65)
		(end 107 100.6)
		(width 0.15)
		(layer "F.Cu")
		(net 37)
	)
	(segment
		(start 107 100.6)
		(end 107.7 99.9)
		(width 0.15)
		(layer "F.Cu")
		(net 37)
	)
	(segment
		(start 110.8 97.5)
		(end 110.8 97)
		(width 0.15)
		(layer "F.Cu")
		(net 37)
	)
	(segment
		(start 111.872348 96.827652)
		(end 111.872348 96.927652)
		(width 0.15)
		(layer "F.Cu")
		(net 37)
	)
	(segment
		(start 119.9 95.9)
		(end 118.7 97.1)
		(width 0.15)
		(layer "F.Cu")
		(net 37)
	)
	(segment
		(start 110.9 97.6)
		(end 110.8 97.5)
		(width 0.15)
		(layer "F.Cu")
		(net 37)
	)
	(segment
		(start 121.3 95.9)
		(end 119.9 95.9)
		(width 0.145)
		(layer "F.Cu")
		(net 37)
	)
	(segment
		(start 103.946446 99.8)
		(end 104.796446 100.65)
		(width 0.15)
		(layer "F.Cu")
		(net 37)
	)
	(segment
		(start 112 99.9)
		(end 113.5 98.4)
		(width 0.15)
		(layer "F.Cu")
		(net 37)
	)
	(segment
		(start 121.5 95.7)
		(end 121.3 95.9)
		(width 0.15)
		(layer "F.Cu")
		(net 37)
	)
	(segment
		(start 112.8 97.1)
		(end 112.6 97.3)
		(width 0.15)
		(layer "F.Cu")
		(net 37)
	)
	(segment
		(start 111.2 97.6)
		(end 110.9 97.6)
		(width 0.15)
		(layer "F.Cu")
		(net 37)
	)
	(segment
		(start 121.9 94.7)
		(end 121.5 95.1)
		(width 0.15)
		(layer "F.Cu")
		(net 37)
	)
	(segment
		(start 111.872348 96.927652)
		(end 111.2 97.6)
		(width 0.15)
		(layer "F.Cu")
		(net 37)
	)
	(segment
		(start 121.5 95.1)
		(end 121.5 95.7)
		(width 0.15)
		(layer "F.Cu")
		(net 37)
	)
	(segment
		(start 102.8 99.8)
		(end 103.946446 99.8)
		(width 0.15)
		(layer "F.Cu")
		(net 37)
	)
	(segment
		(start 107.7 99.9)
		(end 112 99.9)
		(width 0.15)
		(layer "F.Cu")
		(net 37)
	)
	(via
		(at 111.872348 96.827652)
		(size 0.45)
		(drill 0.2)
		(layers "F.Cu" "B.Cu")
		(net 37)
	)
	(via
		(at 112.6 97.3)
		(size 0.45)
		(drill 0.2)
		(layers "F.Cu" "B.Cu")
		(net 37)
	)
	(via
		(at 113.5 98.4)
		(size 0.45)
		(drill 0.2)
		(layers "F.Cu" "B.Cu")
		(net 37)
	)
	(via
		(at 102.8 99.8)
		(size 0.45)
		(drill 0.2)
		(layers "F.Cu" "B.Cu")
		(net 37)
	)
	(segment
		(start 103.19 97.285)
		(end 103.19 99.41)
		(width 0.15)
		(layer "B.Cu")
		(net 37)
	)
	(segment
		(start 112.044696 97)
		(end 112.3 97)
		(width 0.15)
		(layer "B.Cu")
		(net 37)
	)
	(segment
		(start 103.19 99.41)
		(end 102.8 99.8)
		(width 0.15)
		(layer "B.Cu")
		(net 37)
	)
	(segment
		(start 113.5 98.2)
		(end 112.6 97.3)
		(width 0.15)
		(layer "B.Cu")
		(net 37)
	)
	(segment
		(start 113.5 98.4)
		(end 113.5 98.2)
		(width 0.15)
		(layer "B.Cu")
		(net 37)
	)
	(segment
		(start 111.872348 96.827652)
		(end 112.044696 97)
		(width 0.15)
		(layer "B.Cu")
		(net 37)
	)
	(segment
		(start 112.3 97)
		(end 112.6 97.3)
		(width 0.15)
		(layer "B.Cu")
		(net 37)
	)
	(segment
		(start 111.9 93.9)
		(end 120.3 93.9)
		(width 0.15)
		(layer "F.Cu")
		(net 38)
	)
	(segment
		(start 111.5 94.3)
		(end 111.9 93.9)
		(width 0.15)
		(layer "F.Cu")
		(net 38)
	)
	(segment
		(start 111 95.6)
		(end 111.4 95.6)
		(width 0.15)
		(layer "F.Cu")
		(net 38)
	)
	(segment
		(start 111.9 93.9)
		(end 111.998711 93.9)
		(width 0.15)
		(layer "F.Cu")
		(net 38)
	)
	(segment
		(start 111.5 95.5)
		(end 111.5 94.3)
		(width 0.15)
		(layer "F.Cu")
		(net 38)
	)
	(segment
		(start 111.998711 93.9)
		(end 112.047692 93.851019)
		(width 0.15)
		(layer "F.Cu")
		(net 38)
	)
	(segment
		(start 111.4 95.6)
		(end 111.5 95.5)
		(width 0.15)
		(layer "F.Cu")
		(net 38)
	)
	(via
		(at 103.7 95.1)
		(size 0.45)
		(drill 0.2)
		(layers "F.Cu" "B.Cu")
		(net 38)
	)
	(via
		(at 112.047692 93.851019)
		(size 0.45)
		(drill 0.2)
		(layers "F.Cu" "B.Cu")
		(net 38)
	)
	(segment
		(start 104.19 97.285)
		(end 103.695 96.79)
		(width 0.15)
		(layer "B.Cu")
		(net 38)
	)
	(segment
		(start 103.695 96.79)
		(end 103.695 95.105)
		(width 0.15)
		(layer "B.Cu")
		(net 38)
	)
	(segment
		(start 103.695 95.105)
		(end 103.7 95.1)
		(width 0.15)
		(layer "B.Cu")
		(net 38)
	)
	(segment
		(start 112.047692 93.851019)
		(end 111.798711 94.1)
		(width 0.15)
		(layer "In6.Cu")
		(net 38)
	)
	(segment
		(start 104.7 94.1)
		(end 103.7 95.1)
		(width 0.15)
		(layer "In6.Cu")
		(net 38)
	)
	(segment
		(start 111.798711 94.1)
		(end 104.7 94.1)
		(width 0.15)
		(layer "In6.Cu")
		(net 38)
	)
	(segment
		(start 108.7 94.5)
		(end 109.4 95.2)
		(width 0.15)
		(layer "F.Cu")
		(net 39)
	)
	(segment
		(start 108.1 94.5)
		(end 108.7 94.5)
		(width 0.15)
		(layer "F.Cu")
		(net 39)
	)
	(segment
		(start 113.4 94.7)
		(end 120.3 94.7)
		(width 0.15)
		(layer "F.Cu")
		(net 39)
	)
	(segment
		(start 112.4 95.7)
		(end 113.4 94.7)
		(width 0.15)
		(layer "F.Cu")
		(net 39)
	)
	(via
		(at 108.1 94.5)
		(size 0.45)
		(drill 0.2)
		(layers "F.Cu" "B.Cu")
		(net 39)
	)
	(via
		(at 112.4 95.7)
		(size 0.45)
		(drill 0.2)
		(layers "F.Cu" "B.Cu")
		(net 39)
	)
	(via
		(at 102.1 100.2)
		(size 0.45)
		(drill 0.2)
		(layers "F.Cu" "B.Cu")
		(net 39)
	)
	(segment
		(start 105.19 98.01)
		(end 102.9 100.3)
		(width 0.15)
		(layer "B.Cu")
		(net 39)
	)
	(segment
		(start 102.2 100.3)
		(end 102.1 100.2)
		(width 0.15)
		(layer "B.Cu")
		(net 39)
	)
	(segment
		(start 105.19 97.285)
		(end 105.19 98.01)
		(width 0.15)
		(layer "B.Cu")
		(net 39)
	)
	(segment
		(start 102.9 100.3)
		(end 102.2 100.3)
		(width 0.15)
		(layer "B.Cu")
		(net 39)
	)
	(segment
		(start 112.4 95.7)
		(end 111.7 95.7)
		(width 0.15)
		(layer "In6.Cu")
		(net 39)
	)
	(segment
		(start 108.6 97.9)
		(end 106.3 95.6)
		(width 0.15)
		(layer "In6.Cu")
		(net 39)
	)
	(segment
		(start 111.7 95.7)
		(end 110.5 94.5)
		(width 0.15)
		(layer "In6.Cu")
		(net 39)
	)
	(segment
		(start 110.5 94.5)
		(end 108.1 94.5)
		(width 0.15)
		(layer "In6.Cu")
		(net 39)
	)
	(segment
		(start 106.3 95.134314)
		(end 106.934314 94.5)
		(width 0.15)
		(layer "In6.Cu")
		(net 39)
	)
	(segment
		(start 106.934314 94.5)
		(end 108.1 94.5)
		(width 0.15)
		(layer "In6.Cu")
		(net 39)
	)
	(segment
		(start 104.5 99)
		(end 105.189169 99)
		(width 0.15)
		(layer "In6.Cu")
		(net 39)
	)
	(segment
		(start 106.3 95.6)
		(end 106.3 95.134314)
		(width 0.15)
		(layer "In6.Cu")
		(net 39)
	)
	(segment
		(start 108.6 98.1)
		(end 108.6 97.9)
		(width 0.15)
		(layer "In6.Cu")
		(net 39)
	)
	(segment
		(start 108.060686 99.075)
		(end 108.600419 98.535267)
		(width 0.15)
		(layer "In6.Cu")
		(net 39)
	)
	(segment
		(start 108.600419 98.100419)
		(end 108.6 98.1)
		(width 0.15)
		(layer "In6.Cu")
		(net 39)
	)
	(segment
		(start 103.3 100.2)
		(end 104.5 99)
		(width 0.15)
		(layer "In6.Cu")
		(net 39)
	)
	(segment
		(start 108.600419 98.535267)
		(end 108.600419 98.100419)
		(width 0.15)
		(layer "In6.Cu")
		(net 39)
	)
	(segment
		(start 105.264169 99.075)
		(end 108.060686 99.075)
		(width 0.15)
		(layer "In6.Cu")
		(net 39)
	)
	(segment
		(start 102.1 100.2)
		(end 103.3 100.2)
		(width 0.15)
		(layer "In6.Cu")
		(net 39)
	)
	(segment
		(start 105.189169 99)
		(end 105.264169 99.075)
		(width 0.15)
		(layer "In6.Cu")
		(net 39)
	)
	(segment
		(start 118.45 114.48)
		(end 119.78 113.15)
		(width 0.15)
		(layer "F.Cu")
		(net 40)
	)
	(segment
		(start 119.68 95.5)
		(end 118.89 96.29)
		(width 0.15)
		(layer "F.Cu")
		(net 40)
	)
	(segment
		(start 121.545 113.15)
		(end 120.53 113.15)
		(width 0.15)
		(layer "F.Cu")
		(net 40)
	)
	(segment
		(start 121.545 113.15)
		(end 121.545 115.15)
		(width 0.15)
		(layer "F.Cu")
		(net 40)
	)
	(segment
		(start 116.42 96.29)
		(end 116.218854 96.491146)
		(width 0.15)
		(layer "F.Cu")
		(net 40)
	)
	(segment
		(start 119.78 113.15)
		(end 120.53 113.15)
		(width 0.15)
		(layer "F.Cu")
		(net 40)
	)
	(segment
		(start 120.3 95.5)
		(end 119.68 95.5)
		(width 0.15)
		(layer "F.Cu")
		(net 40)
	)
	(segment
		(start 118.89 96.29)
		(end 116.42 96.29)
		(width 0.15)
		(layer "F.Cu")
		(net 40)
	)
	(via
		(at 118.45 114.48)
		(size 0.45)
		(drill 0.2)
		(layers "F.Cu" "B.Cu")
		(remove_unused_layers yes)
		(keep_end_layers yes)
		(zone_layer_connections)
		(net 40)
	)
	(via
		(at 116.218854 96.491146)
		(size 0.45)
		(drill 0.2)
		(layers "F.Cu" "B.Cu")
		(remove_unused_layers yes)
		(keep_end_layers yes)
		(zone_layer_connections)
		(net 40)
	)
	(segment
		(start 117.64 113.67)
		(end 118.45 114.48)
		(width 0.15)
		(layer "B.Cu")
		(net 40)
	)
	(segment
		(start 117.64 112.844314)
		(end 117.64 113.67)
		(width 0.15)
		(layer "B.Cu")
		(net 40)
	)
	(segment
		(start 116.218854 111.423168)
		(end 117.64 112.844314)
		(width 0.15)
		(layer "B.Cu")
		(net 40)
	)
	(segment
		(start 116.218854 96.491146)
		(end 116.218854 111.423168)
		(width 0.15)
		(layer "B.Cu")
		(net 40)
	)
	(segment
		(start 109.3 96.4)
		(end 108.9 96.8)
		(width 0.15)
		(layer "F.Cu")
		(net 41)
	)
	(segment
		(start 118.75 95.8)
		(end 119.45 95.1)
		(width 0.15)
		(layer "F.Cu")
		(net 41)
	)
	(segment
		(start 113.2 95.8)
		(end 118.75 95.8)
		(width 0.15)
		(layer "F.Cu")
		(net 41)
	)
	(segment
		(start 112.8 96.2)
		(end 113.2 95.8)
		(width 0.15)
		(layer "F.Cu")
		(net 41)
	)
	(segment
		(start 119.45 95.1)
		(end 120.57 95.1)
		(width 0.147)
		(layer "F.Cu")
		(net 41)
	)
	(segment
		(start 120.57 95.1)
		(end 120.97 94.7)
		(width 0.15)
		(layer "F.Cu")
		(net 41)
	)
	(via
		(at 112.8 96.2)
		(size 0.45)
		(drill 0.2)
		(layers "F.Cu" "B.Cu")
		(remove_unused_layers yes)
		(keep_end_layers yes)
		(zone_layer_connections)
		(net 41)
	)
	(via
		(at 108.9 96.8)
		(size 0.45)
		(drill 0.2)
		(layers "F.Cu" "B.Cu")
		(net 41)
	)
	(via
		(at 105.689882 95.827492)
		(size 0.45)
		(drill 0.2)
		(layers "F.Cu" "B.Cu")
		(net 41)
	)
	(segment
		(start 105.689882 96.784882)
		(end 105.689882 95.827492)
		(width 0.15)
		(layer "B.Cu")
		(net 41)
	)
	(segment
		(start 106.19 97.285)
		(end 105.689882 96.784882)
		(width 0.15)
		(layer "B.Cu")
		(net 41)
	)
	(segment
		(start 106.66239 96.8)
		(end 105.689882 95.827492)
		(width 0.15)
		(layer "In4.Cu")
		(net 41)
	)
	(segment
		(start 108.9 96.8)
		(end 106.66239 96.8)
		(width 0.15)
		(layer "In4.Cu")
		(net 41)
	)
	(segment
		(start 112.8 96.2)
		(end 112.7 96.3)
		(width 0.15)
		(layer "In6.Cu")
		(net 41)
	)
	(segment
		(start 112.7 96.3)
		(end 111.634313 96.3)
		(width 0.15)
		(layer "In6.Cu")
		(net 41)
	)
	(segment
		(start 110.934313 97)
		(end 109.1 97)
		(width 0.15)
		(layer "In6.Cu")
		(net 41)
	)
	(segment
		(start 111.634313 96.3)
		(end 110.934313 97)
		(width 0.15)
		(layer "In6.Cu")
		(net 41)
	)
	(segment
		(start 109.1 97)
		(end 108.9 96.8)
		(width 0.15)
		(layer "In6.Cu")
		(net 41)
	)
	(segment
		(start 107.4 107.685)
		(end 107.4 108.4)
		(width 0.15)
		(layer "F.Cu")
		(net 42)
	)
	(segment
		(start 116.18 113.37)
		(end 116.36 113.37)
		(width 0.15)
		(layer "F.Cu")
		(net 42)
	)
	(segment
		(start 121.08 108.65)
		(end 121.545 108.65)
		(width 0.15)
		(layer "F.Cu")
		(net 42)
	)
	(segment
		(start 107.4 108.4)
		(end 107.6 108.6)
		(width 0.15)
		(layer "F.Cu")
		(net 42)
	)
	(segment
		(start 116.36 113.37)
		(end 121.08 108.65)
		(width 0.15)
		(layer "F.Cu")
		(net 42)
	)
	(via
		(at 107.6 108.6)
		(size 0.45)
		(drill 0.2)
		(layers "F.Cu" "B.Cu")
		(net 42)
	)
	(via
		(at 116.18 113.37)
		(size 0.45)
		(drill 0.2)
		(layers "F.Cu" "B.Cu")
		(remove_unused_layers yes)
		(keep_end_layers yes)
		(zone_layer_connections)
		(net 42)
	)
	(segment
		(start 112.37 113.37)
		(end 116.18 113.37)
		(width 0.15)
		(layer "B.Cu")
		(net 42)
	)
	(segment
		(start 107.6 108.6)
		(end 112.37 113.37)
		(width 0.15)
		(layer "B.Cu")
		(net 42)
	)
	(segment
		(start 158.275 120.725)
		(end 158.275 118.325)
		(width 0.15)
		(layer "F.Cu")
		(net 43)
	)
	(segment
		(start 158.25 120.75)
		(end 158.275 120.725)
		(width 0.15)
		(layer "F.Cu")
		(net 43)
	)
	(segment
		(start 125.09 90.7)
		(end 124.69 91.1)
		(width 0.15)
		(layer "F.Cu")
		(net 43)
	)
	(via
		(at 158.25 120.75)
		(size 0.45)
		(drill 0.2)
		(layers "F.Cu" "B.Cu")
		(remove_unused_layers yes)
		(keep_end_layers yes)
		(zone_layer_connections)
		(net 43)
	)
	(via
		(at 124.69 91.1)
		(size 0.45)
		(drill 0.2)
		(layers "F.Cu" "B.Cu")
		(remove_unused_layers yes)
		(keep_end_layers yes)
		(free yes)
		(zone_layer_connections)
		(net 43)
	)
	(segment
		(start 121.5 92.9)
		(end 120.4 94)
		(width 0.125)
		(layer "B.Cu")
		(net 43)
	)
	(segment
		(start 122.9 91.5)
		(end 122.687499 91.712501)
		(width 0.125)
		(layer "B.Cu")
		(net 43)
	)
	(segment
		(start 122 92.9)
		(end 121.5 92.9)
		(width 0.125)
		(layer "B.Cu")
		(net 43)
	)
	(segment
		(start 132.09 117.11)
		(end 125.29 110.31)
		(width 0.15)
		(layer "B.Cu")
		(net 43)
	)
	(segment
		(start 120.4 105.1)
		(end 120.2 105.3)
		(width 0.125)
		(layer "B.Cu")
		(net 43)
	)
	(segment
		(start 158.25 120.75)
		(end 157.5 121.5)
		(width 0.15)
		(layer "B.Cu")
		(net 43)
	)
	(segment
		(start 120.2 105.3)
		(end 120.2 105.6)
		(width 0.125)
		(layer "B.Cu")
		(net 43)
	)
	(segment
		(start 132.09 117.11)
		(end 135.845 120.865)
		(width 0.125)
		(layer "B.Cu")
		(net 43)
	)
	(segment
		(start 124.69 91.1)
		(end 124.69 91.11)
		(width 0.125)
		(layer "B.Cu")
		(net 43)
	)
	(segment
		(start 124.91 110.31)
		(end 125.29 110.31)
		(width 0.125)
		(layer "B.Cu")
		(net 43)
	)
	(segment
		(start 122.687499 91.712501)
		(end 122.687499 92.212501)
		(width 0.125)
		(layer "B.Cu")
		(net 43)
	)
	(segment
		(start 137.87 121.5)
		(end 137.235 120.865)
		(width 0.15)
		(layer "B.Cu")
		(net 43)
	)
	(segment
		(start 124.69 91.11)
		(end 124.3 91.5)
		(width 0.125)
		(layer "B.Cu")
		(net 43)
	)
	(segment
		(start 122.687499 92.212501)
		(end 122 92.9)
		(width 0.125)
		(layer "B.Cu")
		(net 43)
	)
	(segment
		(start 122.9 91.5)
		(end 124.3 91.5)
		(width 0.125)
		(layer "B.Cu")
		(net 43)
	)
	(segment
		(start 120.2 105.6)
		(end 124.91 110.31)
		(width 0.125)
		(layer "B.Cu")
		(net 43)
	)
	(segment
		(start 120.4 94)
		(end 120.4 105.1)
		(width 0.125)
		(layer "B.Cu")
		(net 43)
	)
	(segment
		(start 135.845 120.865)
		(end 137.235 120.865)
		(width 0.125)
		(layer "B.Cu")
		(net 43)
	)
	(segment
		(start 157.5 121.5)
		(end 137.87 121.5)
		(width 0.15)
		(layer "B.Cu")
		(net 43)
	)
	(segment
		(start 159.25 121)
		(end 159.25 118.2)
		(width 0.15)
		(layer "F.Cu")
		(net 44)
	)
	(via
		(at 159.25 121)
		(size 0.45)
		(drill 0.2)
		(layers "F.Cu" "B.Cu")
		(remove_unused_layers yes)
		(keep_end_layers yes)
		(zone_layer_connections)
		(net 44)
	)
	(via
		(at 121 92.3005)
		(size 0.45)
		(drill 0.2)
		(layers "F.Cu" "B.Cu")
		(remove_unused_layers yes)
		(keep_end_layers yes)
		(free yes)
		(zone_layer_connections)
		(net 44)
	)
	(segment
		(start 120.18 106.43)
		(end 119.6 105.85)
		(width 0.125)
		(layer "B.Cu")
		(net 44)
	)
	(segment
		(start 119.6 93.7005)
		(end 121 92.3005)
		(width 0.125)
		(layer "B.Cu")
		(net 44)
	)
	(segment
		(start 125.29 110.75)
		(end 126.11 111.57)
		(width 0.15)
		(layer "B.Cu")
		(net 44)
	)
	(segment
		(start 126.11 111.57)
		(end 126.11 112.2)
		(width 0.15)
		(layer "B.Cu")
		(net 44)
	)
	(segment
		(start 120.18 106.43)
		(end 124.5 110.75)
		(width 0.15)
		(layer "B.Cu")
		(net 44)
	)
	(segment
		(start 135.91 122)
		(end 158.25 122)
		(width 0.15)
		(layer "B.Cu")
		(net 44)
	)
	(segment
		(start 158.25 122)
		(end 159.25 121)
		(width 0.15)
		(layer "B.Cu")
		(net 44)
	)
	(segment
		(start 126.11 112.2)
		(end 135.91 122)
		(width 0.15)
		(layer "B.Cu")
		(net 44)
	)
	(segment
		(start 124.5 110.75)
		(end 125.29 110.75)
		(width 0.15)
		(layer "B.Cu")
		(net 44)
	)
	(segment
		(start 119.6 105.85)
		(end 119.6 93.7005)
		(width 0.125)
		(layer "B.Cu")
		(net 44)
	)
	(segment
		(start 95.03 84.54)
		(end 96.1 83.47)
		(width 0.15)
		(layer "F.Cu")
		(net 45)
	)
	(segment
		(start 95.225 89.13)
		(end 95.225 86.855)
		(width 0.3)
		(layer "F.Cu")
		(net 45)
	)
	(segment
		(start 96.1 83.47)
		(end 96.1 82.4)
		(width 0.15)
		(layer "F.Cu")
		(net 45)
	)
	(segment
		(start 95.03 86.8)
		(end 95.03 84.54)
		(width 0.15)
		(layer "F.Cu")
		(net 45)
	)
	(segment
		(start 97.61 84.08)
		(end 97.61 82.2)
		(width 0.15)
		(layer "F.Cu")
		(net 46)
	)
	(segment
		(start 98.5 84.97)
		(end 97.61 84.08)
		(width 0.15)
		(layer "F.Cu")
		(net 46)
	)
	(segment
		(start 97.61 82.2)
		(end 97.34 81.93)
		(width 0.15)
		(layer "F.Cu")
		(net 46)
	)
	(segment
		(start 96.34 81.4)
		(end 96.1 81.4)
		(width 0.15)
		(layer "F.Cu")
		(net 46)
	)
	(segment
		(start 97.34 81.93)
		(end 96.87 81.93)
		(width 0.15)
		(layer "F.Cu")
		(net 46)
	)
	(segment
		(start 96.87 81.93)
		(end 96.34 81.4)
		(width 0.15)
		(layer "F.Cu")
		(net 46)
	)
	(segment
		(start 98.5 84.97)
		(end 98.5 85.83)
		(width 0.15)
		(layer "F.Cu")
		(net 46)
	)
	(segment
		(start 100.98 86.945)
		(end 99.615 86.945)
		(width 0.3)
		(layer "F.Cu")
		(net 46)
	)
	(segment
		(start 90.285 94.0168)
		(end 94.875 98.6068)
		(width 0.15)
		(layer "F.Cu")
		(net 47)
	)
	(segment
		(start 90.285 84.3532)
		(end 90.285 94.0168)
		(width 0.15)
		(layer "F.Cu")
		(net 47)
	)
	(segment
		(start 93.7232 106.725)
		(end 91.4 106.725)
		(width 0.15)
		(layer "F.Cu")
		(net 47)
	)
	(segment
		(start 94.875 105.5732)
		(end 93.7232 106.725)
		(width 0.15)
		(layer "F.Cu")
		(net 47)
	)
	(segment
		(start 91.1 81.4)
		(end 91.55 81.85)
		(width 0.15)
		(layer "F.Cu")
		(net 47)
	)
	(segment
		(start 94.875 98.6068)
		(end 94.875 105.5732)
		(width 0.15)
		(layer "F.Cu")
		(net 47)
	)
	(segment
		(start 91.4 106.725)
		(end 91.3 106.825)
		(width 0.15)
		(layer "F.Cu")
		(net 47)
	)
	(segment
		(start 91.55 83.0882)
		(end 90.285 84.3532)
		(width 0.15)
		(layer "F.Cu")
		(net 47)
	)
	(segment
		(start 91.3 106.825)
		(end 90.975 106.825)
		(width 0.15)
		(layer "F.Cu")
		(net 47)
	)
	(segment
		(start 91.55 81.85)
		(end 91.55 83.0882)
		(width 0.15)
		(layer "F.Cu")
		(net 47)
	)
	(segment
		(start 89.835 91.975)
		(end 89.9342 91.975)
		(width 0.15)
		(layer "F.Cu")
		(net 48)
	)
	(segment
		(start 89.835 91.9742)
		(end 89.835 91.975)
		(width 0.15)
		(layer "F.Cu")
		(net 48)
	)
	(segment
		(start 89.2366 91.6734)
		(end 89.2366 91.675)
		(width 0.15)
		(layer "F.Cu")
		(net 48)
	)
	(segment
		(start 93.5368 106.275)
		(end 91.4 106.275)
		(width 0.15)
		(layer "F.Cu")
		(net 48)
	)
	(segment
		(start 89.5358 91.9742)
		(end 89.835 91.9742)
		(width 0.15)
		(layer "F.Cu")
		(net 48)
	)
	(segment
		(start 91.1 82.4)
		(end 91.1 82.9018)
		(width 0.15)
		(layer "F.Cu")
		(net 48)
	)
	(segment
		(start 89.835 92.575)
		(end 89.5358 92.575)
		(width 0.15)
		(layer "F.Cu")
		(net 48)
	)
	(segment
		(start 91.3 106.175)
		(end 90.975 106.175)
		(width 0.15)
		(layer "F.Cu")
		(net 48)
	)
	(segment
		(start 94.425 98.7932)
		(end 94.425 105.3868)
		(width 0.15)
		(layer "F.Cu")
		(net 48)
	)
	(segment
		(start 90.0334 92.0742)
		(end 90.0334 92.4758)
		(width 0.15)
		(layer "F.Cu")
		(net 48)
	)
	(segment
		(start 91.1 82.9018)
		(end 89.835 84.1668)
		(width 0.15)
		(layer "F.Cu")
		(net 48)
	)
	(segment
		(start 89.835 84.1668)
		(end 89.835 91.075)
		(width 0.15)
		(layer "F.Cu")
		(net 48)
	)
	(segment
		(start 89.9342 92.575)
		(end 89.835 92.575)
		(width 0.15)
		(layer "F.Cu")
		(net 48)
	)
	(segment
		(start 89.835 94.2032)
		(end 94.425 98.7932)
		(width 0.15)
		(layer "F.Cu")
		(net 48)
	)
	(segment
		(start 89.835 93.4742)
		(end 89.835 94.2032)
		(width 0.15)
		(layer "F.Cu")
		(net 48)
	)
	(segment
		(start 94.425 105.3868)
		(end 93.5368 106.275)
		(width 0.15)
		(layer "F.Cu")
		(net 48)
	)
	(segment
		(start 89.2366 92.8742)
		(end 89.2366 92.8758)
		(width 0.15)
		(layer "F.Cu")
		(net 48)
	)
	(segment
		(start 91.4 106.275)
		(end 91.3 106.175)
		(width 0.15)
		(layer "F.Cu")
		(net 48)
	)
	(arc
		(start 89.835 91.075)
		(mid 89.747366 91.286566)
		(end 89.5358 91.3742)
		(width 0.15)
		(layer "F.Cu")
		(net 48)
	)
	(arc
		(start 89.9342 91.975)
		(mid 90.004345 92.004055)
		(end 90.0334 92.0742)
		(width 0.15)
		(layer "F.Cu")
		(net 48)
	)
	(arc
		(start 90.0334 92.4758)
		(mid 90.004345 92.545945)
		(end 89.9342 92.575)
		(width 0.15)
		(layer "F.Cu")
		(net 48)
	)
	(arc
		(start 89.2366 91.675)
		(mid 89.324234 91.886566)
		(end 89.5358 91.9742)
		(width 0.15)
		(layer "F.Cu")
		(net 48)
	)
	(arc
		(start 89.5358 91.3742)
		(mid 89.324234 91.461834)
		(end 89.2366 91.6734)
		(width 0.15)
		(layer "F.Cu")
		(net 48)
	)
	(arc
		(start 89.2366 92.8758)
		(mid 89.324234 93.087366)
		(end 89.5358 93.175)
		(width 0.15)
		(layer "F.Cu")
		(net 48)
	)
	(arc
		(start 89.5358 92.575)
		(mid 89.324234 92.662634)
		(end 89.2366 92.8742)
		(width 0.15)
		(layer "F.Cu")
		(net 48)
	)
	(arc
		(start 89.5358 93.175)
		(mid 89.747366 93.262634)
		(end 89.835 93.4742)
		(width 0.15)
		(layer "F.Cu")
		(net 48)
	)
	(segment
		(start 137.69 105.45)
		(end 137.69 105.0008)
		(width 0.3)
		(layer "F.Cu")
		(net 49)
	)
	(segment
		(start 137.69 105.0008)
		(end 137.1392 104.45)
		(width 0.3)
		(layer "F.Cu")
		(net 49)
	)
	(via
		(at 151.368556 107.288556)
		(size 0.45)
		(drill 0.2)
		(layers "F.Cu" "B.Cu")
		(remove_unused_layers yes)
		(keep_end_layers yes)
		(zone_layer_connections)
		(net 49)
	)
	(via
		(at 135.64 99.25)
		(size 0.45)
		(drill 0.2)
		(layers "F.Cu" "B.Cu")
		(remove_unused_layers yes)
		(keep_end_layers yes)
		(free yes)
		(zone_layer_connections "In6.Cu")
		(net 49)
	)
	(via
		(at 137.69 105.45)
		(size 0.45)
		(drill 0.2)
		(layers "F.Cu" "B.Cu")
		(remove_unused_layers yes)
		(keep_end_layers yes)
		(free yes)
		(zone_layer_connections "In6.Cu")
		(net 49)
	)
	(via
		(at 135.04 99.55)
		(size 0.45)
		(drill 0.2)
		(layers "F.Cu" "B.Cu")
		(remove_unused_layers yes)
		(keep_end_layers yes)
		(free yes)
		(zone_layer_connections "In6.Cu")
		(net 49)
	)
	(via
		(at 132.84 99.2)
		(size 0.45)
		(drill 0.2)
		(layers "F.Cu" "B.Cu")
		(remove_unused_layers yes)
		(keep_end_layers yes)
		(free yes)
		(zone_layer_connections "In6.Cu")
		(net 49)
	)
	(via
		(at 137.19 106.95)
		(size 0.45)
		(drill 0.2)
		(layers "F.Cu" "B.Cu")
		(remove_unused_layers yes)
		(keep_end_layers yes)
		(free yes)
		(zone_layer_connections "In6.Cu")
		(net 49)
	)
	(via
		(at 133.29 99.8)
		(size 0.45)
		(drill 0.2)
		(layers "F.Cu" "B.Cu")
		(remove_unused_layers yes)
		(keep_end_layers yes)
		(free yes)
		(zone_layer_connections "In6.Cu")
		(net 49)
	)
	(via
		(at 132.54 99.85)
		(size 0.45)
		(drill 0.2)
		(layers "F.Cu" "B.Cu")
		(remove_unused_layers yes)
		(keep_end_layers yes)
		(free yes)
		(zone_layer_connections "In6.Cu")
		(net 49)
	)
	(via
		(at 137.69 106.45)
		(size 0.45)
		(drill 0.2)
		(layers "F.Cu" "B.Cu")
		(remove_unused_layers yes)
		(keep_end_layers yes)
		(free yes)
		(zone_layer_connections "In6.Cu")
		(net 49)
	)
	(via
		(at 130.99 99.15)
		(size 0.45)
		(drill 0.2)
		(layers "F.Cu" "B.Cu")
		(remove_unused_layers yes)
		(keep_end_layers yes)
		(free yes)
		(zone_layer_connections "In6.Cu")
		(net 49)
	)
	(via
		(at 135.64 99.9)
		(size 0.45)
		(drill 0.2)
		(layers "F.Cu" "B.Cu")
		(remove_unused_layers yes)
		(keep_end_layers yes)
		(free yes)
		(zone_layer_connections "In6.Cu")
		(net 49)
	)
	(via
		(at 137.19 105.95)
		(size 0.45)
		(drill 0.2)
		(layers "F.Cu" "B.Cu")
		(remove_unused_layers yes)
		(keep_end_layers yes)
		(free yes)
		(zone_layer_connections "In6.Cu")
		(net 49)
	)
	(segment
		(start 151.368556 107.211444)
		(end 153.93 104.65)
		(width 0.15)
		(layer "B.Cu")
		(net 49)
	)
	(segment
		(start 151.368556 107.288556)
		(end 151.368556 107.211444)
		(width 0.15)
		(layer "B.Cu")
		(net 49)
	)
	(segment
		(start 153.93 104.65)
		(end 154.6675 104.65)
		(width 0.15)
		(layer "B.Cu")
		(net 49)
	)
	(segment
		(start 148.53 105.45)
		(end 137.69 105.45)
		(width 0.15)
		(layer "In2.Cu")
		(net 49)
	)
	(segment
		(start 150.368556 107.288556)
		(end 148.53 105.45)
		(width 0.15)
		(layer "In2.Cu")
		(net 49)
	)
	(segment
		(start 151.368556 107.288556)
		(end 150.368556 107.288556)
		(width 0.15)
		(layer "In2.Cu")
		(net 49)
	)
	(segment
		(start 137.69 111.9)
		(end 136.3392 111.9)
		(width 0.3)
		(layer "F.Cu")
		(net 50)
	)
	(segment
		(start 137.79 112)
		(end 137.69 111.9)
		(width 0.3)
		(layer "F.Cu")
		(net 50)
	)
	(via
		(at 150.525175 102.054825)
		(size 0.45)
		(drill 0.2)
		(layers "F.Cu" "B.Cu")
		(remove_unused_layers yes)
		(keep_end_layers yes)
		(zone_layer_connections)
		(net 50)
	)
	(via
		(at 138.74 96.95)
		(size 0.45)
		(drill 0.2)
		(layers "F.Cu" "B.Cu")
		(remove_unused_layers yes)
		(keep_end_layers yes)
		(free yes)
		(zone_layer_connections "In6.Cu")
		(net 50)
	)
	(via
		(at 138.2 89.8)
		(size 0.45)
		(drill 0.2)
		(layers "F.Cu" "B.Cu")
		(net 50)
	)
	(via
		(at 137.29 113.5)
		(size 0.45)
		(drill 0.2)
		(layers "F.Cu" "B.Cu")
		(remove_unused_layers yes)
		(keep_end_layers yes)
		(free yes)
		(zone_layer_connections "In6.Cu")
		(net 50)
	)
	(via
		(at 138.2 89.1)
		(size 0.45)
		(drill 0.2)
		(layers "F.Cu" "B.Cu")
		(free yes)
		(net 50)
	)
	(via
		(at 138.74 96)
		(size 0.45)
		(drill 0.2)
		(layers "F.Cu" "B.Cu")
		(remove_unused_layers yes)
		(keep_end_layers yes)
		(free yes)
		(zone_layer_connections "In6.Cu")
		(net 50)
	)
	(via
		(at 136.98 88.17)
		(size 0.45)
		(drill 0.2)
		(layers "F.Cu" "B.Cu")
		(free yes)
		(net 50)
	)
	(via
		(at 137.19 112.5)
		(size 0.45)
		(drill 0.2)
		(layers "F.Cu" "B.Cu")
		(remove_unused_layers yes)
		(keep_end_layers yes)
		(free yes)
		(zone_layer_connections "In6.Cu")
		(net 50)
	)
	(via
		(at 137.79 112)
		(size 0.45)
		(drill 0.2)
		(layers "F.Cu" "B.Cu")
		(remove_unused_layers yes)
		(keep_end_layers yes)
		(free yes)
		(zone_layer_connections "In6.Cu")
		(net 50)
	)
	(via
		(at 137.79 113)
		(size 0.45)
		(drill 0.2)
		(layers "F.Cu" "B.Cu")
		(remove_unused_layers yes)
		(keep_end_layers yes)
		(free yes)
		(zone_layer_connections "In6.Cu")
		(net 50)
	)
	(via
		(at 139.39 96.45)
		(size 0.45)
		(drill 0.2)
		(layers "F.Cu" "B.Cu")
		(remove_unused_layers yes)
		(keep_end_layers yes)
		(free yes)
		(zone_layer_connections "In6.Cu")
		(net 50)
	)
	(via
		(at 137.32 87.76)
		(size 0.45)
		(drill 0.2)
		(layers "F.Cu" "B.Cu")
		(free yes)
		(net 50)
	)
	(segment
		(start 151.82035 103.35)
		(end 150.525175 102.054825)
		(width 0.15)
		(layer "B.Cu")
		(net 50)
	)
	(segment
		(start 154.6675 103.35)
		(end 151.82035 103.35)
		(width 0.15)
		(layer "B.Cu")
		(net 50)
	)
	(segment
		(start 150.525175 102.054825)
		(end 150.525175 101.792626)
		(width 0.15)
		(layer "In2.Cu")
		(net 50)
	)
	(segment
		(start 150.525175 101.792626)
		(end 142.582549 93.85)
		(width 0.15)
		(layer "In2.Cu")
		(net 50)
	)
	(segment
		(start 138.2 92.4)
		(end 138.2 89.8)
		(width 0.15)
		(layer "In2.Cu")
		(net 50)
	)
	(segment
		(start 138.2 92.4)
		(end 139.65 93.85)
		(width 0.15)
		(layer "In2.Cu")
		(net 50)
	)
	(segment
		(start 139.65 93.85)
		(end 142.582549 93.85)
		(width 0.15)
		(layer "In2.Cu")
		(net 50)
	)
	(segment
		(start 168.595 96.895)
		(end 168.3 96.6)
		(width 0.15)
		(layer "F.Cu")
		(net 56)
	)
	(segment
		(start 169.6 96.895)
		(end 168.595 96.895)
		(width 0.15)
		(layer "F.Cu")
		(net 56)
	)
	(segment
		(start 168.3 96.6)
		(end 167.685 96.6)
		(width 0.15)
		(layer "F.Cu")
		(net 56)
	)
	(segment
		(start 165.575 70.335)
		(end 164.79 69.55)
		(width 0.3)
		(layer "F.Cu")
		(net 58)
	)
	(segment
		(start 166.09 70.335)
		(end 165.575 70.335)
		(width 0.3)
		(layer "F.Cu")
		(net 58)
	)
	(segment
		(start 166.09 70.335)
		(end 166.09 71.69)
		(width 0.15)
		(layer "F.Cu")
		(net 58)
	)
	(segment
		(start 166.09 71.69)
		(end 165.83 71.95)
		(width 0.15)
		(layer "F.Cu")
		(net 58)
	)
	(via
		(at 165.83 71.95)
		(size 0.45)
		(drill 0.2)
		(layers "F.Cu" "B.Cu")
		(remove_unused_layers yes)
		(keep_end_layers yes)
		(zone_layer_connections)
		(net 58)
	)
	(via
		(at 160.3925 100.35)
		(size 0.45)
		(drill 0.2)
		(layers "F.Cu" "B.Cu")
		(remove_unused_layers yes)
		(keep_end_layers yes)
		(zone_layer_connections)
		(net 58)
	)
	(segment
		(start 154.6675 100.2875)
		(end 160.3925 100.2875)
		(width 0.3)
		(layer "B.Cu")
		(net 58)
	)
	(segment
		(start 160.3925 100.2875)
		(end 160.3925 100.35)
		(width 0.3)
		(layer "B.Cu")
		(net 58)
	)
	(segment
		(start 160.3925 100.35)
		(end 160.3925 102.05)
		(width 0.3)
		(layer "B.Cu")
		(net 58)
	)
	(segment
		(start 154.6675 100.2875)
		(end 154.6675 98.45)
		(width 0.3)
		(layer "B.Cu")
		(net 58)
	)
	(segment
		(start 154.6675 102.05)
		(end 154.6675 100.2875)
		(width 0.3)
		(layer "B.Cu")
		(net 58)
	)
	(segment
		(start 160.3925 99.1)
		(end 160.3925 100.2875)
		(width 0.3)
		(layer "B.Cu")
		(net 58)
	)
	(segment
		(start 163.63 81.95)
		(end 162.46 80.78)
		(width 0.15)
		(layer "In2.Cu")
		(net 58)
	)
	(segment
		(start 163.63 97.75)
		(end 163.63 81.95)
		(width 0.15)
		(layer "In2.Cu")
		(net 58)
	)
	(segment
		(start 162.46 80.78)
		(end 162.46 73.54)
		(width 0.15)
		(layer "In2.Cu")
		(net 58)
	)
	(segment
		(start 161.0925 100.2875)
		(end 163.63 97.75)
		(width 0.15)
		(layer "In2.Cu")
		(net 58)
	)
	(segment
		(start 162.46 73.54)
		(end 163.22 72.78)
		(width 0.15)
		(layer "In2.Cu")
		(net 58)
	)
	(segment
		(start 160.3925 100.2875)
		(end 161.0925 100.2875)
		(width 0.15)
		(layer "In2.Cu")
		(net 58)
	)
	(segment
		(start 165 72.78)
		(end 165.83 71.95)
		(width 0.15)
		(layer "In2.Cu")
		(net 58)
	)
	(segment
		(start 163.22 72.78)
		(end 165 72.78)
		(width 0.15)
		(layer "In2.Cu")
		(net 58)
	)
	(segment
		(start 131.39 56.77)
		(end 131.46 56.7)
		(width 0.5)
		(layer "F.Cu")
		(net 60)
	)
	(segment
		(start 131.46 56.7)
		(end 134.43 56.7)
		(width 0.5)
		(layer "F.Cu")
		(net 60)
	)
	(via
		(at 131.39 56.77)
		(size 0.45)
		(drill 0.2)
		(layers "F.Cu" "B.Cu")
		(remove_unused_layers yes)
		(keep_end_layers yes)
		(zone_layer_connections)
		(net 60)
	)
	(segment
		(start 131.76 57.14)
		(end 132.135 57.14)
		(width 0.5)
		(layer "B.Cu")
		(net 60)
	)
	(segment
		(start 131.39 56.77)
		(end 131.27 56.65)
		(width 0.5)
		(layer "B.Cu")
		(net 60)
	)
	(segment
		(start 131.27 56.65)
		(end 130.51 56.65)
		(width 0.5)
		(layer "B.Cu")
		(net 60)
	)
	(segment
		(start 131.39 56.77)
		(end 131.76 57.14)
		(width 0.5)
		(layer "B.Cu")
		(net 60)
	)
	(segment
		(start 161.49 70.335)
		(end 162.005 70.335)
		(width 0.3)
		(layer "F.Cu")
		(net 62)
	)
	(segment
		(start 162.005 70.335)
		(end 162.79 69.55)
		(width 0.3)
		(layer "F.Cu")
		(net 62)
	)
	(segment
		(start 165.63 118.4)
		(end 165.63 117.05)
		(width 0.2)
		(layer "F.Cu")
		(net 63)
	)
	(segment
		(start 162.83 118.4)
		(end 162.83 117.05)
		(width 0.2)
		(layer "F.Cu")
		(net 64)
	)
	(segment
		(start 145.59 57.95)
		(end 145.59 57.015)
		(width 0.3)
		(layer "F.Cu")
		(net 65)
	)
	(segment
		(start 145.59 57.015)
		(end 145.225 56.65)
		(width 0.3)
		(layer "F.Cu")
		(net 65)
	)
	(segment
		(start 127.75 109.35)
		(end 127.3 108.9)
		(width 0.15)
		(layer "F.Cu")
		(net 66)
	)
	(segment
		(start 125.48 114.7)
		(end 126.965 113.215)
		(width 0.15)
		(layer "F.Cu")
		(net 66)
	)
	(segment
		(start 126.965 113.215)
		(end 126.965 111.535)
		(width 0.15)
		(layer "F.Cu")
		(net 66)
	)
	(segment
		(start 125.03 114.7)
		(end 125.48 114.7)
		(width 0.15)
		(layer "F.Cu")
		(net 66)
	)
	(segment
		(start 126.965 111.535)
		(end 127.75 110.75)
		(width 0.15)
		(layer "F.Cu")
		(net 66)
	)
	(segment
		(start 127.75 110.75)
		(end 127.75 109.35)
		(width 0.15)
		(layer "F.Cu")
		(net 66)
	)
	(segment
		(start 124.5 111.5)
		(end 125.6 110.4)
		(width 0.15)
		(layer "F.Cu")
		(net 67)
	)
	(segment
		(start 123 111.5)
		(end 124.5 111.5)
		(width 0.15)
		(layer "F.Cu")
		(net 67)
	)
	(segment
		(start 125.6 110.4)
		(end 127 110.4)
		(width 0.15)
		(layer "F.Cu")
		(net 67)
	)
	(segment
		(start 122.515 111.985)
		(end 123 111.5)
		(width 0.15)
		(layer "F.Cu")
		(net 67)
	)
	(segment
		(start 132.48 95.9)
		(end 133.027 96.447)
		(width 0.15)
		(layer "F.Cu")
		(net 68)
	)
	(segment
		(start 137.625057 95.534455)
		(end 137.52928 95.630232)
		(width 0.15)
		(layer "F.Cu")
		(net 68)
	)
	(segment
		(start 131.9 95.9)
		(end 132.48 95.9)
		(width 0.15)
		(layer "F.Cu")
		(net 68)
	)
	(segment
		(start 166.284 113.863)
		(end 166.15 113.997)
		(width 0.15)
		(layer "F.Cu")
		(net 68)
	)
	(segment
		(start 136.246512 97.793)
		(end 133.893488 97.793)
		(width 0.15)
		(layer "F.Cu")
		(net 68)
	)
	(segment
		(start 168.891512 112.378)
		(end 167.406512 113.863)
		(width 0.15)
		(layer "F.Cu")
		(net 68)
	)
	(segment
		(start 137.52928 96.510232)
		(end 136.246512 97.793)
		(width 0.15)
		(layer "F.Cu")
		(net 68)
	)
	(segment
		(start 137.684455 95.534455)
		(end 137.625057 95.534455)
		(width 0.15)
		(layer "F.Cu")
		(net 68)
	)
	(segment
		(start 167.406512 113.863)
		(end 166.284 113.863)
		(width 0.15)
		(layer "F.Cu")
		(net 68)
	)
	(segment
		(start 133.893488 97.793)
		(end 133.027 96.926512)
		(width 0.15)
		(layer "F.Cu")
		(net 68)
	)
	(segment
		(start 137.52928 95.630232)
		(end 137.52928 96.510232)
		(width 0.15)
		(layer "F.Cu")
		(net 68)
	)
	(segment
		(start 131.5 95.5)
		(end 131.9 95.9)
		(width 0.15)
		(layer "F.Cu")
		(net 68)
	)
	(segment
		(start 169.133 112.378)
		(end 168.891512 112.378)
		(width 0.15)
		(layer "F.Cu")
		(net 68)
	)
	(segment
		(start 133.027 96.926512)
		(end 133.027 96.447)
		(width 0.15)
		(layer "F.Cu")
		(net 68)
	)
	(via
		(at 166.15 113.997)
		(size 0.45)
		(drill 0.2)
		(layers "F.Cu" "B.Cu")
		(remove_unused_layers yes)
		(keep_end_layers yes)
		(zone_layer_connections)
		(net 68)
	)
	(via
		(at 137.684455 95.534455)
		(size 0.45)
		(drill 0.2)
		(layers "F.Cu" "B.Cu")
		(remove_unused_layers yes)
		(keep_end_layers yes)
		(zone_layer_connections)
		(net 68)
	)
	(segment
		(start 147.378979 101.107938)
		(end 147.546915 100.939999)
		(width 0.168)
		(layer "In4.Cu")
		(net 68)
	)
	(segment
		(start 137.684455 95.481421)
		(end 138.028376 95.1375)
		(width 0.168)
		(layer "In4.Cu")
		(net 68)
	)
	(segment
		(start 150.38312 103.511039)
		(end 150.383119 103.511037)
		(width 0.168)
		(layer "In4.Cu")
		(net 68)
	)
	(segment
		(start 150.899659 105.565535)
		(end 150.899661 105.565536)
		(width 0.168)
		(layer "In4.Cu")
		(net 68)
	)
	(segment
		(start 147.81208 100.939998)
		(end 147.812081 100.94)
		(width 0.168)
		(layer "In4.Cu")
		(net 68)
	)
	(segment
		(start 148.496559 101.889643)
		(end 147.559643 102.82656)
		(width 0.168)
		(layer "In4.Cu")
		(net 68)
	)
	(segment
		(start 150.899661 105.565536)
		(end 159.201624 113.8675)
		(width 0.168)
		(layer "In4.Cu")
		(net 68)
	)
	(segment
		(start 159.201624 113.8675)
		(end 166.0205 113.8675)
		(width 0.168)
		(layer "In4.Cu")
		(net 68)
	)
	(segment
		(start 147.812081 100.94)
		(end 148.49656 101.624479)
		(width 0.168)
		(layer "In4.Cu")
		(net 68)
	)
	(segment
		(start 149.181038 104.447955)
		(end 150.117955 103.511038)
		(width 0.168)
		(layer "In4.Cu")
		(net 68)
	)
	(segment
		(start 147.559644 103.763477)
		(end 147.559643 103.763476)
		(width 0.168)
		(layer "In4.Cu")
		(net 68)
	)
	(segment
		(start 138.028376 95.1375)
		(end 140.471624 95.1375)
		(width 0.168)
		(layer "In4.Cu")
		(net 68)
	)
	(segment
		(start 150.383119 103.511037)
		(end 151.067598 104.195516)
		(width 0.168)
		(layer "In4.Cu")
		(net 68)
	)
	(segment
		(start 140.471624 95.1375)
		(end 146.442061 101.107936)
		(width 0.168)
		(layer "In4.Cu")
		(net 68)
	)
	(segment
		(start 151.067597 104.460681)
		(end 151.067599 104.460682)
		(width 0.168)
		(layer "In4.Cu")
		(net 68)
	)
	(segment
		(start 147.559643 103.763476)
		(end 148.244122 104.447955)
		(width 0.168)
		(layer "In4.Cu")
		(net 68)
	)
	(segment
		(start 166.0205 113.8675)
		(end 166.15 113.997)
		(width 0.168)
		(layer "In4.Cu")
		(net 68)
	)
	(segment
		(start 148.496559 101.889644)
		(end 148.496559 101.889643)
		(width 0.168)
		(layer "In4.Cu")
		(net 68)
	)
	(segment
		(start 151.067599 104.460682)
		(end 150.89966 104.628618)
		(width 0.168)
		(layer "In4.Cu")
		(net 68)
	)
	(segment
		(start 137.684455 95.534455)
		(end 137.684455 95.481421)
		(width 0.168)
		(layer "In4.Cu")
		(net 68)
	)
	(arc
		(start 147.546915 100.939999)
		(mid 147.679497 100.885081)
		(end 147.81208 100.939998)
		(width 0.168)
		(layer "In4.Cu")
		(net 68)
	)
	(arc
		(start 148.49656 101.624479)
		(mid 148.551477 101.757062)
		(end 148.496559 101.889644)
		(width 0.168)
		(layer "In4.Cu")
		(net 68)
	)
	(arc
		(start 150.89966 104.628618)
		(mid 150.705618 105.097076)
		(end 150.899659 105.565535)
		(width 0.168)
		(layer "In4.Cu")
		(net 68)
	)
	(arc
		(start 147.559643 102.82656)
		(mid 147.365602 103.295019)
		(end 147.559644 103.763477)
		(width 0.168)
		(layer "In4.Cu")
		(net 68)
	)
	(arc
		(start 148.244122 104.447955)
		(mid 148.71258 104.641997)
		(end 149.181038 104.447955)
		(width 0.168)
		(layer "In4.Cu")
		(net 68)
	)
	(arc
		(start 146.442061 101.107936)
		(mid 146.910521 101.30198)
		(end 147.378979 101.107938)
		(width 0.168)
		(layer "In4.Cu")
		(net 68)
	)
	(arc
		(start 151.067598 104.195516)
		(mid 151.122515 104.328099)
		(end 151.067597 104.460681)
		(width 0.168)
		(layer "In4.Cu")
		(net 68)
	)
	(arc
		(start 150.117955 103.511038)
		(mid 150.250538 103.456121)
		(end 150.38312 103.511039)
		(width 0.168)
		(layer "In4.Cu")
		(net 68)
	)
	(segment
		(start 136.053488 97.327)
		(end 134.086512 97.327)
		(width 0.15)
		(layer "F.Cu")
		(net 69)
	)
	(segment
		(start 137.295545 95.145545)
		(end 137.295545 95.204943)
		(width 0.15)
		(layer "F.Cu")
		(net 69)
	)
	(segment
		(start 133.493 96.733488)
		(end 133.493 96.303)
		(width 0.15)
		(layer "F.Cu")
		(net 69)
	)
	(segment
		(start 167.213488 113.397)
		(end 166.284 113.397)
		(width 0.15)
		(layer "F.Cu")
		(net 69)
	)
	(segment
		(start 133.493 96.303)
		(end 132.69 95.5)
		(width 0.15)
		(layer "F.Cu")
		(net 69)
	)
	(segment
		(start 137.06328 96.317208)
		(end 136.053488 97.327)
		(width 0.15)
		(layer "F.Cu")
		(net 69)
	)
	(segment
		(start 166.284 113.397)
		(end 166.15 113.263)
		(width 0.15)
		(layer "F.Cu")
		(net 69)
	)
	(segment
		(start 132.69 95.5)
		(end 132.3 95.5)
		(width 0.15)
		(layer "F.Cu")
		(net 69)
	)
	(segment
		(start 137.295545 95.204943)
		(end 137.06328 95.437208)
		(width 0.15)
		(layer "F.Cu")
		(net 69)
	)
	(segment
		(start 168.698488 111.912)
		(end 167.213488 113.397)
		(width 0.15)
		(layer "F.Cu")
		(net 69)
	)
	(segment
		(start 169.133 111.912)
		(end 168.698488 111.912)
		(width 0.15)
		(layer "F.Cu")
		(net 69)
	)
	(segment
		(start 137.06328 95.437208)
		(end 137.06328 96.317208)
		(width 0.15)
		(layer "F.Cu")
		(net 69)
	)
	(segment
		(start 134.086512 97.327)
		(end 133.493 96.733488)
		(width 0.15)
		(layer "F.Cu")
		(net 69)
	)
	(via
		(at 166.15 113.263)
		(size 0.45)
		(drill 0.2)
		(layers "F.Cu" "B.Cu")
		(remove_unused_layers yes)
		(keep_end_layers yes)
		(zone_layer_connections)
		(net 69)
	)
	(via
		(at 137.295545 95.145545)
		(size 0.45)
		(drill 0.2)
		(layers "F.Cu" "B.Cu")
		(remove_unused_layers yes)
		(keep_end_layers yes)
		(zone_layer_connections)
		(net 69)
	)
	(segment
		(start 147.895519 103.162436)
		(end 148.832435 102.225519)
		(width 0.168)
		(layer "In4.Cu")
		(net 69)
	)
	(segment
		(start 137.831624 94.6625)
		(end 138.0425 94.6625)
		(width 0.168)
		(layer "In4.Cu")
		(net 69)
	)
	(segment
		(start 147.043104 100.772063)
		(end 147.043102 100.772062)
		(width 0.168)
		(layer "In4.Cu")
		(net 69)
	)
	(segment
		(start 150.718996 103.175163)
		(end 150.718995 103.175162)
		(width 0.168)
		(layer "In4.Cu")
		(net 69)
	)
	(segment
		(start 159.398376 113.3925)
		(end 166.0205 113.3925)
		(width 0.168)
		(layer "In4.Cu")
		(net 69)
	)
	(segment
		(start 151.235536 105.229659)
		(end 159.398376 113.3925)
		(width 0.168)
		(layer "In4.Cu")
		(net 69)
	)
	(segment
		(start 140.668376 94.6625)
		(end 146.777936 100.772061)
		(width 0.168)
		(layer "In4.Cu")
		(net 69)
	)
	(segment
		(start 137.348579 95.145545)
		(end 137.831624 94.6625)
		(width 0.168)
		(layer "In4.Cu")
		(net 69)
	)
	(segment
		(start 147.89552 103.427601)
		(end 147.895519 103.427601)
		(width 0.168)
		(layer "In4.Cu")
		(net 69)
	)
	(segment
		(start 148.147957 100.604124)
		(end 148.147956 100.604124)
		(width 0.168)
		(layer "In4.Cu")
		(net 69)
	)
	(segment
		(start 151.235534 105.229658)
		(end 151.235536 105.229659)
		(width 0.168)
		(layer "In4.Cu")
		(net 69)
	)
	(segment
		(start 148.845163 104.112079)
		(end 148.845163 104.11208)
		(width 0.168)
		(layer "In4.Cu")
		(net 69)
	)
	(segment
		(start 147.895519 103.427601)
		(end 148.579998 104.11208)
		(width 0.168)
		(layer "In4.Cu")
		(net 69)
	)
	(segment
		(start 166.0205 113.3925)
		(end 166.15 113.263)
		(width 0.168)
		(layer "In4.Cu")
		(net 69)
	)
	(segment
		(start 148.845163 104.11208)
		(end 149.782077 103.17516)
		(width 0.168)
		(layer "In4.Cu")
		(net 69)
	)
	(segment
		(start 138.3425 94.3625)
		(end 138.3425 94.2625)
		(width 0.168)
		(layer "In4.Cu")
		(net 69)
	)
	(segment
		(start 151.403474 104.796557)
		(end 151.235535 104.964493)
		(width 0.168)
		(layer "In4.Cu")
		(net 69)
	)
	(segment
		(start 139.2425 94.6625)
		(end 139.2925 94.6625)
		(width 0.168)
		(layer "In4.Cu")
		(net 69)
	)
	(segment
		(start 150.718995 103.175162)
		(end 151.403474 103.859641)
		(width 0.168)
		(layer "In4.Cu")
		(net 69)
	)
	(segment
		(start 147.043102 100.772062)
		(end 147.21104 100.604125)
		(width 0.168)
		(layer "In4.Cu")
		(net 69)
	)
	(segment
		(start 138.9425 94.2625)
		(end 138.9425 94.3625)
		(width 0.168)
		(layer "In4.Cu")
		(net 69)
	)
	(segment
		(start 148.147956 100.604124)
		(end 148.832435 101.288603)
		(width 0.168)
		(layer "In4.Cu")
		(net 69)
	)
	(segment
		(start 139.2925 94.6625)
		(end 140.668376 94.6625)
		(width 0.168)
		(layer "In4.Cu")
		(net 69)
	)
	(arc
		(start 147.21104 100.604125)
		(mid 147.679498 100.410083)
		(end 148.147957 100.604124)
		(width 0.168)
		(layer "In4.Cu")
		(net 69)
	)
	(arc
		(start 138.3425 94.2625)
		(mid 138.430368 94.050368)
		(end 138.6425 93.9625)
		(width 0.168)
		(layer "In4.Cu")
		(net 69)
	)
	(arc
		(start 146.777936 100.772061)
		(mid 146.91052 100.82698)
		(end 147.043104 100.772063)
		(width 0.168)
		(layer "In4.Cu")
		(net 69)
	)
	(arc
		(start 138.9425 94.3625)
		(mid 139.030368 94.574632)
		(end 139.2425 94.6625)
		(width 0.168)
		(layer "In4.Cu")
		(net 69)
	)
	(arc
		(start 148.579998 104.11208)
		(mid 148.712581 104.166997)
		(end 148.845163 104.112079)
		(width 0.168)
		(layer "In4.Cu")
		(net 69)
	)
	(arc
		(start 148.832435 101.288603)
		(mid 149.026477 101.757061)
		(end 148.832435 102.225519)
		(width 0.168)
		(layer "In4.Cu")
		(net 69)
	)
	(arc
		(start 151.403474 103.859641)
		(mid 151.597516 104.328099)
		(end 151.403474 104.796557)
		(width 0.168)
		(layer "In4.Cu")
		(net 69)
	)
	(arc
		(start 149.782077 103.17516)
		(mid 150.250536 102.981119)
		(end 150.718996 103.175163)
		(width 0.168)
		(layer "In4.Cu")
		(net 69)
	)
	(arc
		(start 138.6425 93.9625)
		(mid 138.854632 94.050368)
		(end 138.9425 94.2625)
		(width 0.168)
		(layer "In4.Cu")
		(net 69)
	)
	(arc
		(start 151.235535 104.964493)
		(mid 151.180617 105.097075)
		(end 151.235534 105.229658)
		(width 0.168)
		(layer "In4.Cu")
		(net 69)
	)
	(arc
		(start 138.0425 94.6625)
		(mid 138.254632 94.574632)
		(end 138.3425 94.3625)
		(width 0.168)
		(layer "In4.Cu")
		(net 69)
	)
	(arc
		(start 147.895519 103.162436)
		(mid 147.840602 103.295019)
		(end 147.89552 103.427601)
		(width 0.168)
		(layer "In4.Cu")
		(net 69)
	)
	(segment
		(start 135.324359 90.876981)
		(end 133.497183 92.704157)
		(width 0.15)
		(layer "F.Cu")
		(net 70)
	)
	(segment
		(start 167.549509 111.660003)
		(end 167.549509 111.849509)
		(width 0.15)
		(layer "F.Cu")
		(net 70)
	)
	(segment
		(start 168.682999 111.378)
		(end 167.831512 111.378)
		(width 0.15)
		(layer "F.Cu")
		(net 70)
	)
	(segment
		(start 167.831512 111.378)
		(end 167.549509 111.660003)
		(width 0.15)
		(layer "F.Cu")
		(net 70)
	)
	(segment
		(start 133.497183 92.704157)
		(end 132.484156 92.704157)
		(width 0.15)
		(layer "F.Cu")
		(net 70)
	)
	(segment
		(start 132.48 92.7)
		(end 131.9 92.7)
		(width 0.15)
		(layer "F.Cu")
		(net 70)
	)
	(segment
		(start 136.542583 90.876981)
		(end 135.324359 90.876981)
		(width 0.15)
		(layer "F.Cu")
		(net 70)
	)
	(segment
		(start 136.626108 90.793456)
		(end 136.542583 90.876981)
		(width 0.15)
		(layer "F.Cu")
		(net 70)
	)
	(segment
		(start 168.699999 111.395)
		(end 168.682999 111.378)
		(width 0.15)
		(layer "F.Cu")
		(net 70)
	)
	(segment
		(start 131.9 92.7)
		(end 131.5 92.3)
		(width 0.15)
		(layer "F.Cu")
		(net 70)
	)
	(segment
		(start 169.6 111.395)
		(end 168.699999 111.395)
		(width 0.15)
		(layer "F.Cu")
		(net 70)
	)
	(via
		(at 167.549509 111.849509)
		(size 0.45)
		(drill 0.2)
		(layers "F.Cu" "B.Cu")
		(remove_unused_layers yes)
		(keep_end_layers yes)
		(zone_layer_connections)
		(net 70)
	)
	(via
		(at 136.626108 90.793456)
		(size 0.45)
		(drill 0.2)
		(layers "F.Cu" "B.Cu")
		(remove_unused_layers yes)
		(keep_end_layers yes)
		(zone_layer_connections)
		(net 70)
	)
	(segment
		(start 147.225301 96.533219)
		(end 147.520871 96.828789)
		(width 0.168)
		(layer "In4.Cu")
		(net 70)
	)
	(segment
		(start 145.727652 95.300735)
		(end 145.72765 95.300734)
		(width 0.168)
		(layer "In4.Cu")
		(net 70)
	)
	(segment
		(start 147.520872 97.093955)
		(end 147.352933 97.261891)
		(width 0.168)
		(layer "In4.Cu")
		(net 70)
	)
	(segment
		(start 145.72765 95.300734)
		(end 144.790733 96.23765)
		(width 0.168)
		(layer "In4.Cu")
		(net 70)
	)
	(segment
		(start 144.998979 94.907938)
		(end 145.166915 94.739999)
		(width 0.168)
		(layer "In4.Cu")
		(net 70)
	)
	(segment
		(start 147.352932 98.198808)
		(end 147.352934 98.198809)
		(width 0.168)
		(layer "In4.Cu")
		(net 70)
	)
	(segment
		(start 145.432081 94.74)
		(end 145.727651 95.03557)
		(width 0.168)
		(layer "In4.Cu")
		(net 70)
	)
	(segment
		(start 146.02322 97.470136)
		(end 146.491677 97.001677)
		(width 0.168)
		(layer "In4.Cu")
		(net 70)
	)
	(segment
		(start 141.711624 94.1275)
		(end 143.281624 94.1275)
		(width 0.168)
		(layer "In4.Cu")
		(net 70)
	)
	(segment
		(start 145.43208 94.739998)
		(end 145.432081 94.74)
		(width 0.168)
		(layer "In4.Cu")
		(net 70)
	)
	(segment
		(start 167.366367 111.849509)
		(end 167.549509 111.849509)
		(width 0.168)
		(layer "In4.Cu")
		(net 70)
	)
	(segment
		(start 144.790733 97.174566)
		(end 145.086303 97.470136)
		(width 0.168)
		(layer "In4.Cu")
		(net 70)
	)
	(segment
		(start 166.938376 112.2775)
		(end 167.366367 111.849509)
		(width 0.168)
		(layer "In4.Cu")
		(net 70)
	)
	(segment
		(start 138.34008 90.755956)
		(end 141.711624 94.1275)
		(width 0.168)
		(layer "In4.Cu")
		(net 70)
	)
	(segment
		(start 146.491677 97.001677)
		(end 146.960137 96.53322)
		(width 0.168)
		(layer "In4.Cu")
		(net 70)
	)
	(segment
		(start 147.225302 96.533221)
		(end 147.225301 96.533219)
		(width 0.168)
		(layer "In4.Cu")
		(net 70)
	)
	(segment
		(start 146.023219 97.470136)
		(end 146.02322 97.470136)
		(width 0.168)
		(layer "In4.Cu")
		(net 70)
	)
	(segment
		(start 147.520872 97.093954)
		(end 147.520872 97.093955)
		(width 0.168)
		(layer "In4.Cu")
		(net 70)
	)
	(segment
		(start 143.281624 94.1275)
		(end 144.062061 94.907936)
		(width 0.168)
		(layer "In4.Cu")
		(net 70)
	)
	(segment
		(start 161.431624 112.2775)
		(end 166.938376 112.2775)
		(width 0.168)
		(layer "In4.Cu")
		(net 70)
	)
	(segment
		(start 144.790734 97.174567)
		(end 144.790733 97.174566)
		(width 0.168)
		(layer "In4.Cu")
		(net 70)
	)
	(segment
		(start 147.352934 98.198809)
		(end 161.431624 112.2775)
		(width 0.168)
		(layer "In4.Cu")
		(net 70)
	)
	(segment
		(start 136.663608 90.755956)
		(end 138.34008 90.755956)
		(width 0.168)
		(layer "In4.Cu")
		(net 70)
	)
	(arc
		(start 144.790733 96.23765)
		(mid 144.596692 96.706109)
		(end 144.790734 97.174567)
		(width 0.168)
		(layer "In4.Cu")
		(net 70)
	)
	(arc
		(start 145.727651 95.03557)
		(mid 145.782569 95.168152)
		(end 145.727652 95.300735)
		(width 0.168)
		(layer "In4.Cu")
		(net 70)
	)
	(arc
		(start 144.062061 94.907936)
		(mid 144.530521 95.10198)
		(end 144.998979 94.907938)
		(width 0.168)
		(layer "In4.Cu")
		(net 70)
	)
	(arc
		(start 145.086303 97.470136)
		(mid 145.554761 97.664178)
		(end 146.023219 97.470136)
		(width 0.168)
		(layer "In4.Cu")
		(net 70)
	)
	(arc
		(start 145.166915 94.739999)
		(mid 145.299497 94.685081)
		(end 145.43208 94.739998)
		(width 0.168)
		(layer "In4.Cu")
		(net 70)
	)
	(arc
		(start 147.520871 96.828789)
		(mid 147.575789 96.961371)
		(end 147.520872 97.093954)
		(width 0.168)
		(layer "In4.Cu")
		(net 70)
	)
	(arc
		(start 146.960137 96.53322)
		(mid 147.09272 96.478303)
		(end 147.225302 96.533221)
		(width 0.168)
		(layer "In4.Cu")
		(net 70)
	)
	(arc
		(start 147.352933 97.261891)
		(mid 147.158891 97.730349)
		(end 147.352932 98.198808)
		(width 0.168)
		(layer "In4.Cu")
		(net 70)
	)
	(segment
		(start 133.27 92.3)
		(end 134.201398 91.368604)
		(width 0.15)
		(layer "F.Cu")
		(net 71)
	)
	(segment
		(start 136.458564 90.411)
		(end 136.626108 90.243456)
		(width 0.15)
		(layer "F.Cu")
		(net 71)
	)
	(segment
		(start 167.219997 111.330491)
		(end 167.030491 111.330491)
		(width 0.15)
		(layer "F.Cu")
		(net 71)
	)
	(segment
		(start 168.699999 110.895)
		(end 168.682999 110.912)
		(width 0.15)
		(layer "F.Cu")
		(net 71)
	)
	(segment
		(start 132.3 92.3)
		(end 133.27 92.3)
		(width 0.15)
		(layer "F.Cu")
		(net 71)
	)
	(segment
		(start 169.6 110.895)
		(end 168.699999 110.895)
		(width 0.15)
		(layer "F.Cu")
		(net 71)
	)
	(segment
		(start 134.201398 91.368604)
		(end 135.159 90.411)
		(width 0.15)
		(layer "F.Cu")
		(net 71)
	)
	(segment
		(start 168.682999 110.912)
		(end 167.638488 110.912)
		(width 0.15)
		(layer "F.Cu")
		(net 71)
	)
	(segment
		(start 167.638488 110.912)
		(end 167.219997 111.330491)
		(width 0.15)
		(layer "F.Cu")
		(net 71)
	)
	(segment
		(start 135.159 90.411)
		(end 136.458564 90.411)
		(width 0.15)
		(layer "F.Cu")
		(net 71)
	)
	(via
		(at 167.030491 111.330491)
		(size 0.45)
		(drill 0.2)
		(layers "F.Cu" "B.Cu")
		(remove_unused_layers yes)
		(keep_end_layers yes)
		(zone_layer_connections)
		(net 71)
	)
	(via
		(at 136.626108 90.243456)
		(size 0.45)
		(drill 0.2)
		(layers "F.Cu" "B.Cu")
		(remove_unused_layers yes)
		(keep_end_layers yes)
		(zone_layer_connections)
		(net 71)
	)
	(segment
		(start 139.616465 91.360589)
		(end 139.616466 91.36059)
		(width 0.168)
		(layer "In4.Cu")
		(net 71)
	)
	(segment
		(start 145.767957 94.404124)
		(end 145.767956 94.404124)
		(width 0.168)
		(layer "In4.Cu")
		(net 71)
	)
	(segment
		(start 144.663102 94.572062)
		(end 144.83104 94.404125)
		(width 0.168)
		(layer "In4.Cu")
		(net 71)
	)
	(segment
		(start 147.856746 97.42983)
		(end 147.688809 97.597768)
		(width 0.168)
		(layer "In4.Cu")
		(net 71)
	)
	(segment
		(start 147.856747 97.42983)
		(end 147.856746 97.42983)
		(width 0.168)
		(layer "In4.Cu")
		(net 71)
	)
	(segment
		(start 147.688808 97.862933)
		(end 147.688808 97.862932)
		(width 0.168)
		(layer "In4.Cu")
		(net 71)
	)
	(segment
		(start 167.030491 111.513633)
		(end 167.030491 111.330491)
		(width 0.168)
		(layer "In4.Cu")
		(net 71)
	)
	(segment
		(start 145.687344 97.134262)
		(end 145.687344 97.134261)
		(width 0.168)
		(layer "In4.Cu")
		(net 71)
	)
	(segment
		(start 136.663608 90.280956)
		(end 138.536832 90.280956)
		(width 0.168)
		(layer "In4.Cu")
		(net 71)
	)
	(segment
		(start 139.616466 91.36059)
		(end 141.908376 93.6525)
		(width 0.168)
		(layer "In4.Cu")
		(net 71)
	)
	(segment
		(start 141.908376 93.6525)
		(end 143.478376 93.6525)
		(width 0.168)
		(layer "In4.Cu")
		(net 71)
	)
	(segment
		(start 146.063527 95.636612)
		(end 145.126609 96.573526)
		(width 0.168)
		(layer "In4.Cu")
		(net 71)
	)
	(segment
		(start 139.730423 90.82237)
		(end 139.730424 90.822369)
		(width 0.168)
		(layer "In4.Cu")
		(net 71)
	)
	(segment
		(start 161.628376 111.8025)
		(end 166.741624 111.8025)
		(width 0.168)
		(layer "In4.Cu")
		(net 71)
	)
	(segment
		(start 166.741624 111.8025)
		(end 167.030491 111.513633)
		(width 0.168)
		(layer "In4.Cu")
		(net 71)
	)
	(segment
		(start 145.687344 97.134261)
		(end 146.624259 96.197342)
		(width 0.168)
		(layer "In4.Cu")
		(net 71)
	)
	(segment
		(start 145.12661 96.838691)
		(end 145.126609 96.838691)
		(width 0.168)
		(layer "In4.Cu")
		(net 71)
	)
	(segment
		(start 144.663104 94.572063)
		(end 144.663102 94.572062)
		(width 0.168)
		(layer "In4.Cu")
		(net 71)
	)
	(segment
		(start 146.063526 95.63661)
		(end 146.063527 95.636612)
		(width 0.168)
		(layer "In4.Cu")
		(net 71)
	)
	(segment
		(start 147.561177 96.197344)
		(end 147.856747 96.492914)
		(width 0.168)
		(layer "In4.Cu")
		(net 71)
	)
	(segment
		(start 138.536832 90.280956)
		(end 138.767938 90.512062)
		(width 0.168)
		(layer "In4.Cu")
		(net 71)
	)
	(segment
		(start 147.561178 96.197345)
		(end 147.561177 96.197344)
		(width 0.168)
		(layer "In4.Cu")
		(net 71)
	)
	(segment
		(start 145.126609 96.838691)
		(end 145.422179 97.134261)
		(width 0.168)
		(layer "In4.Cu")
		(net 71)
	)
	(segment
		(start 147.688808 97.862932)
		(end 161.628376 111.8025)
		(width 0.168)
		(layer "In4.Cu")
		(net 71)
	)
	(segment
		(start 145.767956 94.404124)
		(end 146.063526 94.699694)
		(width 0.168)
		(layer "In4.Cu")
		(net 71)
	)
	(segment
		(start 139.192202 90.512062)
		(end 139.30616 90.398105)
		(width 0.168)
		(layer "In4.Cu")
		(net 71)
	)
	(segment
		(start 139.192203 90.512061)
		(end 139.192202 90.512062)
		(width 0.168)
		(layer "In4.Cu")
		(net 71)
	)
	(segment
		(start 139.730424 90.822369)
		(end 139.616465 90.936325)
		(width 0.168)
		(layer "In4.Cu")
		(net 71)
	)
	(segment
		(start 143.478376 93.6525)
		(end 144.397936 94.572061)
		(width 0.168)
		(layer "In4.Cu")
		(net 71)
	)
	(arc
		(start 147.856747 96.492914)
		(mid 148.050789 96.961372)
		(end 147.856747 97.42983)
		(width 0.168)
		(layer "In4.Cu")
		(net 71)
	)
	(arc
		(start 138.767938 90.512062)
		(mid 138.980072 90.599931)
		(end 139.192203 90.512061)
		(width 0.168)
		(layer "In4.Cu")
		(net 71)
	)
	(arc
		(start 146.063526 94.699694)
		(mid 146.257568 95.168152)
		(end 146.063526 95.63661)
		(width 0.168)
		(layer "In4.Cu")
		(net 71)
	)
	(arc
		(start 144.83104 94.404125)
		(mid 145.299498 94.210083)
		(end 145.767957 94.404124)
		(width 0.168)
		(layer "In4.Cu")
		(net 71)
	)
	(arc
		(start 139.616465 90.936325)
		(mid 139.528597 91.148457)
		(end 139.616465 91.360589)
		(width 0.168)
		(layer "In4.Cu")
		(net 71)
	)
	(arc
		(start 145.126609 96.573526)
		(mid 145.071692 96.706109)
		(end 145.12661 96.838691)
		(width 0.168)
		(layer "In4.Cu")
		(net 71)
	)
	(arc
		(start 146.624259 96.197342)
		(mid 147.092718 96.003301)
		(end 147.561178 96.197345)
		(width 0.168)
		(layer "In4.Cu")
		(net 71)
	)
	(arc
		(start 139.30616 90.398105)
		(mid 139.518292 90.310237)
		(end 139.730424 90.398105)
		(width 0.168)
		(layer "In4.Cu")
		(net 71)
	)
	(arc
		(start 144.397936 94.572061)
		(mid 144.53052 94.62698)
		(end 144.663104 94.572063)
		(width 0.168)
		(layer "In4.Cu")
		(net 71)
	)
	(arc
		(start 139.730424 90.398105)
		(mid 139.818291 90.610237)
		(end 139.730423 90.82237)
		(width 0.168)
		(layer "In4.Cu")
		(net 71)
	)
	(arc
		(start 147.688809 97.597768)
		(mid 147.633891 97.73035)
		(end 147.688808 97.862933)
		(width 0.168)
		(layer "In4.Cu")
		(net 71)
	)
	(arc
		(start 145.422179 97.134261)
		(mid 145.554761 97.189179)
		(end 145.687344 97.134262)
		(width 0.168)
		(layer "In4.Cu")
		(net 71)
	)
	(segment
		(start 166.731512 110.378)
		(end 166.549509 110.560003)
		(width 0.15)
		(layer "F.Cu")
		(net 72)
	)
	(segment
		(start 132.540786 95.138775)
		(end 132.990575 95.138775)
		(width 0.15)
		(layer "F.Cu")
		(net 72)
	)
	(segment
		(start 132.990575 95.138775)
		(end 133.6348 95.783)
		(width 0.15)
		(layer "F.Cu")
		(net 72)
	)
	(segment
		(start 135.9752 95.783)
		(end 137.1532 94.605)
		(width 0.15)
		(layer "F.Cu")
		(net 72)
	)
	(segment
		(start 131.9 95.1)
		(end 132.502011 95.1)
		(width 0.15)
		(layer "F.Cu")
		(net 72)
	)
	(segment
		(start 169.6 110.395)
		(end 168.699999 110.395)
		(width 0.15)
		(layer "F.Cu")
		(net 72)
	)
	(segment
		(start 131.5 94.7)
		(end 131.9 95.1)
		(width 0.15)
		(layer "F.Cu")
		(net 72)
	)
	(segment
		(start 132.502011 95.1)
		(end 132.540786 95.138775)
		(width 0.15)
		(layer "F.Cu")
		(net 72)
	)
	(segment
		(start 142.678 90.113)
		(end 142.72 90.155)
		(width 0.15)
		(layer "F.Cu")
		(net 72)
	)
	(segment
		(start 142.2352 90.113)
		(end 142.678 90.113)
		(width 0.15)
		(layer "F.Cu")
		(net 72)
	)
	(segment
		(start 168.682999 110.378)
		(end 166.731512 110.378)
		(width 0.15)
		(layer "F.Cu")
		(net 72)
	)
	(segment
		(start 137.7432 94.605)
		(end 142.2352 90.113)
		(width 0.15)
		(layer "F.Cu")
		(net 72)
	)
	(segment
		(start 166.549509 110.560003)
		(end 166.549509 110.749509)
		(width 0.15)
		(layer "F.Cu")
		(net 72)
	)
	(segment
		(start 137.1532 94.605)
		(end 137.7432 94.605)
		(width 0.15)
		(layer "F.Cu")
		(net 72)
	)
	(segment
		(start 133.6348 95.783)
		(end 135.9752 95.783)
		(width 0.15)
		(layer "F.Cu")
		(net 72)
	)
	(segment
		(start 168.699999 110.395)
		(end 168.682999 110.378)
		(width 0.15)
		(layer "F.Cu")
		(net 72)
	)
	(via
		(at 166.549509 110.749509)
		(size 0.45)
		(drill 0.2)
		(layers "F.Cu" "B.Cu")
		(remove_unused_layers yes)
		(keep_end_layers yes)
		(zone_layer_connections)
		(net 72)
	)
	(via
		(at 142.72 90.155)
		(size 0.45)
		(drill 0.2)
		(layers "F.Cu" "B.Cu")
		(remove_unused_layers yes)
		(keep_end_layers yes)
		(zone_layer_connections)
		(net 72)
	)
	(segment
		(start 148.87732 93.691826)
		(end 148.709383 93.859764)
		(width 0.168)
		(layer "In4.Cu")
		(net 72)
	)
	(segment
		(start 147.225519 92.040025)
		(end 146.430025 92.835519)
		(width 0.168)
		(layer "In4.Cu")
		(net 72)
	)
	(segment
		(start 148.709383 94.655258)
		(end 148.709382 94.655256)
		(width 0.168)
		(layer "In4.Cu")
		(net 72)
	)
	(segment
		(start 147.225519 92.040026)
		(end 147.225519 92.040025)
		(width 0.168)
		(layer "In4.Cu")
		(net 72)
	)
	(segment
		(start 163.321624 111.1175)
		(end 165.998376 111.1175)
		(width 0.168)
		(layer "In4.Cu")
		(net 72)
	)
	(segment
		(start 148.511038 93.2018)
		(end 148.51104 93.201801)
		(width 0.168)
		(layer "In4.Cu")
		(net 72)
	)
	(segment
		(start 150.516 96.461875)
		(end 150.516 98.311876)
		(width 0.168)
		(layer "In4.Cu")
		(net 72)
	)
	(segment
		(start 146.859239 91.55)
		(end 147.22552 91.916281)
		(width 0.168)
		(layer "In4.Cu")
		(net 72)
	)
	(segment
		(start 148.709382 94.655256)
		(end 150.516 96.461875)
		(width 0.168)
		(layer "In4.Cu")
		(net 72)
	)
	(segment
		(start 146.859238 91.55)
		(end 146.859239 91.55)
		(width 0.168)
		(layer "In4.Cu")
		(net 72)
	)
	(segment
		(start 146.567557 91.717938)
		(end 146.735493 91.549999)
		(width 0.168)
		(layer "In4.Cu")
		(net 72)
	)
	(segment
		(start 142.7575 90.1175)
		(end 144.171624 90.1175)
		(width 0.168)
		(layer "In4.Cu")
		(net 72)
	)
	(segment
		(start 147.5918 93.997294)
		(end 148.387294 93.2018)
		(width 0.168)
		(layer "In4.Cu")
		(net 72)
	)
	(segment
		(start 144.171624 90.1175)
		(end 145.772061 91.717936)
		(width 0.168)
		(layer "In4.Cu")
		(net 72)
	)
	(segment
		(start 142.72 90.155)
		(end 142.7575 90.1175)
		(width 0.168)
		(layer "In4.Cu")
		(net 72)
	)
	(segment
		(start 148.87732 93.691827)
		(end 148.87732 93.691826)
		(width 0.168)
		(layer "In4.Cu")
		(net 72)
	)
	(segment
		(start 166.366367 110.749509)
		(end 166.549509 110.749509)
		(width 0.168)
		(layer "In4.Cu")
		(net 72)
	)
	(segment
		(start 165.998376 111.1175)
		(end 166.366367 110.749509)
		(width 0.168)
		(layer "In4.Cu")
		(net 72)
	)
	(segment
		(start 146.430025 93.631013)
		(end 146.796306 93.997294)
		(width 0.168)
		(layer "In4.Cu")
		(net 72)
	)
	(segment
		(start 150.516 98.311876)
		(end 163.321624 111.1175)
		(width 0.168)
		(layer "In4.Cu")
		(net 72)
	)
	(segment
		(start 148.51104 93.201801)
		(end 148.877321 93.568082)
		(width 0.168)
		(layer "In4.Cu")
		(net 72)
	)
	(arc
		(start 146.735493 91.549999)
		(mid 146.797367 91.524372)
		(end 146.859238 91.55)
		(width 0.168)
		(layer "In4.Cu")
		(net 72)
	)
	(arc
		(start 146.430025 92.835519)
		(mid 146.265273 93.233266)
		(end 146.430025 93.631013)
		(width 0.168)
		(layer "In4.Cu")
		(net 72)
	)
	(arc
		(start 147.22552 91.916281)
		(mid 147.251147 91.978153)
		(end 147.225519 92.040026)
		(width 0.168)
		(layer "In4.Cu")
		(net 72)
	)
	(arc
		(start 146.796306 93.997294)
		(mid 147.194053 94.162046)
		(end 147.5918 93.997294)
		(width 0.168)
		(layer "In4.Cu")
		(net 72)
	)
	(arc
		(start 145.772061 91.717936)
		(mid 146.169809 91.882689)
		(end 146.567557 91.717938)
		(width 0.168)
		(layer "In4.Cu")
		(net 72)
	)
	(arc
		(start 148.709383 93.859764)
		(mid 148.54463 94.25751)
		(end 148.709383 94.655258)
		(width 0.168)
		(layer "In4.Cu")
		(net 72)
	)
	(arc
		(start 148.387294 93.2018)
		(mid 148.449166 93.176172)
		(end 148.511038 93.2018)
		(width 0.168)
		(layer "In4.Cu")
		(net 72)
	)
	(arc
		(start 148.877321 93.568082)
		(mid 148.902948 93.629954)
		(end 148.87732 93.691827)
		(width 0.168)
		(layer "In4.Cu")
		(net 72)
	)
	(segment
		(start 132.3 94.701)
		(end 133.1892 94.701)
		(width 0.15)
		(layer "F.Cu")
		(net 73)
	)
	(segment
		(start 168.699999 109.895)
		(end 168.682999 109.912)
		(width 0.15)
		(layer "F.Cu")
		(net 73)
	)
	(segment
		(start 142.678 89.647)
		(end 142.72 89.605)
		(width 0.15)
		(layer "F.Cu")
		(net 73)
	)
	(segment
		(start 166.219997 110.230491)
		(end 166.030491 110.230491)
		(width 0.15)
		(layer "F.Cu")
		(net 73)
	)
	(segment
		(start 142.0648 89.647)
		(end 142.678 89.647)
		(width 0.15)
		(layer "F.Cu")
		(net 73)
	)
	(segment
		(start 136.9668 94.155)
		(end 137.5568 94.155)
		(width 0.15)
		(layer "F.Cu")
		(net 73)
	)
	(segment
		(start 166.538488 109.912)
		(end 166.219997 110.230491)
		(width 0.15)
		(layer "F.Cu")
		(net 73)
	)
	(segment
		(start 133.8052 95.317)
		(end 135.8048 95.317)
		(width 0.15)
		(layer "F.Cu")
		(net 73)
	)
	(segment
		(start 133.1892 94.701)
		(end 133.8052 95.317)
		(width 0.15)
		(layer "F.Cu")
		(net 73)
	)
	(segment
		(start 169.6 109.895)
		(end 168.699999 109.895)
		(width 0.15)
		(layer "F.Cu")
		(net 73)
	)
	(segment
		(start 135.8048 95.317)
		(end 136.9668 94.155)
		(width 0.15)
		(layer "F.Cu")
		(net 73)
	)
	(segment
		(start 137.5568 94.155)
		(end 142.0648 89.647)
		(width 0.15)
		(layer "F.Cu")
		(net 73)
	)
	(segment
		(start 168.682999 109.912)
		(end 166.538488 109.912)
		(width 0.15)
		(layer "F.Cu")
		(net 73)
	)
	(via
		(at 166.030491 110.230491)
		(size 0.45)
		(drill 0.2)
		(layers "F.Cu" "B.Cu")
		(remove_unused_layers yes)
		(keep_end_layers yes)
		(zone_layer_connections)
		(net 73)
	)
	(via
		(at 142.72 89.605)
		(size 0.45)
		(drill 0.2)
		(layers "F.Cu" "B.Cu")
		(remove_unused_layers yes)
		(keep_end_layers yes)
		(zone_layer_connections)
		(net 73)
	)
	(segment
		(start 142.918376 89.6425)
		(end 142.768376 89.6425)
		(width 0.168)
		(layer "In4.Cu")
		(net 73)
	)
	(segment
		(start 148.051419 92.865925)
		(end 147.255926 93.66142)
		(width 0.168)
		(layer "In4.Cu")
		(net 73)
	)
	(segment
		(start 144.368376 89.6425)
		(end 146.107936 91.382061)
		(width 0.168)
		(layer "In4.Cu")
		(net 73)
	)
	(segment
		(start 149.213194 93.232206)
		(end 148.846913 92.865925)
		(width 0.168)
		(layer "In4.Cu")
		(net 73)
	)
	(segment
		(start 166.030491 110.230491)
		(end 166.030491 110.413633)
		(width 0.168)
		(layer "In4.Cu")
		(net 73)
	)
	(segment
		(start 150.984 98.108125)
		(end 150.984 96.258125)
		(width 0.168)
		(layer "In4.Cu")
		(net 73)
	)
	(segment
		(start 165.801624 110.6425)
		(end 163.518376 110.6425)
		(width 0.168)
		(layer "In4.Cu")
		(net 73)
	)
	(segment
		(start 143.718376 88.9925)
		(end 143.568376 88.9925)
		(width 0.168)
		(layer "In4.Cu")
		(net 73)
	)
	(segment
		(start 149.045257 94.195638)
		(end 149.213194 94.0277)
		(width 0.168)
		(layer "In4.Cu")
		(net 73)
	)
	(segment
		(start 146.7659 93.295139)
		(end 146.7659 93.295138)
		(width 0.168)
		(layer "In4.Cu")
		(net 73)
	)
	(segment
		(start 163.518376 110.6425)
		(end 150.984 98.108125)
		(width 0.168)
		(layer "In4.Cu")
		(net 73)
	)
	(segment
		(start 166.030491 110.413633)
		(end 165.801624 110.6425)
		(width 0.168)
		(layer "In4.Cu")
		(net 73)
	)
	(segment
		(start 147.195112 91.214124)
		(end 147.195114 91.214125)
		(width 0.168)
		(layer "In4.Cu")
		(net 73)
	)
	(segment
		(start 146.39962 91.214125)
		(end 146.231682 91.382062)
		(width 0.168)
		(layer "In4.Cu")
		(net 73)
	)
	(segment
		(start 147.255926 93.66142)
		(end 147.255926 93.661419)
		(width 0.168)
		(layer "In4.Cu")
		(net 73)
	)
	(segment
		(start 142.7575 89.6425)
		(end 142.72 89.605)
		(width 0.168)
		(layer "In4.Cu")
		(net 73)
	)
	(segment
		(start 146.7659 93.171394)
		(end 147.561393 92.375899)
		(width 0.168)
		(layer "In4.Cu")
		(net 73)
	)
	(segment
		(start 142.768376 89.6425)
		(end 142.7575 89.6425)
		(width 0.168)
		(layer "In4.Cu")
		(net 73)
	)
	(segment
		(start 146.231682 91.382062)
		(end 146.231682 91.382063)
		(width 0.168)
		(layer "In4.Cu")
		(net 73)
	)
	(segment
		(start 147.132181 93.66142)
		(end 146.7659 93.295139)
		(width 0.168)
		(layer "In4.Cu")
		(net 73)
	)
	(segment
		(start 147.561393 91.580405)
		(end 147.195112 91.214124)
		(width 0.168)
		(layer "In4.Cu")
		(net 73)
	)
	(segment
		(start 150.984 96.258125)
		(end 149.045258 94.319383)
		(width 0.168)
		(layer "In4.Cu")
		(net 73)
	)
	(arc
		(start 147.255926 93.661419)
		(mid 147.194054 93.687048)
		(end 147.132181 93.66142)
		(width 0.168)
		(layer "In4.Cu")
		(net 73)
	)
	(arc
		(start 144.043376 89.3175)
		(mid 143.948186 89.08769)
		(end 143.718376 88.9925)
		(width 0.168)
		(layer "In4.Cu")
		(net 73)
	)
	(arc
		(start 146.231682 91.382063)
		(mid 146.16981 91.407691)
		(end 146.107936 91.382061)
		(width 0.168)
		(layer "In4.Cu")
		(net 73)
	)
	(arc
		(start 147.561393 92.375899)
		(mid 147.726146 91.978153)
		(end 147.561393 91.580405)
		(width 0.168)
		(layer "In4.Cu")
		(net 73)
	)
	(arc
		(start 147.195114 91.214125)
		(mid 146.797366 91.049372)
		(end 146.39962 91.214125)
		(width 0.168)
		(layer "In4.Cu")
		(net 73)
	)
	(arc
		(start 149.213194 94.0277)
		(mid 149.377947 93.629954)
		(end 149.213194 93.232206)
		(width 0.168)
		(layer "In4.Cu")
		(net 73)
	)
	(arc
		(start 144.368376 89.6425)
		(mid 144.138566 89.54731)
		(end 144.043376 89.3175)
		(width 0.168)
		(layer "In4.Cu")
		(net 73)
	)
	(arc
		(start 149.045258 94.319383)
		(mid 149.019628 94.25751)
		(end 149.045257 94.195638)
		(width 0.168)
		(layer "In4.Cu")
		(net 73)
	)
	(arc
		(start 146.7659 93.295138)
		(mid 146.740272 93.233266)
		(end 146.7659 93.171394)
		(width 0.168)
		(layer "In4.Cu")
		(net 73)
	)
	(arc
		(start 148.846913 92.865925)
		(mid 148.449165 92.701172)
		(end 148.051419 92.865925)
		(width 0.168)
		(layer "In4.Cu")
		(net 73)
	)
	(arc
		(start 143.568376 88.9925)
		(mid 143.338566 89.08769)
		(end 143.243376 89.3175)
		(width 0.168)
		(layer "In4.Cu")
		(net 73)
	)
	(arc
		(start 143.243376 89.3175)
		(mid 143.148186 89.54731)
		(end 142.918376 89.6425)
		(width 0.168)
		(layer "In4.Cu")
		(net 73)
	)
	(segment
		(start 166.144 109.378)
		(end 166.01 109.512)
		(width 0.15)
		(layer "F.Cu")
		(net 74)
	)
	(segment
		(start 137.583 91.397)
		(end 136.557 92.423)
		(width 0.15)
		(layer "F.Cu")
		(net 74)
	)
	(segment
		(start 132.44 93.5)
		(end 131.9 93.5)
		(width 0.15)
		(layer "F.Cu")
		(net 74)
	)
	(segment
		(start 131.9 93.5)
		(end 131.5 93.1)
		(width 0.15)
		(layer "F.Cu")
		(net 74)
	)
	(segment
		(start 168.699999 109.395)
		(end 168.682999 109.378)
		(width 0.15)
		(layer "F.Cu")
		(net 74)
	)
	(segment
		(start 135.416512 92.423)
		(end 134.334122 93.50539)
		(width 0.15)
		(layer "F.Cu")
		(net 74)
	)
	(segment
		(start 132.44539 93.50539)
		(end 132.44 93.5)
		(width 0.15)
		(layer "F.Cu")
		(net 74)
	)
	(segment
		(start 169.6 109.395)
		(end 168.699999 109.395)
		(width 0.15)
		(layer "F.Cu")
		(net 74)
	)
	(segment
		(start 137.625 89.45)
		(end 137.583 89.492)
		(width 0.15)
		(layer "F.Cu")
		(net 74)
	)
	(segment
		(start 134.334122 93.50539)
		(end 132.44539 93.50539)
		(width 0.15)
		(layer "F.Cu")
		(net 74)
	)
	(segment
		(start 136.557 92.423)
		(end 135.416512 92.423)
		(width 0.15)
		(layer "F.Cu")
		(net 74)
	)
	(segment
		(start 137.583 89.492)
		(end 137.583 91.397)
		(width 0.15)
		(layer "F.Cu")
		(net 74)
	)
	(segment
		(start 168.682999 109.378)
		(end 166.144 109.378)
		(width 0.15)
		(layer "F.Cu")
		(net 74)
	)
	(via
		(at 166.01 109.512)
		(size 0.45)
		(drill 0.2)
		(layers "F.Cu" "B.Cu")
		(remove_unused_layers yes)
		(keep_end_layers yes)
		(zone_layer_connections)
		(net 74)
	)
	(via
		(at 137.625 89.45)
		(size 0.45)
		(drill 0.2)
		(layers "F.Cu" "B.Cu")
		(remove_unused_layers yes)
		(keep_end_layers yes)
		(zone_layer_connections)
		(net 74)
	)
	(segment
		(start 140.3375 87.9825)
		(end 140.3375 87.745)
		(width 0.168)
		(layer "In4.Cu")
		(net 74)
	)
	(segment
		(start 137.584 88.981876)
		(end 138.108376 88.4575)
		(width 0.168)
		(layer "In4.Cu")
		(net 74)
	)
	(segment
		(start 141.5055 89.17)
		(end 142.1985 89.17)
		(width 0.168)
		(layer "In4.Cu")
		(net 74)
	)
	(segment
		(start 138.108376 88.4575)
		(end 139.8625 88.4575)
		(width 0.168)
		(layer "In4.Cu")
		(net 74)
	)
	(segment
		(start 164.376624 109.3825)
		(end 165.8805 109.3825)
		(width 0.168)
		(layer "In4.Cu")
		(net 74)
	)
	(segment
		(start 152.7125 95.078376)
		(end 152.7125 97.718376)
		(width 0.168)
		(layer "In4.Cu")
		(net 74)
	)
	(segment
		(start 152.7125 97.718376)
		(end 164.376624 109.3825)
		(width 0.168)
		(layer "In4.Cu")
		(net 74)
	)
	(segment
		(start 142.6735 88.4575)
		(end 146.091624 88.4575)
		(width 0.168)
		(layer "In4.Cu")
		(net 74)
	)
	(segment
		(start 141.0305 87.745)
		(end 141.0305 88.695)
		(width 0.168)
		(layer "In4.Cu")
		(net 74)
	)
	(segment
		(start 137.625 89.45)
		(end 137.584 89.409)
		(width 0.168)
		(layer "In4.Cu")
		(net 74)
	)
	(segment
		(start 146.091624 88.4575)
		(end 152.7125 95.078376)
		(width 0.168)
		(layer "In4.Cu")
		(net 74)
	)
	(segment
		(start 142.6735 88.695)
		(end 142.6735 88.4575)
		(width 0.168)
		(layer "In4.Cu")
		(net 74)
	)
	(segment
		(start 165.8805 109.3825)
		(end 166.01 109.512)
		(width 0.168)
		(layer "In4.Cu")
		(net 74)
	)
	(segment
		(start 137.584 89.409)
		(end 137.584 88.981876)
		(width 0.168)
		(layer "In4.Cu")
		(net 74)
	)
	(segment
		(start 140.3375 87.745)
		(end 141.0305 87.745)
		(width 0.168)
		(layer "In4.Cu")
		(net 74)
	)
	(arc
		(start 142.1985 89.17)
		(mid 142.534376 89.030876)
		(end 142.6735 88.695)
		(width 0.168)
		(layer "In4.Cu")
		(net 74)
	)
	(arc
		(start 141.0305 88.695)
		(mid 141.169624 89.030876)
		(end 141.5055 89.17)
		(width 0.168)
		(layer "In4.Cu")
		(net 74)
	)
	(arc
		(start 139.8625 88.4575)
		(mid 140.198376 88.318376)
		(end 140.3375 87.9825)
		(width 0.168)
		(layer "In4.Cu")
		(net 74)
	)
	(segment
		(start 168.699999 108.895)
		(end 168.682999 108.912)
		(width 0.15)
		(layer "F.Cu")
		(net 75)
	)
	(segment
		(start 137.075 89.45)
		(end 137.117 89.492)
		(width 0.15)
		(layer "F.Cu")
		(net 75)
	)
	(segment
		(start 137.117 91.253)
		(end 136.413 91.957)
		(width 0.15)
		(layer "F.Cu")
		(net 75)
	)
	(segment
		(start 169.6 108.895)
		(end 168.699999 108.895)
		(width 0.15)
		(layer "F.Cu")
		(net 75)
	)
	(segment
		(start 135.223488 91.957)
		(end 134.110488 93.07)
		(width 0.15)
		(layer "F.Cu")
		(net 75)
	)
	(segment
		(start 166.144 108.912)
		(end 166.01 108.778)
		(width 0.15)
		(layer "F.Cu")
		(net 75)
	)
	(segment
		(start 168.682999 108.912)
		(end 166.144 108.912)
		(width 0.15)
		(layer "F.Cu")
		(net 75)
	)
	(segment
		(start 132.55 93.07)
		(end 132.52 93.1)
		(width 0.15)
		(layer "F.Cu")
		(net 75)
	)
	(segment
		(start 134.110488 93.07)
		(end 132.55 93.07)
		(width 0.15)
		(layer "F.Cu")
		(net 75)
	)
	(segment
		(start 137.117 89.492)
		(end 137.117 91.253)
		(width 0.15)
		(layer "F.Cu")
		(net 75)
	)
	(segment
		(start 132.52 93.1)
		(end 132.3 93.1)
		(width 0.15)
		(layer "F.Cu")
		(net 75)
	)
	(segment
		(start 136.413 91.957)
		(end 135.223488 91.957)
		(width 0.15)
		(layer "F.Cu")
		(net 75)
	)
	(via
		(at 166.01 108.778)
		(size 0.45)
		(drill 0.2)
		(layers "F.Cu" "B.Cu")
		(remove_unused_layers yes)
		(keep_end_layers yes)
		(zone_layer_connections)
		(net 75)
	)
	(via
		(at 137.075 89.45)
		(size 0.45)
		(drill 0.2)
		(layers "F.Cu" "B.Cu")
		(remove_unused_layers yes)
		(keep_end_layers yes)
		(zone_layer_connections)
		(net 75)
	)
	(segment
		(start 139.8625 87.9825)
		(end 139.8625 87.745)
		(width 0.168)
		(layer "In4.Cu")
		(net 75)
	)
	(segment
		(start 141.5055 87.745)
		(end 141.5055 88.695)
		(width 0.168)
		(layer "In4.Cu")
		(net 75)
	)
	(segment
		(start 165.8805 108.9075)
		(end 166.01 108.778)
		(width 0.168)
		(layer "In4.Cu")
		(net 75)
	)
	(segment
		(start 164.573376 108.9075)
		(end 165.8805 108.9075)
		(width 0.168)
		(layer "In4.Cu")
		(net 75)
	)
	(segment
		(start 139.111624 87.9825)
		(end 139.8625 87.9825)
		(width 0.168)
		(layer "In4.Cu")
		(net 75)
	)
	(segment
		(start 153.1875 97.521624)
		(end 164.573376 108.9075)
		(width 0.168)
		(layer "In4.Cu")
		(net 75)
	)
	(segment
		(start 140.3375 87.27)
		(end 141.0305 87.27)
		(width 0.168)
		(layer "In4.Cu")
		(net 75)
	)
	(segment
		(start 138.461624 87.4325)
		(end 138.511624 87.4325)
		(width 0.168)
		(layer "In4.Cu")
		(net 75)
	)
	(segment
		(start 146.288376 87.9825)
		(end 153.1875 94.881624)
		(width 0.168)
		(layer "In4.Cu")
		(net 75)
	)
	(segment
		(start 139.061624 87.9825)
		(end 139.111624 87.9825)
		(width 0.168)
		(layer "In4.Cu")
		(net 75)
	)
	(segment
		(start 137.075 89.45)
		(end 137.116 89.409)
		(width 0.168)
		(layer "In4.Cu")
		(net 75)
	)
	(segment
		(start 153.1875 94.881624)
		(end 153.1875 97.521624)
		(width 0.168)
		(layer "In4.Cu")
		(net 75)
	)
	(segment
		(start 142.6735 87.9825)
		(end 146.288376 87.9825)
		(width 0.168)
		(layer "In4.Cu")
		(net 75)
	)
	(segment
		(start 142.1985 88.695)
		(end 142.1985 88.4575)
		(width 0.168)
		(layer "In4.Cu")
		(net 75)
	)
	(segment
		(start 141.5055 88.695)
		(end 142.1985 88.695)
		(width 0.168)
		(layer "In4.Cu")
		(net 75)
	)
	(segment
		(start 137.116 89.409)
		(end 137.116 88.778124)
		(width 0.168)
		(layer "In4.Cu")
		(net 75)
	)
	(segment
		(start 137.116 88.778124)
		(end 137.911624 87.9825)
		(width 0.168)
		(layer "In4.Cu")
		(net 75)
	)
	(arc
		(start 142.1985 88.4575)
		(mid 142.337624 88.121624)
		(end 142.6735 87.9825)
		(width 0.168)
		(layer "In4.Cu")
		(net 75)
	)
	(arc
		(start 138.186624 87.7075)
		(mid 138.26717 87.513046)
		(end 138.461624 87.4325)
		(width 0.168)
		(layer "In4.Cu")
		(net 75)
	)
	(arc
		(start 141.0305 87.27)
		(mid 141.366376 87.409124)
		(end 141.5055 87.745)
		(width 0.168)
		(layer "In4.Cu")
		(net 75)
	)
	(arc
		(start 138.786624 87.7075)
		(mid 138.86717 87.901954)
		(end 139.061624 87.9825)
		(width 0.168)
		(layer "In4.Cu")
		(net 75)
	)
	(arc
		(start 137.911624 87.9825)
		(mid 138.106078 87.901954)
		(end 138.186624 87.7075)
		(width 0.168)
		(layer "In4.Cu")
		(net 75)
	)
	(arc
		(start 138.511624 87.4325)
		(mid 138.706078 87.513046)
		(end 138.786624 87.7075)
		(width 0.168)
		(layer "In4.Cu")
		(net 75)
	)
	(arc
		(start 139.8625 87.745)
		(mid 140.001624 87.409124)
		(end 140.3375 87.27)
		(width 0.168)
		(layer "In4.Cu")
		(net 75)
	)
	(segment
		(start 135.906512 93.623)
		(end 135.226512 94.303)
		(width 0.15)
		(layer "F.Cu")
		(net 76)
	)
	(segment
		(start 132.765417 94.303)
		(end 132.762417 94.3)
		(width 0.15)
		(layer "F.Cu")
		(net 76)
	)
	(segment
		(start 168.699999 107.895)
		(end 168.682999 107.878)
		(width 0.15)
		(layer "F.Cu")
		(net 76)
	)
	(segment
		(start 167.514 107.878)
		(end 167.38 108.012)
		(width 0.15)
		(layer "F.Cu")
		(net 76)
	)
	(segment
		(start 136.706512 93.623)
		(end 139.133 91.196512)
		(width 0.15)
		(layer "F.Cu")
		(net 76)
	)
	(segment
		(start 132.762417 94.3)
		(end 131.9 94.3)
		(width 0.15)
		(layer "F.Cu")
		(net 76)
	)
	(segment
		(start 136.706512 93.623)
		(end 135.906512 93.623)
		(width 0.15)
		(layer "F.Cu")
		(net 76)
	)
	(segment
		(start 169.6 107.895)
		(end 168.699999 107.895)
		(width 0.15)
		(layer "F.Cu")
		(net 76)
	)
	(segment
		(start 139.133 87.333)
		(end 139.1 87.3)
		(width 0.15)
		(layer "F.Cu")
		(net 76)
	)
	(segment
		(start 168.682999 107.878)
		(end 167.514 107.878)
		(width 0.15)
		(layer "F.Cu")
		(net 76)
	)
	(segment
		(start 139.133 91.196512)
		(end 139.133 87.333)
		(width 0.15)
		(layer "F.Cu")
		(net 76)
	)
	(segment
		(start 135.226512 94.303)
		(end 132.765417 94.303)
		(width 0.15)
		(layer "F.Cu")
		(net 76)
	)
	(segment
		(start 131.9 94.3)
		(end 131.5 93.9)
		(width 0.15)
		(layer "F.Cu")
		(net 76)
	)
	(via
		(at 167.38 108.012)
		(size 0.45)
		(drill 0.2)
		(layers "F.Cu" "B.Cu")
		(remove_unused_layers yes)
		(keep_end_layers yes)
		(zone_layer_connections)
		(net 76)
	)
	(via
		(at 139.1 87.3)
		(size 0.45)
		(drill 0.2)
		(layers "F.Cu" "B.Cu")
		(remove_unused_layers yes)
		(keep_end_layers yes)
		(zone_layer_connections)
		(net 76)
	)
	(segment
		(start 165.284505 107.8825)
		(end 162.6225 105.220495)
		(width 0.168)
		(layer "In4.Cu")
		(net 76)
	)
	(segment
		(start 139.6725 86.7275)
		(end 139.1 87.3)
		(width 0.168)
		(layer "In4.Cu")
		(net 76)
	)
	(segment
		(start 154.5825 93.098376)
		(end 148.211624 86.7275)
		(width 0.168)
		(layer "In4.Cu")
		(net 76)
	)
	(segment
		(start 162.6225 104.178376)
		(end 154.5825 96.138376)
		(width 0.168)
		(layer "In4.Cu")
		(net 76)
	)
	(segment
		(start 162.6225 105.220495)
		(end 162.6225 104.178376)
		(width 0.168)
		(layer "In4.Cu")
		(net 76)
	)
	(segment
		(start 148.211624 86.7275)
		(end 139.6725 86.7275)
		(width 0.168)
		(layer "In4.Cu")
		(net 76)
	)
	(segment
		(start 167.38 108.012)
		(end 167.2505 107.8825)
		(width 0.168)
		(layer "In4.Cu")
		(net 76)
	)
	(segment
		(start 167.2505 107.8825)
		(end 165.284505 107.8825)
		(width 0.168)
		(layer "In4.Cu")
		(net 76)
	)
	(segment
		(start 154.5825 96.138376)
		(end 154.5825 93.098376)
		(width 0.168)
		(layer "In4.Cu")
		(net 76)
	)
	(segment
		(start 138.567 90.903488)
		(end 138.567 90.753488)
		(width 0.15)
		(layer "F.Cu")
		(net 77)
	)
	(segment
		(start 138.667 87.023488)
		(end 138.865545 86.824943)
		(width 0.15)
		(layer "F.Cu")
		(net 77)
	)
	(segment
		(start 134.183488 94.037)
		(end 134.383488 94.037)
		(width 0.15)
		(layer "F.Cu")
		(net 77)
	)
	(segment
		(start 132.845417 93.837)
		(end 133.183488 93.837)
		(width 0.15)
		(layer "F.Cu")
		(net 77)
	)
	(segment
		(start 135.253867 93.263066)
		(end 135.359934 93.157)
		(width 0.15)
		(layer "F.Cu")
		(net 77)
	)
	(segment
		(start 133.383488 94.037)
		(end 133.583488 94.037)
		(width 0.15)
		(layer "F.Cu")
		(net 77)
	)
	(segment
		(start 135.253867 93.439842)
		(end 135.253868 93.439843)
		(width 0.15)
		(layer "F.Cu")
		(net 77)
	)
	(segment
		(start 138.667 90.503488)
		(end 138.667 87.023488)
		(width 0.15)
		(layer "F.Cu")
		(net 77)
	)
	(segment
		(start 135.359934 93.157)
		(end 135.359934 93.156999)
		(width 0.15)
		(layer "F.Cu")
		(net 77)
	)
	(segment
		(start 136.513488 93.157)
		(end 138.667 91.003488)
		(width 0.15)
		(layer "F.Cu")
		(net 77)
	)
	(segment
		(start 133.783488 93.837)
		(end 133.983488 93.837)
		(width 0.15)
		(layer "F.Cu")
		(net 77)
	)
	(segment
		(start 132.3 93.9)
		(end 132.782417 93.9)
		(width 0.15)
		(layer "F.Cu")
		(net 77)
	)
	(segment
		(start 135.713488 93.157)
		(end 136.513488 93.157)
		(width 0.15)
		(layer "F.Cu")
		(net 77)
	)
	(segment
		(start 169.6 107.395)
		(end 168.699999 107.395)
		(width 0.15)
		(layer "F.Cu")
		(net 77)
	)
	(segment
		(start 138.667 90.653488)
		(end 138.667 90.503488)
		(width 0.15)
		(layer "F.Cu")
		(net 77)
	)
	(segment
		(start 168.682999 107.412)
		(end 167.514 107.412)
		(width 0.15)
		(layer "F.Cu")
		(net 77)
	)
	(segment
		(start 132.782417 93.9)
		(end 132.845417 93.837)
		(width 0.15)
		(layer "F.Cu")
		(net 77)
	)
	(segment
		(start 134.583488 93.837)
		(end 135.033488 93.837)
		(width 0.15)
		(layer "F.Cu")
		(net 77)
	)
	(segment
		(start 135.033488 93.837)
		(end 135.253866 93.616619)
		(width 0.15)
		(layer "F.Cu")
		(net 77)
	)
	(segment
		(start 168.699999 107.395)
		(end 168.682999 107.412)
		(width 0.15)
		(layer "F.Cu")
		(net 77)
	)
	(segment
		(start 138.865545 86.824943)
		(end 138.865545 86.765545)
		(width 0.15)
		(layer "F.Cu")
		(net 77)
	)
	(segment
		(start 167.514 107.412)
		(end 167.38 107.278)
		(width 0.15)
		(layer "F.Cu")
		(net 77)
	)
	(segment
		(start 135.536711 93.157)
		(end 135.53671 93.157)
		(width 0.15)
		(layer "F.Cu")
		(net 77)
	)
	(via
		(at 167.38 107.278)
		(size 0.45)
		(drill 0.2)
		(layers "F.Cu" "B.Cu")
		(remove_unused_layers yes)
		(keep_end_layers yes)
		(zone_layer_connections)
		(net 77)
	)
	(via
		(at 138.865545 86.765545)
		(size 0.45)
		(drill 0.2)
		(layers "F.Cu" "B.Cu")
		(remove_unused_layers yes)
		(keep_end_layers yes)
		(zone_layer_connections)
		(net 77)
	)
	(arc
		(start 138.667 91.003488)
		(mid 138.652355 90.968133)
		(end 138.617 90.953488)
		(width 0.15)
		(layer "F.Cu")
		(net 77)
	)
	(arc
		(start 135.359934 93.156999)
		(mid 135.448323 93.120388)
		(end 135.536711 93.157)
		(width 0.15)
		(layer "F.Cu")
		(net 77)
	)
	(arc
		(start 135.253866 93.616619)
		(mid 135.290478 93.528231)
		(end 135.253867 93.439842)
		(width 0.15)
		(layer "F.Cu")
		(net 77)
	)
	(arc
		(start 133.183488 93.837)
		(mid 133.254199 93.866289)
		(end 133.283488 93.937)
		(width 0.15)
		(layer "F.Cu")
		(net 77)
	)
	(arc
		(start 138.567 90.753488)
		(mid 138.581645 90.718133)
		(end 138.617 90.703488)
		(width 0.15)
		(layer "F.Cu")
		(net 77)
	)
	(arc
		(start 138.617 90.703488)
		(mid 138.652355 90.688843)
		(end 138.667 90.653488)
		(width 0.15)
		(layer "F.Cu")
		(net 77)
	)
	(arc
		(start 134.383488 94.037)
		(mid 134.454199 94.007711)
		(end 134.483488 93.937)
		(width 0.15)
		(layer "F.Cu")
		(net 77)
	)
	(arc
		(start 133.983488 93.837)
		(mid 134.054199 93.866289)
		(end 134.083488 93.937)
		(width 0.15)
		(layer "F.Cu")
		(net 77)
	)
	(arc
		(start 135.53671 93.157)
		(mid 135.625099 93.193612)
		(end 135.713488 93.157)
		(width 0.15)
		(layer "F.Cu")
		(net 77)
	)
	(arc
		(start 135.253868 93.439843)
		(mid 135.217256 93.351455)
		(end 135.253867 93.263066)
		(width 0.15)
		(layer "F.Cu")
		(net 77)
	)
	(arc
		(start 134.083488 93.937)
		(mid 134.112777 94.007711)
		(end 134.183488 94.037)
		(width 0.15)
		(layer "F.Cu")
		(net 77)
	)
	(arc
		(start 133.683488 93.937)
		(mid 133.712777 93.866289)
		(end 133.783488 93.837)
		(width 0.15)
		(layer "F.Cu")
		(net 77)
	)
	(arc
		(start 133.283488 93.937)
		(mid 133.312777 94.007711)
		(end 133.383488 94.037)
		(width 0.15)
		(layer "F.Cu")
		(net 77)
	)
	(arc
		(start 134.483488 93.937)
		(mid 134.512777 93.866289)
		(end 134.583488 93.837)
		(width 0.15)
		(layer "F.Cu")
		(net 77)
	)
	(arc
		(start 133.583488 94.037)
		(mid 133.654199 94.007711)
		(end 133.683488 93.937)
		(width 0.15)
		(layer "F.Cu")
		(net 77)
	)
	(arc
		(start 138.617 90.953488)
		(mid 138.581645 90.938843)
		(end 138.567 90.903488)
		(width 0.15)
		(layer "F.Cu")
		(net 77)
	)
	(segment
		(start 165.481257 107.4075)
		(end 167.2505 107.4075)
		(width 0.168)
		(layer "In4.Cu")
		(net 77)
	)
	(segment
		(start 148.408376 86.2525)
		(end 155.0575 92.901624)
		(width 0.168)
		(layer "In4.Cu")
		(net 77)
	)
	(segment
		(start 139.485648 86.2525)
		(end 138.972603 86.765545)
		(width 0.168)
		(layer "In4.Cu")
		(net 77)
	)
	(segment
		(start 167.2505 107.4075)
		(end 167.38 107.278)
		(width 0.168)
		(layer "In4.Cu")
		(net 77)
	)
	(segment
		(start 155.0575 95.941624)
		(end 163.0975 103.981624)
		(width 0.168)
		(layer "In4.Cu")
		(net 77)
	)
	(segment
		(start 138.972603 86.765545)
		(end 138.865545 86.765545)
		(width 0.168)
		(layer "In4.Cu")
		(net 77)
	)
	(segment
		(start 163.0975 105.023743)
		(end 165.481257 107.4075)
		(width 0.168)
		(layer "In4.Cu")
		(net 77)
	)
	(segment
		(start 163.0975 103.981624)
		(end 163.0975 105.023743)
		(width 0.168)
		(layer "In4.Cu")
		(net 77)
	)
	(segment
		(start 138.865545 86.765545)
		(end 138.918579 86.765545)
		(width 0.168)
		(layer "In4.Cu")
		(net 77)
	)
	(segment
		(start 155.0575 92.901624)
		(end 155.0575 95.941624)
		(width 0.168)
		(layer "In4.Cu")
		(net 77)
	)
	(segment
		(start 148.408376 86.2525)
		(end 139.485648 86.2525)
		(width 0.168)
		(layer "In4.Cu")
		(net 77)
	)
	(segment
		(start 127.5 89.1)
		(end 127.9 88.7)
		(width 0.15)
		(layer "F.Cu")
		(net 78)
	)
	(segment
		(start 169.0702 103.378)
		(end 168.003199 104.445001)
		(width 0.15)
		(layer "F.Cu")
		(net 78)
	)
	(segment
		(start 169.0922 103.4)
		(end 169.0702 103.378)
		(width 0.15)
		(layer "F.Cu")
		(net 78)
	)
	(segment
		(start 167.279999 104.445001)
		(end 167.13 104.595)
		(width 0.15)
		(layer "F.Cu")
		(net 78)
	)
	(segment
		(start 168.003199 104.445001)
		(end 167.279999 104.445001)
		(width 0.15)
		(layer "F.Cu")
		(net 78)
	)
	(via
		(at 127.9 88.7)
		(size 0.45)
		(drill 0.2)
		(layers "F.Cu" "B.Cu")
		(remove_unused_layers yes)
		(keep_end_layers yes)
		(zone_layer_connections)
		(net 78)
	)
	(via
		(at 167.13 104.595)
		(size 0.45)
		(drill 0.2)
		(layers "F.Cu" "B.Cu")
		(remove_unused_layers yes)
		(keep_end_layers yes)
		(zone_layer_connections)
		(net 78)
	)
	(segment
		(start 130.934314 88.3)
		(end 130.784314 88.15)
		(width 0.15)
		(layer "In4.Cu")
		(net 78)
	)
	(segment
		(start 158.1925 90.728376)
		(end 158.1925 96.658376)
		(width 0.168)
		(layer "In4.Cu")
		(net 78)
	)
	(segment
		(start 141.4845 85.053924)
		(end 141.4845 83.576076)
		(width 0.168)
		(layer "In4.Cu")
		(net 78)
	)
	(segment
		(start 130.784314 88.15)
		(end 130.75 88.15)
		(width 0.15)
		(layer "In4.Cu")
		(net 78)
	)
	(segment
		(start 151.941624 84.667005)
		(end 151.941624 84.667004)
		(width 0.168)
		(layer "In4.Cu")
		(net 78)
	)
	(segment
		(start 165.988124 104.454)
		(end 166.989 104.454)
		(width 0.168)
		(layer "In4.Cu")
		(net 78)
	)
	(segment
		(start 127.9 88.7)
		(end 128.3 88.3)
		(width 0.15)
		(layer "In4.Cu")
		(net 78)
	)
	(segment
		(start 130.465686 88.3)
		(end 130.615686 88.15)
		(width 0.15)
		(layer "In4.Cu")
		(net 78)
	)
	(segment
		(start 132.390885 88.15)
		(end 132.536385 88.2955)
		(width 0.15)
		(layer "In4.Cu")
		(net 78)
	)
	(segment
		(start 131.265686 88.3)
		(end 130.934314 88.3)
		(width 0.15)
		(layer "In4.Cu")
		(net 78)
	)
	(segment
		(start 152.490038 85.841101)
		(end 153.065568 85.265568)
		(width 0.168)
		(layer "In4.Cu")
		(net 78)
	)
	(segment
		(start 144.4565 84.751462)
		(end 144.4565 84.513962)
		(width 0.168)
		(layer "In4.Cu")
		(net 78)
	)
	(segment
		(start 128.95 88.3)
		(end 129.1 88.15)
		(width 0.15)
		(layer "In4.Cu")
		(net 78)
	)
	(segment
		(start 131.415686 88.15)
		(end 131.265686 88.3)
		(width 0.15)
		(layer "In4.Cu")
		(net 78)
	)
	(segment
		(start 143.2385 83.576076)
		(end 143.2385 84.751462)
		(width 0.168)
		(layer "In4.Cu")
		(net 78)
	)
	(segment
		(start 139.673426 84.4775)
		(end 140.1325 84.4775)
		(width 0.168)
		(layer "In4.Cu")
		(net 78)
	)
	(segment
		(start 153.517762 86.053638)
		(end 158.1925 90.728376)
		(width 0.168)
		(layer "In4.Cu")
		(net 78)
	)
	(segment
		(start 158.1925 96.658376)
		(end 165.988124 104.454)
		(width 0.168)
		(layer "In4.Cu")
		(net 78)
	)
	(segment
		(start 141.7525 83.576076)
		(end 141.7525 85.053924)
		(width 0.168)
		(layer "In4.Cu")
		(net 78)
	)
	(segment
		(start 131.45 88.15)
		(end 131.415686 88.15)
		(width 0.15)
		(layer "In4.Cu")
		(net 78)
	)
	(segment
		(start 128.3 88.3)
		(end 128.95 88.3)
		(width 0.15)
		(layer "In4.Cu")
		(net 78)
	)
	(segment
		(start 130.75 88.15)
		(end 130.615686 88.15)
		(width 0.15)
		(layer "In4.Cu")
		(net 78)
	)
	(segment
		(start 142.9705 85.053924)
		(end 142.9705 83.576076)
		(width 0.168)
		(layer "In4.Cu")
		(net 78)
	)
	(segment
		(start 153.830604 84.879543)
		(end 153.830605 84.879542)
		(width 0.168)
		(layer "In4.Cu")
		(net 78)
	)
	(segment
		(start 153.830605 84.879542)
		(end 153.517762 85.192382)
		(width 0.168)
		(layer "In4.Cu")
		(net 78)
	)
	(segment
		(start 133.05 88.15)
		(end 136.000926 88.15)
		(width 0.168)
		(layer "In4.Cu")
		(net 78)
	)
	(segment
		(start 151.941624 84.4775)
		(end 151.941624 84.477499)
		(width 0.168)
		(layer "In4.Cu")
		(net 78)
	)
	(segment
		(start 153.517763 86.053639)
		(end 153.517762 86.053638)
		(width 0.168)
		(layer "In4.Cu")
		(net 78)
	)
	(segment
		(start 132.536385 88.2955)
		(end 132.9045 88.2955)
		(width 0.15)
		(layer "In4.Cu")
		(net 78)
	)
	(segment
		(start 129.971586 88.15)
		(end 129.985793 88.164207)
		(width 0.168)
		(layer "In4.Cu")
		(net 78)
	)
	(segment
		(start 144.492962 84.4775)
		(end 151.941624 84.4775)
		(width 0.168)
		(layer "In4.Cu")
		(net 78)
	)
	(segment
		(start 130.465686 88.3)
		(end 130.134314 88.3)
		(width 0.15)
		(layer "In4.Cu")
		(net 78)
	)
	(segment
		(start 136.000926 88.15)
		(end 139.673426 84.4775)
		(width 0.168)
		(layer "In4.Cu")
		(net 78)
	)
	(segment
		(start 130.134314 88.3)
		(end 129.992157 88.157843)
		(width 0.15)
		(layer "In4.Cu")
		(net 78)
	)
	(segment
		(start 143.749962 85.262924)
		(end 143.945038 85.262924)
		(width 0.168)
		(layer "In4.Cu")
		(net 78)
	)
	(segment
		(start 151.628783 85.841102)
		(end 151.628782 85.841101)
		(width 0.168)
		(layer "In4.Cu")
		(net 78)
	)
	(segment
		(start 129.1 88.15)
		(end 129.971586 88.15)
		(width 0.168)
		(layer "In4.Cu")
		(net 78)
	)
	(segment
		(start 132.9045 88.2955)
		(end 133.05 88.15)
		(width 0.15)
		(layer "In4.Cu")
		(net 78)
	)
	(segment
		(start 153.065568 85.265568)
		(end 153.641101 84.690038)
		(width 0.168)
		(layer "In4.Cu")
		(net 78)
	)
	(segment
		(start 140.2665 84.6115)
		(end 140.2665 85.053924)
		(width 0.168)
		(layer "In4.Cu")
		(net 78)
	)
	(segment
		(start 152.490039 85.8411)
		(end 152.490038 85.841101)
		(width 0.168)
		(layer "In4.Cu")
		(net 78)
	)
	(segment
		(start 131.45 88.15)
		(end 132.35 88.15)
		(width 0.168)
		(layer "In4.Cu")
		(net 78)
	)
	(segment
		(start 132.35 88.15)
		(end 132.390885 88.15)
		(width 0.15)
		(layer "In4.Cu")
		(net 78)
	)
	(segment
		(start 166.989 104.454)
		(end 167.13 104.595)
		(width 0.168)
		(layer "In4.Cu")
		(net 78)
	)
	(segment
		(start 151.941624 84.667004)
		(end 151.628782 84.979845)
		(width 0.168)
		(layer "In4.Cu")
		(net 78)
	)
	(arc
		(start 153.641101 84.690038)
		(mid 153.735853 84.65079)
		(end 153.830605 84.690038)
		(width 0.168)
		(layer "In4.Cu")
		(net 78)
	)
	(arc
		(start 140.2665 85.053924)
		(mid 140.444872 85.484552)
		(end 140.8755 85.662924)
		(width 0.168)
		(layer "In4.Cu")
		(net 78)
	)
	(arc
		(start 142.3615 85.662924)
		(mid 142.792128 85.484552)
		(end 142.9705 85.053924)
		(width 0.168)
		(layer "In4.Cu")
		(net 78)
	)
	(arc
		(start 141.6185 83.442076)
		(mid 141.713252 83.481324)
		(end 141.7525 83.576076)
		(width 0.168)
		(layer "In4.Cu")
		(net 78)
	)
	(arc
		(start 141.7525 85.053924)
		(mid 141.930872 85.484552)
		(end 142.3615 85.662924)
		(width 0.168)
		(layer "In4.Cu")
		(net 78)
	)
	(arc
		(start 151.628782 84.979845)
		(mid 151.45041 85.410474)
		(end 151.628783 85.841102)
		(width 0.168)
		(layer "In4.Cu")
		(net 78)
	)
	(arc
		(start 141.4845 83.576076)
		(mid 141.523748 83.481324)
		(end 141.6185 83.442076)
		(width 0.168)
		(layer "In4.Cu")
		(net 78)
	)
	(arc
		(start 143.2385 84.751462)
		(mid 143.388304 85.11312)
		(end 143.749962 85.262924)
		(width 0.168)
		(layer "In4.Cu")
		(net 78)
	)
	(arc
		(start 153.517762 85.192382)
		(mid 153.339391 85.623012)
		(end 153.517763 86.053639)
		(width 0.168)
		(layer "In4.Cu")
		(net 78)
	)
	(arc
		(start 153.830605 84.690038)
		(mid 153.869852 84.784791)
		(end 153.830604 84.879543)
		(width 0.168)
		(layer "In4.Cu")
		(net 78)
	)
	(arc
		(start 140.1325 84.4775)
		(mid 140.227252 84.516748)
		(end 140.2665 84.6115)
		(width 0.168)
		(layer "In4.Cu")
		(net 78)
	)
	(arc
		(start 143.1045 83.442076)
		(mid 143.199252 83.481324)
		(end 143.2385 83.576076)
		(width 0.168)
		(layer "In4.Cu")
		(net 78)
	)
	(arc
		(start 143.945038 85.262924)
		(mid 144.306696 85.11312)
		(end 144.4565 84.751462)
		(width 0.168)
		(layer "In4.Cu")
		(net 78)
	)
	(arc
		(start 151.628782 85.841101)
		(mid 152.059411 86.019473)
		(end 152.490039 85.8411)
		(width 0.168)
		(layer "In4.Cu")
		(net 78)
	)
	(arc
		(start 151.941624 84.477499)
		(mid 151.980872 84.572252)
		(end 151.941624 84.667005)
		(width 0.168)
		(layer "In4.Cu")
		(net 78)
	)
	(arc
		(start 142.9705 83.576076)
		(mid 143.009748 83.481324)
		(end 143.1045 83.442076)
		(width 0.168)
		(layer "In4.Cu")
		(net 78)
	)
	(arc
		(start 140.8755 85.662924)
		(mid 141.306128 85.484552)
		(end 141.4845 85.053924)
		(width 0.168)
		(layer "In4.Cu")
		(net 78)
	)
	(arc
		(start 144.4565 84.513962)
		(mid 144.467179 84.488179)
		(end 144.492962 84.4775)
		(width 0.168)
		(layer "In4.Cu")
		(net 78)
	)
	(segment
		(start 167.816801 103.994999)
		(end 167.279999 103.994999)
		(width 0.15)
		(layer "F.Cu")
		(net 79)
	)
	(segment
		(start 168.8998 102.912)
		(end 167.816801 103.994999)
		(width 0.15)
		(layer "F.Cu")
		(net 79)
	)
	(segment
		(start 167.279999 103.994999)
		(end 167.13 103.845)
		(width 0.15)
		(layer "F.Cu")
		(net 79)
	)
	(segment
		(start 168.8998 102.912)
		(end 169.583 102.912)
		(width 0.15)
		(layer "F.Cu")
		(net 79)
	)
	(segment
		(start 127.9 87.9)
		(end 128.3 88.3)
		(width 0.15)
		(layer "F.Cu")
		(net 79)
	)
	(via
		(at 127.9 87.9)
		(size 0.45)
		(drill 0.2)
		(layers "F.Cu" "B.Cu")
		(remove_unused_layers yes)
		(keep_end_layers yes)
		(zone_layer_connections)
		(net 79)
	)
	(via
		(at 167.13 103.845)
		(size 0.45)
		(drill 0.2)
		(layers "F.Cu" "B.Cu")
		(remove_unused_layers yes)
		(keep_end_layers yes)
		(zone_layer_connections)
		(net 79)
	)
	(segment
		(start 153.853638 85.717762)
		(end 158.6675 90.531624)
		(width 0.168)
		(layer "In4.Cu")
		(net 79)
	)
	(segment
		(start 130.134314 87.5)
		(end 130.465686 87.5)
		(width 0.15)
		(layer "In4.Cu")
		(net 79)
	)
	(segment
		(start 128.534314 87.5)
		(end 128.95 87.5)
		(width 0.15)
		(layer "In4.Cu")
		(net 79)
	)
	(segment
		(start 142.4955 85.053924)
		(end 142.4955 83.576076)
		(width 0.168)
		(layer "In4.Cu")
		(net 79)
	)
	(segment
		(start 143.9815 84.751462)
		(end 143.9815 84.513962)
		(width 0.168)
		(layer "In4.Cu")
		(net 79)
	)
	(segment
		(start 132.35 87.65)
		(end 132.391885 87.65)
		(width 0.15)
		(layer "In4.Cu")
		(net 79)
	)
	(segment
		(start 133.05 87.65)
		(end 135.839074 87.65)
		(width 0.168)
		(layer "In4.Cu")
		(net 79)
	)
	(segment
		(start 152.154162 85.505224)
		(end 152.154161 85.505225)
		(width 0.168)
		(layer "In4.Cu")
		(net 79)
	)
	(segment
		(start 153.853639 85.717763)
		(end 153.853638 85.717762)
		(width 0.168)
		(layer "In4.Cu")
		(net 79)
	)
	(segment
		(start 130.784314 87.65)
		(end 130.75 87.65)
		(width 0.15)
		(layer "In4.Cu")
		(net 79)
	)
	(segment
		(start 130.615686 87.65)
		(end 130.465686 87.5)
		(width 0.15)
		(layer "In4.Cu")
		(net 79)
	)
	(segment
		(start 139.486574 84.0025)
		(end 140.1325 84.0025)
		(width 0.168)
		(layer "In4.Cu")
		(net 79)
	)
	(segment
		(start 152.154161 85.505225)
		(end 153.305223 84.35416)
		(width 0.168)
		(layer "In4.Cu")
		(net 79)
	)
	(segment
		(start 142.2275 83.576076)
		(end 142.2275 85.053924)
		(width 0.168)
		(layer "In4.Cu")
		(net 79)
	)
	(segment
		(start 140.7415 84.6115)
		(end 140.7415 85.053924)
		(width 0.168)
		(layer "In4.Cu")
		(net 79)
	)
	(segment
		(start 132.536385 87.5055)
		(end 132.9055 87.5055)
		(width 0.15)
		(layer "In4.Cu")
		(net 79)
	)
	(segment
		(start 143.749962 84.787924)
		(end 143.945038 84.787924)
		(width 0.168)
		(layer "In4.Cu")
		(net 79)
	)
	(segment
		(start 141.0095 85.053924)
		(end 141.0095 83.576076)
		(width 0.168)
		(layer "In4.Cu")
		(net 79)
	)
	(segment
		(start 132.391885 87.65)
		(end 132.536385 87.5055)
		(width 0.15)
		(layer "In4.Cu")
		(net 79)
	)
	(segment
		(start 144.492962 84.0025)
		(end 152.138376 84.0025)
		(width 0.168)
		(layer "In4.Cu")
		(net 79)
	)
	(segment
		(start 131.45 87.65)
		(end 131.415686 87.65)
		(width 0.15)
		(layer "In4.Cu")
		(net 79)
	)
	(segment
		(start 128.95 87.5)
		(end 129.1 87.65)
		(width 0.15)
		(layer "In4.Cu")
		(net 79)
	)
	(segment
		(start 128.134314 87.9)
		(end 128.534314 87.5)
		(width 0.15)
		(layer "In4.Cu")
		(net 79)
	)
	(segment
		(start 130.75 87.65)
		(end 130.615686 87.65)
		(width 0.15)
		(layer "In4.Cu")
		(net 79)
	)
	(segment
		(start 131.265686 87.5)
		(end 130.934314 87.5)
		(width 0.15)
		(layer "In4.Cu")
		(net 79)
	)
	(segment
		(start 158.6675 90.531624)
		(end 158.6675 96.461624)
		(width 0.168)
		(layer "In4.Cu")
		(net 79)
	)
	(segment
		(start 130.934314 87.5)
		(end 130.784314 87.65)
		(width 0.15)
		(layer "In4.Cu")
		(net 79)
	)
	(segment
		(start 151.964658 85.505226)
		(end 151.964657 85.505225)
		(width 0.168)
		(layer "In4.Cu")
		(net 79)
	)
	(segment
		(start 129.1 87.65)
		(end 129.971586 87.65)
		(width 0.168)
		(layer "In4.Cu")
		(net 79)
	)
	(segment
		(start 131.45 87.65)
		(end 132.35 87.65)
		(width 0.168)
		(layer "In4.Cu")
		(net 79)
	)
	(segment
		(start 154.166481 85.215418)
		(end 153.853638 85.528258)
		(width 0.168)
		(layer "In4.Cu")
		(net 79)
	)
	(segment
		(start 143.7135 83.576076)
		(end 143.7135 84.751462)
		(width 0.168)
		(layer "In4.Cu")
		(net 79)
	)
	(segment
		(start 166.191876 103.986)
		(end 166.989 103.986)
		(width 0.168)
		(layer "In4.Cu")
		(net 79)
	)
	(segment
		(start 130.134314 87.5)
		(end 129.982157 87.652157)
		(width 0.15)
		(layer "In4.Cu")
		(net 79)
	)
	(segment
		(start 135.839074 87.65)
		(end 139.486574 84.0025)
		(width 0.168)
		(layer "In4.Cu")
		(net 79)
	)
	(segment
		(start 132.9055 87.5055)
		(end 133.05 87.65)
		(width 0.15)
		(layer "In4.Cu")
		(net 79)
	)
	(segment
		(start 166.989 103.986)
		(end 167.13 103.845)
		(width 0.168)
		(layer "In4.Cu")
		(net 79)
	)
	(segment
		(start 129.971586 87.65)
		(end 129.975793 87.645793)
		(width 0.168)
		(layer "In4.Cu")
		(net 79)
	)
	(segment
		(start 127.9 87.9)
		(end 128.134314 87.9)
		(width 0.15)
		(layer "In4.Cu")
		(net 79)
	)
	(segment
		(start 131.415686 87.65)
		(end 131.265686 87.5)
		(width 0.15)
		(layer "In4.Cu")
		(net 79)
	)
	(segment
		(start 154.16648 85.215419)
		(end 154.166481 85.215418)
		(width 0.168)
		(layer "In4.Cu")
		(net 79)
	)
	(segment
		(start 152.277499 85.00288)
		(end 151.964657 85.315721)
		(width 0.168)
		(layer "In4.Cu")
		(net 79)
	)
	(segment
		(start 152.138376 84.0025)
		(end 152.277499 84.141624)
		(width 0.168)
		(layer "In4.Cu")
		(net 79)
	)
	(segment
		(start 158.6675 96.461624)
		(end 166.191876 103.986)
		(width 0.168)
		(layer "In4.Cu")
		(net 79)
	)
	(arc
		(start 141.0095 83.576076)
		(mid 141.187872 83.145448)
		(end 141.6185 82.967076)
		(width 0.168)
		(layer "In4.Cu")
		(net 79)
	)
	(arc
		(start 140.8755 85.187924)
		(mid 140.970252 85.148676)
		(end 141.0095 85.053924)
		(width 0.168)
		(layer "In4.Cu")
		(net 79)
	)
	(arc
		(start 143.9815 84.513962)
		(mid 144.131304 84.152304)
		(end 144.492962 84.0025)
		(width 0.168)
		(layer "In4.Cu")
		(net 79)
	)
	(arc
		(start 142.4955 83.576076)
		(mid 142.673872 83.145448)
		(end 143.1045 82.967076)
		(width 0.168)
		(layer "In4.Cu")
		(net 79)
	)
	(arc
		(start 143.1045 82.967076)
		(mid 143.535128 83.145448)
		(end 143.7135 83.576076)
		(width 0.168)
		(layer "In4.Cu")
		(net 79)
	)
	(arc
		(start 141.6185 82.967076)
		(mid 142.049128 83.145448)
		(end 142.2275 83.576076)
		(width 0.168)
		(layer "In4.Cu")
		(net 79)
	)
	(arc
		(start 143.7135 84.751462)
		(mid 143.724179 84.777245)
		(end 143.749962 84.787924)
		(width 0.168)
		(layer "In4.Cu")
		(net 79)
	)
	(arc
		(start 151.964657 85.505225)
		(mid 152.05941 85.544472)
		(end 152.154162 85.505224)
		(width 0.168)
		(layer "In4.Cu")
		(net 79)
	)
	(arc
		(start 142.3615 85.187924)
		(mid 142.456252 85.148676)
		(end 142.4955 85.053924)
		(width 0.168)
		(layer "In4.Cu")
		(net 79)
	)
	(arc
		(start 153.305223 84.35416)
		(mid 153.735851 84.175788)
		(end 154.166481 84.354162)
		(width 0.168)
		(layer "In4.Cu")
		(net 79)
	)
	(arc
		(start 140.1325 84.0025)
		(mid 140.563128 84.180872)
		(end 140.7415 84.6115)
		(width 0.168)
		(layer "In4.Cu")
		(net 79)
	)
	(arc
		(start 154.166481 84.354162)
		(mid 154.344852 84.78479)
		(end 154.16648 85.215419)
		(width 0.168)
		(layer "In4.Cu")
		(net 79)
	)
	(arc
		(start 152.277499 84.141624)
		(mid 152.455871 84.572252)
		(end 152.277499 85.00288)
		(width 0.168)
		(layer "In4.Cu")
		(net 79)
	)
	(arc
		(start 140.7415 85.053924)
		(mid 140.780748 85.148676)
		(end 140.8755 85.187924)
		(width 0.168)
		(layer "In4.Cu")
		(net 79)
	)
	(arc
		(start 143.945038 84.787924)
		(mid 143.970821 84.777245)
		(end 143.9815 84.751462)
		(width 0.168)
		(layer "In4.Cu")
		(net 79)
	)
	(arc
		(start 142.2275 85.053924)
		(mid 142.266748 85.148676)
		(end 142.3615 85.187924)
		(width 0.168)
		(layer "In4.Cu")
		(net 79)
	)
	(arc
		(start 151.964657 85.315721)
		(mid 151.92541 85.410474)
		(end 151.964658 85.505226)
		(width 0.168)
		(layer "In4.Cu")
		(net 79)
	)
	(arc
		(start 153.853638 85.528258)
		(mid 153.814391 85.623011)
		(end 153.853639 85.717763)
		(width 0.168)
		(layer "In4.Cu")
		(net 79)
	)
	(segment
		(start 165.0815 94.57)
		(end 165.2225 94.711)
		(width 0.15)
		(layer "F.Cu")
		(net 80)
	)
	(segment
		(start 168.682999 102.378)
		(end 168.699999 102.395)
		(width 0.15)
		(layer "F.Cu")
		(net 80)
	)
	(segment
		(start 127.5 87.5)
		(end 127.1 87.9)
		(width 0.15)
		(layer "F.Cu")
		(net 80)
	)
	(segment
		(start 166.698488 102.378)
		(end 168.682999 102.378)
		(width 0.15)
		(layer "F.Cu")
		(net 80)
	)
	(segment
		(start 165.2225 94.711)
		(end 165.217 94.7165)
		(width 0.15)
		(layer "F.Cu")
		(net 80)
	)
	(segment
		(start 165.217 100.896512)
		(end 166.698488 102.378)
		(width 0.15)
		(layer "F.Cu")
		(net 80)
	)
	(segment
		(start 165.217 94.7165)
		(end 165.217 100.896512)
		(width 0.15)
		(layer "F.Cu")
		(net 80)
	)
	(segment
		(start 168.699999 102.395)
		(end 169.6 102.395)
		(width 0.15)
		(layer "F.Cu")
		(net 80)
	)
	(via
		(at 165.0815 94.57)
		(size 0.45)
		(drill 0.2)
		(layers "F.Cu" "B.Cu")
		(remove_unused_layers yes)
		(keep_end_layers yes)
		(zone_layer_connections)
		(net 80)
	)
	(via
		(at 127.1 87.9)
		(size 0.45)
		(drill 0.2)
		(layers "F.Cu" "B.Cu")
		(remove_unused_layers yes)
		(keep_end_layers yes)
		(zone_layer_connections)
		(net 80)
	)
	(segment
		(start 130.66899 82.961933)
		(end 130.668991 82.961934)
		(width 0.168)
		(layer "In4.Cu")
		(net 80)
	)
	(segment
		(start 130.668991 82.961934)
		(end 134.463426 79.1675)
		(width 0.168)
		(layer "In4.Cu")
		(net 80)
	)
	(segment
		(start 128.063615 87.495)
		(end 128.3 87.258615)
		(width 0.15)
		(layer "In4.Cu")
		(net 80)
	)
	(segment
		(start 128.3 85.95)
		(end 128.184 85.834)
		(width 0.168)
		(layer "In4.Cu")
		(net 80)
	)
	(segment
		(start 128.184 85.446926)
		(end 128.735463 84.895463)
		(width 0.168)
		(layer "In4.Cu")
		(net 80)
	)
	(segment
		(start 129.619345 84.612619)
		(end 129.619345 84.61262)
		(width 0.168)
		(layer "In4.Cu")
		(net 80)
	)
	(segment
		(start 127.1 87.9)
		(end 127.505 87.495)
		(width 0.15)
		(layer "In4.Cu")
		(net 80)
	)
	(segment
		(start 129.619345 84.61262)
		(end 129.513278 84.506553)
		(width 0.168)
		(layer "In4.Cu")
		(net 80)
	)
	(segment
		(start 127.505 87.495)
		(end 128.063615 87.495)
		(width 0.15)
		(layer "In4.Cu")
		(net 80)
	)
	(segment
		(start 165.2225 94.429)
		(end 165.2225 87.198376)
		(width 0.168)
		(layer "In4.Cu")
		(net 80)
	)
	(segment
		(start 157.191624 79.1675)
		(end 165.2225 87.198376)
		(width 0.168)
		(layer "In4.Cu")
		(net 80)
	)
	(segment
		(start 130.244727 83.810463)
		(end 130.386148 83.951884)
		(width 0.168)
		(layer "In4.Cu")
		(net 80)
	)
	(segment
		(start 128.184 85.834)
		(end 128.184 85.446926)
		(width 0.168)
		(layer "In4.Cu")
		(net 80)
	)
	(segment
		(start 129.513278 84.117645)
		(end 129.820463 83.810463)
		(width 0.168)
		(layer "In4.Cu")
		(net 80)
	)
	(segment
		(start 134.463426 79.1675)
		(end 157.191624 79.1675)
		(width 0.168)
		(layer "In4.Cu")
		(net 80)
	)
	(segment
		(start 129.619346 85.001528)
		(end 129.619345 85.001529)
		(width 0.168)
		(layer "In4.Cu")
		(net 80)
	)
	(segment
		(start 129.124371 84.895463)
		(end 129.230437 85.001529)
		(width 0.168)
		(layer "In4.Cu")
		(net 80)
	)
	(segment
		(start 128.3 86.2)
		(end 128.3 85.95)
		(width 0.168)
		(layer "In4.Cu")
		(net 80)
	)
	(segment
		(start 128.3 87.258615)
		(end 128.3 86.2)
		(width 0.15)
		(layer "In4.Cu")
		(net 80)
	)
	(segment
		(start 165.0815 94.57)
		(end 165.2225 94.429)
		(width 0.168)
		(layer "In4.Cu")
		(net 80)
	)
	(segment
		(start 129.513279 84.117644)
		(end 129.513278 84.117645)
		(width 0.168)
		(layer "In4.Cu")
		(net 80)
	)
	(segment
		(start 130.810412 83.527619)
		(end 130.66899 83.386197)
		(width 0.168)
		(layer "In4.Cu")
		(net 80)
	)
	(segment
		(start 130.810412 83.527618)
		(end 130.810412 83.527619)
		(width 0.168)
		(layer "In4.Cu")
		(net 80)
	)
	(arc
		(start 129.230437 85.001529)
		(mid 129.424892 85.082074)
		(end 129.619346 85.001528)
		(width 0.168)
		(layer "In4.Cu")
		(net 80)
	)
	(arc
		(start 130.66899 83.386197)
		(mid 130.581122 83.174065)
		(end 130.66899 82.961933)
		(width 0.168)
		(layer "In4.Cu")
		(net 80)
	)
	(arc
		(start 130.810412 83.951884)
		(mid 130.89828 83.739751)
		(end 130.810412 83.527618)
		(width 0.168)
		(layer "In4.Cu")
		(net 80)
	)
	(arc
		(start 128.735463 84.895463)
		(mid 128.929917 84.814918)
		(end 129.124371 84.895463)
		(width 0.168)
		(layer "In4.Cu")
		(net 80)
	)
	(arc
		(start 129.619345 85.001529)
		(mid 129.699891 84.807074)
		(end 129.619345 84.612619)
		(width 0.168)
		(layer "In4.Cu")
		(net 80)
	)
	(arc
		(start 129.820463 83.810463)
		(mid 130.032595 83.722595)
		(end 130.244727 83.810463)
		(width 0.168)
		(layer "In4.Cu")
		(net 80)
	)
	(arc
		(start 130.386148 83.951884)
		(mid 130.59828 84.039752)
		(end 130.810412 83.951884)
		(width 0.168)
		(layer "In4.Cu")
		(net 80)
	)
	(arc
		(start 129.513278 84.506553)
		(mid 129.432733 84.312098)
		(end 129.513279 84.117644)
		(width 0.168)
		(layer "In4.Cu")
		(net 80)
	)
	(segment
		(start 168.682999 101.912)
		(end 168.699999 101.895)
		(width 0.15)
		(layer "F.Cu")
		(net 81)
	)
	(segment
		(start 165.8385 94.57)
		(end 165.6975 94.711)
		(width 0.15)
		(layer "F.Cu")
		(net 81)
	)
	(segment
		(start 166.891512 101.912)
		(end 168.682999 101.912)
		(width 0.15)
		(layer "F.Cu")
		(net 81)
	)
	(segment
		(start 127.5 88.3)
		(end 127.1 88.7)
		(width 0.15)
		(layer "F.Cu")
		(net 81)
	)
	(segment
		(start 165.683 100.703488)
		(end 166.891512 101.912)
		(width 0.15)
		(layer "F.Cu")
		(net 81)
	)
	(segment
		(start 165.683 94.7255)
		(end 165.683 100.703488)
		(width 0.15)
		(layer "F.Cu")
		(net 81)
	)
	(segment
		(start 165.6975 94.711)
		(end 165.683 94.7255)
		(width 0.15)
		(layer "F.Cu")
		(net 81)
	)
	(segment
		(start 168.699999 101.895)
		(end 169.6 101.895)
		(width 0.15)
		(layer "F.Cu")
		(net 81)
	)
	(via
		(at 165.8385 94.57)
		(size 0.45)
		(drill 0.2)
		(layers "F.Cu" "B.Cu")
		(remove_unused_layers yes)
		(keep_end_layers yes)
		(zone_layer_connections)
		(net 81)
	)
	(via
		(at 127.1 88.7)
		(size 0.45)
		(drill 0.2)
		(layers "F.Cu" "B.Cu")
		(remove_unused_layers yes)
		(keep_end_layers yes)
		(zone_layer_connections)
		(net 81)
	)
	(segment
		(start 126.7 88.3)
		(end 126.7 87.47)
		(width 0.15)
		(layer "In4.Cu")
		(net 81)
	)
	(segment
		(start 165.8385 94.57)
		(end 165.6975 94.429)
		(width 0.168)
		(layer "In4.Cu")
		(net 81)
	)
	(segment
		(start 126.699496 87.469496)
		(end 126.699496 86.880504)
		(width 0.15)
		(layer "In4.Cu")
		(net 81)
	)
	(segment
		(start 126.87 86.71)
		(end 127.267843 86.71)
		(width 0.15)
		(layer "In4.Cu")
		(net 81)
	)
	(segment
		(start 127.267843 86.71)
		(end 127.5 86.477843)
		(width 0.15)
		(layer "In4.Cu")
		(net 81)
	)
	(segment
		(start 165.6975 94.429)
		(end 165.6975 87.001624)
		(width 0.168)
		(layer "In4.Cu")
		(net 81)
	)
	(segment
		(start 127.716 85.253074)
		(end 127.716 85.834)
		(width 0.168)
		(layer "In4.Cu")
		(net 81)
	)
	(segment
		(start 165.6975 87.001624)
		(end 157.388376 78.6925)
		(width 0.168)
		(layer "In4.Cu")
		(net 81)
	)
	(segment
		(start 127.1 88.7)
		(end 126.7 88.3)
		(width 0.15)
		(layer "In4.Cu")
		(net 81)
	)
	(segment
		(start 157.388376 78.6925)
		(end 134.276574 78.6925)
		(width 0.168)
		(layer "In4.Cu")
		(net 81)
	)
	(segment
		(start 126.699496 86.880504)
		(end 126.87 86.71)
		(width 0.15)
		(layer "In4.Cu")
		(net 81)
	)
	(segment
		(start 127.716 85.834)
		(end 127.5 86.05)
		(width 0.168)
		(layer "In4.Cu")
		(net 81)
	)
	(segment
		(start 126.7 87.47)
		(end 126.699496 87.469496)
		(width 0.15)
		(layer "In4.Cu")
		(net 81)
	)
	(segment
		(start 134.276574 78.6925)
		(end 127.716 85.253074)
		(width 0.168)
		(layer "In4.Cu")
		(net 81)
	)
	(segment
		(start 127.5 86.477843)
		(end 127.5 86.05)
		(width 0.15)
		(layer "In4.Cu")
		(net 81)
	)
	(segment
		(start 169.6 101.395)
		(end 168.699999 101.395)
		(width 0.15)
		(layer "F.Cu")
		(net 82)
	)
	(segment
		(start 129.9 87.5)
		(end 130.31 87.09)
		(width 0.15)
		(layer "F.Cu")
		(net 82)
	)
	(segment
		(start 166.717 99.108859)
		(end 166.509997 98.901856)
		(width 0.15)
		(layer "F.Cu")
		(net 82)
	)
	(segment
		(start 168.699999 101.395)
		(end 168.682999 101.378)
		(width 0.15)
		(layer "F.Cu")
		(net 82)
	)
	(segment
		(start 168.682999 101.378)
		(end 167.668488 101.378)
		(width 0.15)
		(layer "F.Cu")
		(net 82)
	)
	(segment
		(start 166.509997 98.901856)
		(end 166.320491 98.901856)
		(width 0.15)
		(layer "F.Cu")
		(net 82)
	)
	(segment
		(start 167.668488 101.378)
		(end 166.717 100.426512)
		(width 0.15)
		(layer "F.Cu")
		(net 82)
	)
	(segment
		(start 166.717 100.426512)
		(end 166.717 99.108859)
		(width 0.15)
		(layer "F.Cu")
		(net 82)
	)
	(via
		(at 130.31 87.09)
		(size 0.45)
		(drill 0.2)
		(layers "F.Cu" "B.Cu")
		(remove_unused_layers yes)
		(keep_end_layers yes)
		(zone_layer_connections)
		(net 82)
	)
	(via
		(at 166.320491 98.901856)
		(size 0.45)
		(drill 0.2)
		(layers "F.Cu" "B.Cu")
		(remove_unused_layers yes)
		(keep_end_layers yes)
		(zone_layer_connections)
		(net 82)
	)
	(segment
		(start 130.705 86.470686)
		(end 130.7 86.465686)
		(width 0.15)
		(layer "In4.Cu")
		(net 82)
	)
	(segment
		(start 161.896345 85.529022)
		(end 161.896344 85.529022)
		(width 0.168)
		(layer "In4.Cu")
		(net 82)
	)
	(segment
		(start 130.31 87.09)
		(end 130.705 86.695)
		(width 0.15)
		(layer "In4.Cu")
		(net 82)
	)
	(segment
		(start 160.610825 86.178148)
		(end 161.578148 85.210825)
		(width 0.168)
		(layer "In4.Cu")
		(net 82)
	)
	(segment
		(start 161.730881 86.661808)
		(end 161.730881 86.661807)
		(width 0.168)
		(layer "In4.Cu")
		(net 82)
	)
	(segment
		(start 158.332531 84.867176)
		(end 158.345258 84.879903)
		(width 0.168)
		(layer "In4.Cu")
		(net 82)
	)
	(segment
		(start 157.988884 81.316091)
		(end 157.988883 81.31609)
		(width 0.168)
		(layer "In4.Cu")
		(net 82)
	)
	(segment
		(start 159.287128 82.614335)
		(end 159.299855 82.627062)
		(width 0.168)
		(layer "In4.Cu")
		(net 82)
	)
	(segment
		(start 166.320491 98.713764)
		(end 166.320491 98.901856)
		(width 0.168)
		(layer "In4.Cu")
		(net 82)
	)
	(segment
		(start 161.883619 85.210826)
		(end 161.883618 85.210825)
		(width 0.168)
		(layer "In4.Cu")
		(net 82)
	)
	(segment
		(start 132.546926 83.384)
		(end 133.346926 83.384)
		(width 0.168)
		(layer "In4.Cu")
		(net 82)
	)
	(segment
		(start 131.134 85.244981)
		(end 131.134 84.796926)
		(width 0.168)
		(layer "In4.Cu")
		(net 82)
	)
	(segment
		(start 158.001609 81.634287)
		(end 157.034286 82.601609)
		(width 0.168)
		(layer "In4.Cu")
		(net 82)
	)
	(segment
		(start 131.1 85.278981)
		(end 131.134 85.244981)
		(width 0.15)
		(layer "In4.Cu")
		(net 82)
	)
	(segment
		(start 158.014335 83.581658)
		(end 158.981658 82.614335)
		(width 0.168)
		(layer "In4.Cu")
		(net 82)
	)
	(segment
		(start 156.769123 82.230379)
		(end 157.683413 81.31609)
		(width 0.168)
		(layer "In4.Cu")
		(net 82)
	)
	(segment
		(start 130.705 86.695)
		(end 130.705 86.470686)
		(width 0.15)
		(layer "In4.Cu")
		(net 82)
	)
	(segment
		(start 158.332532 84.867177)
		(end 158.332531 84.867176)
		(width 0.168)
		(layer "In4.Cu")
		(net 82)
	)
	(segment
		(start 159.287129 82.614336)
		(end 159.287128 82.614335)
		(width 0.168)
		(layer "In4.Cu")
		(net 82)
	)
	(segment
		(start 159.299854 82.932532)
		(end 158.332531 83.899854)
		(width 0.168)
		(layer "In4.Cu")
		(net 82)
	)
	(segment
		(start 135.977675 80.753251)
		(end 155.822325 80.753251)
		(width 0.168)
		(layer "In4.Cu")
		(net 82)
	)
	(segment
		(start 155.822325 80.753251)
		(end 155.954537 80.885462)
		(width 0.168)
		(layer "In4.Cu")
		(net 82)
	)
	(segment
		(start 160.585373 83.91258)
		(end 160.5981 83.925307)
		(width 0.168)
		(layer "In4.Cu")
		(net 82)
	)
	(segment
		(start 157.034287 83.568932)
		(end 157.034286 83.568931)
		(width 0.168)
		(layer "In4.Cu")
		(net 82)
	)
	(segment
		(start 155.789074 82.111586)
		(end 155.907867 82.230379)
		(width 0.168)
		(layer "In4.Cu")
		(net 82)
	)
	(segment
		(start 159.630776 86.165421)
		(end 159.643503 86.178148)
		(width 0.168)
		(layer "In4.Cu")
		(net 82)
	)
	(segment
		(start 162.346 94.739273)
		(end 166.320491 98.713764)
		(width 0.168)
		(layer "In4.Cu")
		(net 82)
	)
	(segment
		(start 130.7 86.465686)
		(end 130.7 86)
		(width 0.15)
		(layer "In4.Cu")
		(net 82)
	)
	(segment
		(start 157.034286 83.568931)
		(end 157.047013 83.581658)
		(width 0.168)
		(layer "In4.Cu")
		(net 82)
	)
	(segment
		(start 159.31258 84.879903)
		(end 160.279903 83.91258)
		(width 0.168)
		(layer "In4.Cu")
		(net 82)
	)
	(segment
		(start 158.00161 81.634287)
		(end 158.001609 81.634287)
		(width 0.168)
		(layer "In4.Cu")
		(net 82)
	)
	(segment
		(start 161.730881 86.661807)
		(end 162.346 87.276926)
		(width 0.168)
		(layer "In4.Cu")
		(net 82)
	)
	(segment
		(start 131.134 84.796926)
		(end 132.546926 83.384)
		(width 0.168)
		(layer "In4.Cu")
		(net 82)
	)
	(segment
		(start 159.630777 86.165422)
		(end 159.630776 86.165421)
		(width 0.168)
		(layer "In4.Cu")
		(net 82)
	)
	(segment
		(start 157.988883 81.31609)
		(end 158.00161 81.328817)
		(width 0.168)
		(layer "In4.Cu")
		(net 82)
	)
	(segment
		(start 161.896344 85.529022)
		(end 161.730882 85.694485)
		(width 0.168)
		(layer "In4.Cu")
		(net 82)
	)
	(segment
		(start 160.585374 83.912581)
		(end 160.585373 83.91258)
		(width 0.168)
		(layer "In4.Cu")
		(net 82)
	)
	(segment
		(start 155.954537 81.084867)
		(end 155.789074 81.250329)
		(width 0.168)
		(layer "In4.Cu")
		(net 82)
	)
	(segment
		(start 133.346926 83.384)
		(end 135.977675 80.753251)
		(width 0.168)
		(layer "In4.Cu")
		(net 82)
	)
	(segment
		(start 161.883618 85.210825)
		(end 161.896345 85.223552)
		(width 0.168)
		(layer "In4.Cu")
		(net 82)
	)
	(segment
		(start 155.954537 81.084868)
		(end 155.954537 81.084867)
		(width 0.168)
		(layer "In4.Cu")
		(net 82)
	)
	(segment
		(start 162.346 87.276926)
		(end 162.346 94.739273)
		(width 0.168)
		(layer "In4.Cu")
		(net 82)
	)
	(segment
		(start 155.789073 82.111586)
		(end 155.789074 82.111586)
		(width 0.168)
		(layer "In4.Cu")
		(net 82)
	)
	(segment
		(start 159.299855 82.932532)
		(end 159.299854 82.932532)
		(width 0.168)
		(layer "In4.Cu")
		(net 82)
	)
	(segment
		(start 131.1 85.6)
		(end 131.1 85.278981)
		(width 0.15)
		(layer "In4.Cu")
		(net 82)
	)
	(segment
		(start 130.7 86)
		(end 131.1 85.6)
		(width 0.15)
		(layer "In4.Cu")
		(net 82)
	)
	(segment
		(start 160.5981 84.230777)
		(end 160.598099 84.230777)
		(width 0.168)
		(layer "In4.Cu")
		(net 82)
	)
	(segment
		(start 160.598099 84.230777)
		(end 159.630776 85.198099)
		(width 0.168)
		(layer "In4.Cu")
		(net 82)
	)
	(arc
		(start 160.5981 83.925307)
		(mid 160.661365 84.078042)
		(end 160.5981 84.230777)
		(width 0.168)
		(layer "In4.Cu")
		(net 82)
	)
	(arc
		(start 157.047013 83.581658)
		(mid 157.530674 83.781997)
		(end 158.014335 83.581658)
		(width 0.168)
		(layer "In4.Cu")
		(net 82)
	)
	(arc
		(start 155.789074 81.250329)
		(mid 155.610701 81.680957)
		(end 155.789073 82.111586)
		(width 0.168)
		(layer "In4.Cu")
		(net 82)
	)
	(arc
		(start 161.578148 85.210825)
		(mid 161.730883 85.147559)
		(end 161.883619 85.210826)
		(width 0.168)
		(layer "In4.Cu")
		(net 82)
	)
	(arc
		(start 161.730882 85.694485)
		(mid 161.530541 86.178145)
		(end 161.730881 86.661808)
		(width 0.168)
		(layer "In4.Cu")
		(net 82)
	)
	(arc
		(start 157.034286 82.601609)
		(mid 156.833947 83.085271)
		(end 157.034287 83.568932)
		(width 0.168)
		(layer "In4.Cu")
		(net 82)
	)
	(arc
		(start 157.683413 81.31609)
		(mid 157.836148 81.252824)
		(end 157.988884 81.316091)
		(width 0.168)
		(layer "In4.Cu")
		(net 82)
	)
	(arc
		(start 155.907867 82.230379)
		(mid 156.338495 82.408751)
		(end 156.769123 82.230379)
		(width 0.168)
		(layer "In4.Cu")
		(net 82)
	)
	(arc
		(start 158.00161 81.328817)
		(mid 158.064875 81.481552)
		(end 158.00161 81.634287)
		(width 0.168)
		(layer "In4.Cu")
		(net 82)
	)
	(arc
		(start 158.332531 83.899854)
		(mid 158.132192 84.383516)
		(end 158.332532 84.867177)
		(width 0.168)
		(layer "In4.Cu")
		(net 82)
	)
	(arc
		(start 158.981658 82.614335)
		(mid 159.134393 82.551069)
		(end 159.287129 82.614336)
		(width 0.168)
		(layer "In4.Cu")
		(net 82)
	)
	(arc
		(start 159.630776 85.198099)
		(mid 159.430437 85.681761)
		(end 159.630777 86.165422)
		(width 0.168)
		(layer "In4.Cu")
		(net 82)
	)
	(arc
		(start 158.345258 84.879903)
		(mid 158.828919 85.080242)
		(end 159.31258 84.879903)
		(width 0.168)
		(layer "In4.Cu")
		(net 82)
	)
	(arc
		(start 159.643503 86.178148)
		(mid 160.127164 86.378487)
		(end 160.610825 86.178148)
		(width 0.168)
		(layer "In4.Cu")
		(net 82)
	)
	(arc
		(start 160.279903 83.91258)
		(mid 160.432638 83.849314)
		(end 160.585374 83.912581)
		(width 0.168)
		(layer "In4.Cu")
		(net 82)
	)
	(arc
		(start 159.299855 82.627062)
		(mid 159.36312 82.779797)
		(end 159.299855 82.932532)
		(width 0.168)
		(layer "In4.Cu")
		(net 82)
	)
	(arc
		(start 161.896345 85.223552)
		(mid 161.95961 85.376287)
		(end 161.896345 85.529022)
		(width 0.168)
		(layer "In4.Cu")
		(net 82)
	)
	(arc
		(start 155.954537 80.885462)
		(mid 155.995835 80.985165)
		(end 155.954537 81.084868)
		(width 0.168)
		(layer "In4.Cu")
		(net 82)
	)
	(segment
		(start 167.183 100.233488)
		(end 167.183 98.915835)
		(width 0.15)
		(layer "F.Cu")
		(net 83)
	)
	(segment
		(start 168.699999 100.895)
		(end 168.682999 100.912)
		(width 0.15)
		(layer "F.Cu")
		(net 83)
	)
	(segment
		(start 130.3 86.3)
		(end 129.9 86.7)
		(width 0.15)
		(layer "F.Cu")
		(net 83)
	)
	(segment
		(start 167.861512 100.912)
		(end 167.183 100.233488)
		(width 0.15)
		(layer "F.Cu")
		(net 83)
	)
	(segment
		(start 166.839509 98.572344)
		(end 166.839509 98.382838)
		(width 0.15)
		(layer "F.Cu")
		(net 83)
	)
	(segment
		(start 168.682999 100.912)
		(end 167.861512 100.912)
		(width 0.15)
		(layer "F.Cu")
		(net 83)
	)
	(segment
		(start 169.6 100.895)
		(end 168.699999 100.895)
		(width 0.15)
		(layer "F.Cu")
		(net 83)
	)
	(segment
		(start 167.183 98.915835)
		(end 166.839509 98.572344)
		(width 0.15)
		(layer "F.Cu")
		(net 83)
	)
	(via
		(at 166.839509 98.382838)
		(size 0.45)
		(drill 0.2)
		(layers "F.Cu" "B.Cu")
		(remove_unused_layers yes)
		(keep_end_layers yes)
		(zone_layer_connections)
		(net 83)
	)
	(via
		(at 130.3 86.3)
		(size 0.45)
		(drill 0.2)
		(layers "F.Cu" "B.Cu")
		(remove_unused_layers yes)
		(keep_end_layers yes)
		(zone_layer_connections)
		(net 83)
	)
	(segment
		(start 132.353074 82.916)
		(end 130.666 84.603074)
		(width 0.168)
		(layer "In4.Cu")
		(net 83)
	)
	(segment
		(start 130.3 86.035378)
		(end 130.694998 85.64038)
		(width 0.15)
		(layer "In4.Cu")
		(net 83)
	)
	(segment
		(start 157.365212 83.238005)
		(end 157.365213 83.238006)
		(width 0.168)
		(layer "In4.Cu")
		(net 83)
	)
	(segment
		(start 162.227271 84.892626)
		(end 162.214544 84.879899)
		(width 0.168)
		(layer "In4.Cu")
		(net 83)
	)
	(segment
		(start 157.352485 80.985162)
		(end 156.438197 81.899453)
		(width 0.168)
		(layer "In4.Cu")
		(net 83)
	)
	(segment
		(start 159.618054 82.283409)
		(end 159.618055 82.28341)
		(width 0.168)
		(layer "In4.Cu")
		(net 83)
	)
	(segment
		(start 130.694998 85.64038)
		(end 130.694998 85.273979)
		(width 0.15)
		(layer "In4.Cu")
		(net 83)
	)
	(segment
		(start 160.929026 83.594381)
		(end 160.916299 83.581654)
		(width 0.168)
		(layer "In4.Cu")
		(net 83)
	)
	(segment
		(start 166.651417 98.382838)
		(end 162.814 94.545421)
		(width 0.168)
		(layer "In4.Cu")
		(net 83)
	)
	(segment
		(start 159.312581 83.581655)
		(end 159.630781 83.263458)
		(width 0.168)
		(layer "In4.Cu")
		(net 83)
	)
	(segment
		(start 162.814 93.945421)
		(end 162.814 87.083074)
		(width 0.168)
		(layer "In4.Cu")
		(net 83)
	)
	(segment
		(start 162.914 94.445421)
		(end 162.914 94.045421)
		(width 0.168)
		(layer "In4.Cu")
		(net 83)
	)
	(segment
		(start 157.377939 83.250732)
		(end 157.365212 83.238005)
		(width 0.168)
		(layer "In4.Cu")
		(net 83)
	)
	(segment
		(start 162.814 87.083074)
		(end 162.061806 86.33088)
		(width 0.168)
		(layer "In4.Cu")
		(net 83)
	)
	(segment
		(start 158.981655 84.548977)
		(end 158.981654 84.548977)
		(width 0.168)
		(layer "In4.Cu")
		(net 83)
	)
	(segment
		(start 161.24722 84.879897)
		(end 160.2799 85.847222)
		(width 0.168)
		(layer "In4.Cu")
		(net 83)
	)
	(segment
		(start 159.974429 85.847222)
		(end 159.961702 85.834495)
		(width 0.168)
		(layer "In4.Cu")
		(net 83)
	)
	(segment
		(start 162.061807 86.025409)
		(end 162.227271 85.859948)
		(width 0.168)
		(layer "In4.Cu")
		(net 83)
	)
	(segment
		(start 159.948975 83.581652)
		(end 158.981655 84.548977)
		(width 0.168)
		(layer "In4.Cu")
		(net 83)
	)
	(segment
		(start 166.839509 98.382838)
		(end 166.651417 98.382838)
		(width 0.168)
		(layer "In4.Cu")
		(net 83)
	)
	(segment
		(start 156.238792 81.899453)
		(end 156.119999 81.78066)
		(width 0.168)
		(layer "In4.Cu")
		(net 83)
	)
	(segment
		(start 156.438197 81.899453)
		(end 156.438196 81.899453)
		(width 0.168)
		(layer "In4.Cu")
		(net 83)
	)
	(segment
		(start 158.676184 84.548977)
		(end 158.663457 84.53625)
		(width 0.168)
		(layer "In4.Cu")
		(net 83)
	)
	(segment
		(start 157.68341 83.250732)
		(end 157.683409 83.250732)
		(width 0.168)
		(layer "In4.Cu")
		(net 83)
	)
	(segment
		(start 159.961702 85.834495)
		(end 159.961703 85.834496)
		(width 0.168)
		(layer "In4.Cu")
		(net 83)
	)
	(segment
		(start 157.365212 82.932535)
		(end 158.014336 82.28341)
		(width 0.168)
		(layer "In4.Cu")
		(net 83)
	)
	(segment
		(start 158.014336 82.28341)
		(end 158.332536 81.965213)
		(width 0.168)
		(layer "In4.Cu")
		(net 83)
	)
	(segment
		(start 156.285462 80.554537)
		(end 156.016177 80.285251)
		(width 0.168)
		(layer "In4.Cu")
		(net 83)
	)
	(segment
		(start 158.663457 84.23078)
		(end 159.312581 83.581655)
		(width 0.168)
		(layer "In4.Cu")
		(net 83)
	)
	(segment
		(start 133.153074 82.916)
		(end 132.353074 82.916)
		(width 0.168)
		(layer "In4.Cu")
		(net 83)
	)
	(segment
		(start 159.961702 85.529025)
		(end 160.610826 84.8799)
		(width 0.168)
		(layer "In4.Cu")
		(net 83)
	)
	(segment
		(start 162.214544 84.879899)
		(end 162.214545 84.8799)
		(width 0.168)
		(layer "In4.Cu")
		(net 83)
	)
	(segment
		(start 158.319809 80.985164)
		(end 158.31981 80.985165)
		(width 0.168)
		(layer "In4.Cu")
		(net 83)
	)
	(segment
		(start 158.332536 80.997891)
		(end 158.319809 80.985164)
		(width 0.168)
		(layer "In4.Cu")
		(net 83)
	)
	(segment
		(start 159.630781 82.296136)
		(end 159.618054 82.283409)
		(width 0.168)
		(layer "In4.Cu")
		(net 83)
	)
	(segment
		(start 130.666 84.603074)
		(end 130.666 85.244981)
		(width 0.168)
		(layer "In4.Cu")
		(net 83)
	)
	(segment
		(start 135.783823 80.285251)
		(end 133.153074 82.916)
		(width 0.168)
		(layer "In4.Cu")
		(net 83)
	)
	(segment
		(start 156.016177 80.285251)
		(end 135.783823 80.285251)
		(width 0.168)
		(layer "In4.Cu")
		(net 83)
	)
	(segment
		(start 156.119999 81.581255)
		(end 156.285462 81.415793)
		(width 0.168)
		(layer "In4.Cu")
		(net 83)
	)
	(segment
		(start 156.119999 81.78066)
		(end 156.119998 81.78066)
		(width 0.168)
		(layer "In4.Cu")
		(net 83)
	)
	(segment
		(start 158.65073 82.283407)
		(end 157.68341 83.250732)
		(width 0.168)
		(layer "In4.Cu")
		(net 83)
	)
	(segment
		(start 130.3 86.3)
		(end 130.3 86.035378)
		(width 0.15)
		(layer "In4.Cu")
		(net 83)
	)
	(segment
		(start 160.2799 85.847222)
		(end 160.279899 85.847222)
		(width 0.168)
		(layer "In4.Cu")
		(net 83)
	)
	(segment
		(start 130.694998 85.273979)
		(end 130.666 85.244981)
		(width 0.15)
		(layer "In4.Cu")
		(net 83)
	)
	(segment
		(start 160.610826 84.8799)
		(end 160.929026 84.561703)
		(width 0.168)
		(layer "In4.Cu")
		(net 83)
	)
	(segment
		(start 160.916299 83.581654)
		(end 160.9163 83.581655)
		(width 0.168)
		(layer "In4.Cu")
		(net 83)
	)
	(segment
		(start 158.663457 84.53625)
		(end 158.663458 84.536251)
		(width 0.168)
		(layer "In4.Cu")
		(net 83)
	)
	(arc
		(start 162.061806 86.33088)
		(mid 161.998542 86.178145)
		(end 162.061807 86.025409)
		(width 0.168)
		(layer "In4.Cu")
		(net 83)
	)
	(arc
		(start 156.285462 81.415793)
		(mid 156.463834 80.985165)
		(end 156.285462 80.554537)
		(width 0.168)
		(layer "In4.Cu")
		(net 83)
	)
	(arc
		(start 158.31981 80.985165)
		(mid 157.836148 80.784824)
		(end 157.352485 80.985162)
		(width 0.168)
		(layer "In4.Cu")
		(net 83)
	)
	(arc
		(start 162.864 94.495421)
		(mid 162.899355 94.480776)
		(end 162.914 94.445421)
		(width 0.168)
		(layer "In4.Cu")
		(net 83)
	)
	(arc
		(start 159.961703 85.834496)
		(mid 159.898437 85.681761)
		(end 159.961702 85.529025)
		(width 0.168)
		(layer "In4.Cu")
		(net 83)
	)
	(arc
		(start 156.119998 81.78066)
		(mid 156.0787 81.680957)
		(end 156.119999 81.581255)
		(width 0.168)
		(layer "In4.Cu")
		(net 83)
	)
	(arc
		(start 158.981654 84.548977)
		(mid 158.828919 84.612242)
		(end 158.676184 84.548977)
		(width 0.168)
		(layer "In4.Cu")
		(net 83)
	)
	(arc
		(start 159.630781 83.263458)
		(mid 159.83112 82.779797)
		(end 159.630781 82.296136)
		(width 0.168)
		(layer "In4.Cu")
		(net 83)
	)
	(arc
		(start 162.864 93.995421)
		(mid 162.828645 93.980776)
		(end 162.814 93.945421)
		(width 0.168)
		(layer "In4.Cu")
		(net 83)
	)
	(arc
		(start 157.683409 83.250732)
		(mid 157.530674 83.313997)
		(end 157.377939 83.250732)
		(width 0.168)
		(layer "In4.Cu")
		(net 83)
	)
	(arc
		(start 160.929026 84.561703)
		(mid 161.129365 84.078042)
		(end 160.929026 83.594381)
		(width 0.168)
		(layer "In4.Cu")
		(net 83)
	)
	(arc
		(start 160.279899 85.847222)
		(mid 160.127164 85.910487)
		(end 159.974429 85.847222)
		(width 0.168)
		(layer "In4.Cu")
		(net 83)
	)
	(arc
		(start 159.618055 82.28341)
		(mid 159.134393 82.083069)
		(end 158.65073 82.283407)
		(width 0.168)
		(layer "In4.Cu")
		(net 83)
	)
	(arc
		(start 162.814 94.545421)
		(mid 162.828645 94.510066)
		(end 162.864 94.495421)
		(width 0.168)
		(layer "In4.Cu")
		(net 83)
	)
	(arc
		(start 162.227271 85.859948)
		(mid 162.42761 85.376287)
		(end 162.227271 84.892626)
		(width 0.168)
		(layer "In4.Cu")
		(net 83)
	)
	(arc
		(start 160.9163 83.581655)
		(mid 160.432638 83.381314)
		(end 159.948975 83.581652)
		(width 0.168)
		(layer "In4.Cu")
		(net 83)
	)
	(arc
		(start 156.438196 81.899453)
		(mid 156.338494 81.940751)
		(end 156.238792 81.899453)
		(width 0.168)
		(layer "In4.Cu")
		(net 83)
	)
	(arc
		(start 158.332536 81.965213)
		(mid 158.532875 81.481552)
		(end 158.332536 80.997891)
		(width 0.168)
		(layer "In4.Cu")
		(net 83)
	)
	(arc
		(start 157.365213 83.238006)
		(mid 157.301947 83.085271)
		(end 157.365212 82.932535)
		(width 0.168)
		(layer "In4.Cu")
		(net 83)
	)
	(arc
		(start 162.914 94.045421)
		(mid 162.899355 94.010066)
		(end 162.864 93.995421)
		(width 0.168)
		(layer "In4.Cu")
		(net 83)
	)
	(arc
		(start 162.214545 84.8799)
		(mid 161.730883 84.679559)
		(end 161.24722 84.879897)
		(width 0.168)
		(layer "In4.Cu")
		(net 83)
	)
	(arc
		(start 158.663458 84.536251)
		(mid 158.600192 84.383516)
		(end 158.663457 84.23078)
		(width 0.168)
		(layer "In4.Cu")
		(net 83)
	)
	(segment
		(start 168.744986 100.378)
		(end 168.255333 99.888347)
		(width 0.15)
		(layer "F.Cu")
		(net 84)
	)
	(segment
		(start 167.867016 99.888347)
		(end 167.733016 100.022347)
		(width 0.15)
		(layer "F.Cu")
		(net 84)
	)
	(segment
		(start 131.1 87.06)
		(end 130.74 86.7)
		(width 0.15)
		(layer "F.Cu")
		(net 84)
	)
	(segment
		(start 131.1 87.1)
		(end 131.1 87.06)
		(width 0.15)
		(layer "F.Cu")
		(net 84)
	)
	(segment
		(start 169.133 100.378)
		(end 168.744986 100.378)
		(width 0.15)
		(layer "F.Cu")
		(net 84)
	)
	(segment
		(start 168.255333 99.888347)
		(end 167.867016 99.888347)
		(width 0.15)
		(layer "F.Cu")
		(net 84)
	)
	(via
		(at 131.1 87.1)
		(size 0.45)
		(drill 0.2)
		(layers "F.Cu" "B.Cu")
		(remove_unused_layers yes)
		(keep_end_layers yes)
		(zone_layer_connections)
		(net 84)
	)
	(via
		(at 167.733016 100.022347)
		(size 0.45)
		(drill 0.2)
		(layers "F.Cu" "B.Cu")
		(remove_unused_layers yes)
		(keep_end_layers yes)
		(zone_layer_connections)
		(net 84)
	)
	(segment
		(start 138.496926 82.684)
		(end 143.866 82.684)
		(width 0.168)
		(layer "In4.Cu")
		(net 84)
	)
	(segment
		(start 158.135804 86.71102)
		(end 157.161057 87.685766)
		(width 0.168)
		(layer "In4.Cu")
		(net 84)
	)
	(segment
		(start 146.1 82.984)
		(end 146.1 81.916)
		(width 0.168)
		(layer "In4.Cu")
		(net 84)
	)
	(segment
		(start 131.5 86.134314)
		(end 131.734314 85.9)
		(width 0.15)
		(layer "In4.Cu")
		(net 84)
	)
	(segment
		(start 155.989032 86.513741)
		(end 156.601385 85.901385)
		(width 0.168)
		(layer "In4.Cu")
		(net 84)
	)
	(segment
		(start 153.048124 82.684)
		(end 154.952061 84.587936)
		(width 0.168)
		(layer "In4.Cu")
		(net 84)
	)
	(segment
		(start 156.601385 85.901385)
		(end 157.213741 85.289032)
		(width 0.168)
		(layer "In4.Cu")
		(net 84)
	)
	(segment
		(start 144.466 81.85)
		(end 144.716 81.85)
		(width 0.168)
		(layer "In4.Cu")
		(net 84)
	)
	(segment
		(start 131.1 87.1)
		(end 131.5 86.7)
		(width 0.15)
		(layer "In4.Cu")
		(net 84)
	)
	(segment
		(start 144.782 81.916)
		(end 144.782 82.984)
		(width 0.168)
		(layer "In4.Cu")
		(net 84)
	)
	(segment
		(start 135.280926 85.9)
		(end 138.496926 82.684)
		(width 0.168)
		(layer "In4.Cu")
		(net 84)
	)
	(segment
		(start 160.3125 89.948376)
		(end 160.3125 96.448376)
		(width 0.168)
		(layer "In4.Cu")
		(net 84)
	)
	(segment
		(start 157.053579 86.689455)
		(end 157.053578 86.689453)
		(width 0.168)
		(layer "In4.Cu")
		(net 84)
	)
	(segment
		(start 158.022314 88.547021)
		(end 158.022313 88.547022)
		(width 0.168)
		(layer "In4.Cu")
		(net 84)
	)
	(segment
		(start 157.778364 86.689455)
		(end 157.9463 86.521516)
		(width 0.168)
		(layer "In4.Cu")
		(net 84)
	)
	(segment
		(start 157.999334 86.521517)
		(end 158.135805 86.657988)
		(width 0.168)
		(layer "In4.Cu")
		(net 84)
	)
	(segment
		(start 157.403244 85.478537)
		(end 157.403245 85.478536)
		(width 0.168)
		(layer "In4.Cu")
		(net 84)
	)
	(segment
		(start 158.561482 88.197358)
		(end 158.561481 88.197357)
		(width 0.168)
		(layer "In4.Cu")
		(net 84)
	)
	(segment
		(start 145.316 83.518)
		(end 145.566 83.518)
		(width 0.168)
		(layer "In4.Cu")
		(net 84)
	)
	(segment
		(start 157.999333 86.521515)
		(end 157.999334 86.521517)
		(width 0.168)
		(layer "In4.Cu")
		(net 84)
	)
	(segment
		(start 146.166 81.85)
		(end 146.416 81.85)
		(width 0.168)
		(layer "In4.Cu")
		(net 84)
	)
	(segment
		(start 147.866 81.85)
		(end 148.116 81.85)
		(width 0.168)
		(layer "In4.Cu")
		(net 84)
	)
	(segment
		(start 163.756971 99.892847)
		(end 167.603516 99.892847)
		(width 0.168)
		(layer "In4.Cu")
		(net 84)
	)
	(segment
		(start 158.022313 88.547022)
		(end 158.371977 88.197357)
		(width 0.168)
		(layer "In4.Cu")
		(net 84)
	)
	(segment
		(start 144.4 82.15)
		(end 144.4 81.916)
		(width 0.168)
		(layer "In4.Cu")
		(net 84)
	)
	(segment
		(start 155.989033 86.51374)
		(end 155.989032 86.513741)
		(width 0.168)
		(layer "In4.Cu")
		(net 84)
	)
	(segment
		(start 148.716 83.518)
		(end 148.966 83.518)
		(width 0.168)
		(layer "In4.Cu")
		(net 84)
	)
	(segment
		(start 157.403245 85.478536)
		(end 157.053579 85.828199)
		(width 0.168)
		(layer "In4.Cu")
		(net 84)
	)
	(segment
		(start 149.566 82.684)
		(end 153.048124 82.684)
		(width 0.168)
		(layer "In4.Cu")
		(net 84)
	)
	(segment
		(start 147.8 82.984)
		(end 147.8 81.916)
		(width 0.168)
		(layer "In4.Cu")
		(net 84)
	)
	(segment
		(start 156.352485 84.427777)
		(end 156.352486 84.427776)
		(width 0.168)
		(layer "In4.Cu")
		(net 84)
	)
	(segment
		(start 131.734314 85.9)
		(end 132.15 85.9)
		(width 0.15)
		(layer "In4.Cu")
		(net 84)
	)
	(segment
		(start 146.482 81.916)
		(end 146.482 82.984)
		(width 0.168)
		(layer "In4.Cu")
		(net 84)
	)
	(segment
		(start 158.135806 86.711021)
		(end 158.135804 86.71102)
		(width 0.168)
		(layer "In4.Cu")
		(net 84)
	)
	(segment
		(start 155.813319 84.587938)
		(end 156.162982 84.238272)
		(width 0.168)
		(layer "In4.Cu")
		(net 84)
	)
	(segment
		(start 147.016 83.518)
		(end 147.266 83.518)
		(width 0.168)
		(layer "In4.Cu")
		(net 84)
	)
	(segment
		(start 131.5 86.7)
		(end 131.5 86.134314)
		(width 0.15)
		(layer "In4.Cu")
		(net 84)
	)
	(segment
		(start 160.3125 96.448376)
		(end 163.756971 99.892847)
		(width 0.168)
		(layer "In4.Cu")
		(net 84)
	)
	(segment
		(start 149.5 82.984)
		(end 149.5 82.75)
		(width 0.168)
		(layer "In4.Cu")
		(net 84)
	)
	(segment
		(start 167.603516 99.892847)
		(end 167.733016 100.022347)
		(width 0.168)
		(layer "In4.Cu")
		(net 84)
	)
	(segment
		(start 158.561481 88.197357)
		(end 160.3125 89.948376)
		(width 0.168)
		(layer "In4.Cu")
		(net 84)
	)
	(segment
		(start 156.352487 84.238273)
		(end 156.352486 84.238272)
		(width 0.168)
		(layer "In4.Cu")
		(net 84)
	)
	(segment
		(start 132.15 85.9)
		(end 135.280926 85.9)
		(width 0.168)
		(layer "In4.Cu")
		(net 84)
	)
	(segment
		(start 156.352486 84.427776)
		(end 155.127776 85.652485)
		(width 0.168)
		(layer "In4.Cu")
		(net 84)
	)
	(segment
		(start 148.182 81.916)
		(end 148.182 82.984)
		(width 0.168)
		(layer "In4.Cu")
		(net 84)
	)
	(arc
		(start 148.182 82.984)
		(mid 148.338405 83.361595)
		(end 148.716 83.518)
		(width 0.168)
		(layer "In4.Cu")
		(net 84)
	)
	(arc
		(start 145.566 83.518)
		(mid 145.943595 83.361595)
		(end 146.1 82.984)
		(width 0.168)
		(layer "In4.Cu")
		(net 84)
	)
	(arc
		(start 144.782 82.984)
		(mid 144.938405 83.361595)
		(end 145.316 83.518)
		(width 0.168)
		(layer "In4.Cu")
		(net 84)
	)
	(arc
		(start 157.403245 85.289032)
		(mid 157.442492 85.383785)
		(end 157.403244 85.478537)
		(width 0.168)
		(layer "In4.Cu")
		(net 84)
	)
	(arc
		(start 155.127776 85.652485)
		(mid 154.949404 86.083113)
		(end 155.127776 86.513741)
		(width 0.168)
		(layer "In4.Cu")
		(net 84)
	)
	(arc
		(start 146.1 81.916)
		(mid 146.119331 81.869331)
		(end 146.166 81.85)
		(width 0.168)
		(layer "In4.Cu")
		(net 84)
	)
	(arc
		(start 157.053579 85.828199)
		(mid 156.875207 86.258827)
		(end 157.053579 86.689455)
		(width 0.168)
		(layer "In4.Cu")
		(net 84)
	)
	(arc
		(start 144.716 81.85)
		(mid 144.762669 81.869331)
		(end 144.782 81.916)
		(width 0.168)
		(layer "In4.Cu")
		(net 84)
	)
	(arc
		(start 157.053578 86.689453)
		(mid 157.415972 86.839563)
		(end 157.778364 86.689455)
		(width 0.168)
		(layer "In4.Cu")
		(net 84)
	)
	(arc
		(start 154.952061 84.587936)
		(mid 155.382691 84.76631)
		(end 155.813319 84.587938)
		(width 0.168)
		(layer "In4.Cu")
		(net 84)
	)
	(arc
		(start 146.416 81.85)
		(mid 146.462669 81.869331)
		(end 146.482 81.916)
		(width 0.168)
		(layer "In4.Cu")
		(net 84)
	)
	(arc
		(start 147.266 83.518)
		(mid 147.643595 83.361595)
		(end 147.8 82.984)
		(width 0.168)
		(layer "In4.Cu")
		(net 84)
	)
	(arc
		(start 148.966 83.518)
		(mid 149.343595 83.361595)
		(end 149.5 82.984)
		(width 0.168)
		(layer "In4.Cu")
		(net 84)
	)
	(arc
		(start 156.162982 84.238272)
		(mid 156.257735 84.199025)
		(end 156.352487 84.238273)
		(width 0.168)
		(layer "In4.Cu")
		(net 84)
	)
	(arc
		(start 156.352486 84.238272)
		(mid 156.391733 84.333025)
		(end 156.352485 84.427777)
		(width 0.168)
		(layer "In4.Cu")
		(net 84)
	)
	(arc
		(start 148.116 81.85)
		(mid 148.162669 81.869331)
		(end 148.182 81.916)
		(width 0.168)
		(layer "In4.Cu")
		(net 84)
	)
	(arc
		(start 157.161057 88.547022)
		(mid 157.591686 88.725394)
		(end 158.022314 88.547021)
		(width 0.168)
		(layer "In4.Cu")
		(net 84)
	)
	(arc
		(start 157.213741 85.289032)
		(mid 157.308493 85.249784)
		(end 157.403245 85.289032)
		(width 0.168)
		(layer "In4.Cu")
		(net 84)
	)
	(arc
		(start 158.371977 88.197357)
		(mid 158.46673 88.15811)
		(end 158.561482 88.197358)
		(width 0.168)
		(layer "In4.Cu")
		(net 84)
	)
	(arc
		(start 144.4 81.916)
		(mid 144.419331 81.869331)
		(end 144.466 81.85)
		(width 0.168)
		(layer "In4.Cu")
		(net 84)
	)
	(arc
		(start 146.482 82.984)
		(mid 146.638405 83.361595)
		(end 147.016 83.518)
		(width 0.168)
		(layer "In4.Cu")
		(net 84)
	)
	(arc
		(start 143.866 82.684)
		(mid 144.243595 82.527595)
		(end 144.4 82.15)
		(width 0.168)
		(layer "In4.Cu")
		(net 84)
	)
	(arc
		(start 147.8 81.916)
		(mid 147.819331 81.869331)
		(end 147.866 81.85)
		(width 0.168)
		(layer "In4.Cu")
		(net 84)
	)
	(arc
		(start 155.127776 86.513741)
		(mid 155.558405 86.692113)
		(end 155.989033 86.51374)
		(width 0.168)
		(layer "In4.Cu")
		(net 84)
	)
	(arc
		(start 158.135805 86.657988)
		(mid 158.146789 86.684504)
		(end 158.135806 86.711021)
		(width 0.168)
		(layer "In4.Cu")
		(net 84)
	)
	(arc
		(start 149.5 82.75)
		(mid 149.519331 82.703331)
		(end 149.566 82.684)
		(width 0.168)
		(layer "In4.Cu")
		(net 84)
	)
	(arc
		(start 157.9463 86.521516)
		(mid 157.972816 86.510532)
		(end 157.999333 86.521515)
		(width 0.168)
		(layer "In4.Cu")
		(net 84)
	)
	(arc
		(start 157.161057 87.685766)
		(mid 156.982685 88.116394)
		(end 157.161057 88.547022)
		(width 0.168)
		(layer "In4.Cu")
		(net 84)
	)
	(segment
		(start 131.1 86.3)
		(end 131.1 86.263088)
		(width 0.15)
		(layer "F.Cu")
		(net 85)
	)
	(segment
		(start 168.448357 99.422347)
		(end 167.867016 99.422347)
		(width 0.15)
		(layer "F.Cu")
		(net 85)
	)
	(segment
		(start 131.1 86.263088)
		(end 130.736912 85.9)
		(width 0.15)
		(layer "F.Cu")
		(net 85)
	)
	(segment
		(start 169.133 99.912)
		(end 168.93801 99.912)
		(width 0.15)
		(layer "F.Cu")
		(net 85)
	)
	(segment
		(start 168.93801 99.912)
		(end 168.448357 99.422347)
		(width 0.15)
		(layer "F.Cu")
		(net 85)
	)
	(segment
		(start 167.867016 99.422347)
		(end 167.733016 99.288347)
		(width 0.15)
		(layer "F.Cu")
		(net 85)
	)
	(via
		(at 167.733016 99.288347)
		(size 0.45)
		(drill 0.2)
		(layers "F.Cu" "B.Cu")
		(remove_unused_layers yes)
		(keep_end_layers yes)
		(zone_layer_connections)
		(net 85)
	)
	(via
		(at 131.1 86.3)
		(size 0.45)
		(drill 0.2)
		(layers "F.Cu" "B.Cu")
		(remove_unused_layers yes)
		(keep_end_layers yes)
		(zone_layer_connections)
		(net 85)
	)
	(segment
		(start 145.566 83.05)
		(end 145.316 83.05)
		(width 0.168)
		(layer "In4.Cu")
		(net 85)
	)
	(segment
		(start 157.496933 88.021642)
		(end 158.471681 87.046898)
		(width 0.168)
		(layer "In4.Cu")
		(net 85)
	)
	(segment
		(start 146.95 82.984)
		(end 146.95 81.916)
		(width 0.168)
		(layer "In4.Cu")
		(net 85)
	)
	(segment
		(start 167.733016 99.288347)
		(end 167.603516 99.417847)
		(width 0.168)
		(layer "In4.Cu")
		(net 85)
	)
	(segment
		(start 157.610425 86.185642)
		(end 157.442487 86.353579)
		(width 0.168)
		(layer "In4.Cu")
		(net 85)
	)
	(segment
		(start 158.47168 86.322112)
		(end 158.335209 86.185641)
		(width 0.168)
		(layer "In4.Cu")
		(net 85)
	)
	(segment
		(start 158.335209 86.185641)
		(end 158.33521 86.185641)
		(width 0.168)
		(layer "In4.Cu")
		(net 85)
	)
	(segment
		(start 147.266 83.05)
		(end 147.016 83.05)
		(width 0.168)
		(layer "In4.Cu")
		(net 85)
	)
	(segment
		(start 158.036101 87.861481)
		(end 157.686437 88.211146)
		(width 0.168)
		(layer "In4.Cu")
		(net 85)
	)
	(segment
		(start 143.932 81.916)
		(end 143.932 82.15)
		(width 0.168)
		(layer "In4.Cu")
		(net 85)
	)
	(segment
		(start 157.389453 86.353578)
		(end 157.389455 86.353579)
		(width 0.168)
		(layer "In4.Cu")
		(net 85)
	)
	(segment
		(start 155.287936 84.252061)
		(end 153.251876 82.216)
		(width 0.168)
		(layer "In4.Cu")
		(net 85)
	)
	(segment
		(start 147.332 81.916)
		(end 147.332 82.984)
		(width 0.168)
		(layer "In4.Cu")
		(net 85)
	)
	(segment
		(start 163.852937 99.246351)
		(end 163.852938 99.246351)
		(width 0.168)
		(layer "In4.Cu")
		(net 85)
	)
	(segment
		(start 163.592722 99.056846)
		(end 160.7875 96.251624)
		(width 0.168)
		(layer "In4.Cu")
		(net 85)
	)
	(segment
		(start 157.389455 86.164075)
		(end 157.739121 85.814412)
		(width 0.168)
		(layer "In4.Cu")
		(net 85)
	)
	(segment
		(start 148.116 81.382)
		(end 147.866 81.382)
		(width 0.168)
		(layer "In4.Cu")
		(net 85)
	)
	(segment
		(start 155.477442 84.252062)
		(end 155.477444 84.252063)
		(width 0.168)
		(layer "In4.Cu")
		(net 85)
	)
	(segment
		(start 156.688363 84.763654)
		(end 156.688362 84.763655)
		(width 0.168)
		(layer "In4.Cu")
		(net 85)
	)
	(segment
		(start 148.966 83.05)
		(end 148.716 83.05)
		(width 0.168)
		(layer "In4.Cu")
		(net 85)
	)
	(segment
		(start 153.251876 82.216)
		(end 149.566 82.216)
		(width 0.168)
		(layer "In4.Cu")
		(net 85)
	)
	(segment
		(start 156.877863 84.953154)
		(end 155.653156 86.177865)
		(width 0.168)
		(layer "In4.Cu")
		(net 85)
	)
	(segment
		(start 144.716 81.382)
		(end 144.466 81.382)
		(width 0.168)
		(layer "In4.Cu")
		(net 85)
	)
	(segment
		(start 163.852938 99.175639)
		(end 163.852938 99.17564)
		(width 0.168)
		(layer "In4.Cu")
		(net 85)
	)
	(segment
		(start 143.866 82.216)
		(end 138.303074 82.216)
		(width 0.168)
		(layer "In4.Cu")
		(net 85)
	)
	(segment
		(start 131.7 85.4)
		(end 131.1 86)
		(width 0.15)
		(layer "In4.Cu")
		(net 85)
	)
	(segment
		(start 155.463652 85.988361)
		(end 156.688363 84.763654)
		(width 0.168)
		(layer "In4.Cu")
		(net 85)
	)
	(segment
		(start 146.416 81.382)
		(end 146.166 81.382)
		(width 0.168)
		(layer "In4.Cu")
		(net 85)
	)
	(segment
		(start 167.603516 99.417847)
		(end 163.953723 99.417847)
		(width 0.168)
		(layer "In4.Cu")
		(net 85)
	)
	(segment
		(start 145.25 82.984)
		(end 145.25 81.916)
		(width 0.168)
		(layer "In4.Cu")
		(net 85)
	)
	(segment
		(start 163.852938 99.17564)
		(end 163.734144 99.056846)
		(width 0.168)
		(layer "In4.Cu")
		(net 85)
	)
	(segment
		(start 132.47 85.4)
		(end 132 85.4)
		(width 0.168)
		(layer "In4.Cu")
		(net 85)
	)
	(segment
		(start 138.303074 82.216)
		(end 135.119074 85.4)
		(width 0.168)
		(layer "In4.Cu")
		(net 85)
	)
	(segment
		(start 163.663433 99.056845)
		(end 163.663433 99.056846)
		(width 0.168)
		(layer "In4.Cu")
		(net 85)
	)
	(segment
		(start 158.471681 87.046898)
		(end 158.47168 87.046896)
		(width 0.168)
		(layer "In4.Cu")
		(net 85)
	)
	(segment
		(start 148.65 82.984)
		(end 148.65 81.916)
		(width 0.168)
		(layer "In4.Cu")
		(net 85)
	)
	(segment
		(start 131.1 86)
		(end 131.1 86.3)
		(width 0.15)
		(layer "In4.Cu")
		(net 85)
	)
	(segment
		(start 157.389455 86.353579)
		(end 157.389456 86.35358)
		(width 0.168)
		(layer "In4.Cu")
		(net 85)
	)
	(segment
		(start 145.632 81.916)
		(end 145.632 82.984)
		(width 0.168)
		(layer "In4.Cu")
		(net 85)
	)
	(segment
		(start 157.739121 85.814412)
		(end 157.73912 85.814413)
		(width 0.168)
		(layer "In4.Cu")
		(net 85)
	)
	(segment
		(start 157.686437 88.211146)
		(end 157.686438 88.211145)
		(width 0.168)
		(layer "In4.Cu")
		(net 85)
	)
	(segment
		(start 160.7875 96.251624)
		(end 160.7875 89.751624)
		(width 0.168)
		(layer "In4.Cu")
		(net 85)
	)
	(segment
		(start 160.7875 89.751624)
		(end 158.897357 87.861481)
		(width 0.168)
		(layer "In4.Cu")
		(net 85)
	)
	(segment
		(start 163.592721 99.056846)
		(end 163.592722 99.056846)
		(width 0.168)
		(layer "In4.Cu")
		(net 85)
	)
	(segment
		(start 155.653156 86.177865)
		(end 155.653157 86.177864)
		(width 0.168)
		(layer "In4.Cu")
		(net 85)
	)
	(segment
		(start 149.032 82.75)
		(end 149.032 82.984)
		(width 0.168)
		(layer "In4.Cu")
		(net 85)
	)
	(segment
		(start 132 85.4)
		(end 131.7 85.4)
		(width 0.15)
		(layer "In4.Cu")
		(net 85)
	)
	(segment
		(start 155.827107 83.902398)
		(end 155.477442 84.252062)
		(width 0.168)
		(layer "In4.Cu")
		(net 85)
	)
	(segment
		(start 135.119074 85.4)
		(end 133.67 85.4)
		(width 0.168)
		(layer "In4.Cu")
		(net 85)
	)
	(segment
		(start 157.442487 86.353579)
		(end 157.442489 86.35358)
		(width 0.168)
		(layer "In4.Cu")
		(net 85)
	)
	(segment
		(start 163.953723 99.417847)
		(end 163.852938 99.317062)
		(width 0.168)
		(layer "In4.Cu")
		(net 85)
	)
	(arc
		(start 146.95 81.916)
		(mid 146.793595 81.538405)
		(end 146.416 81.382)
		(width 0.168)
		(layer "In4.Cu")
		(net 85)
	)
	(arc
		(start 158.897357 87.861481)
		(mid 158.466729 87.683109)
		(end 158.036101 87.861481)
		(width 0.168)
		(layer "In4.Cu")
		(net 85)
	)
	(arc
		(start 147.866 81.382)
		(mid 147.488405 81.538405)
		(end 147.332 81.916)
		(width 0.168)
		(layer "In4.Cu")
		(net 85)
	)
	(arc
		(start 146.166 81.382)
		(mid 145.788405 81.538405)
		(end 145.632 81.916)
		(width 0.168)
		(layer "In4.Cu")
		(net 85)
	)
	(arc
		(start 149.032 82.984)
		(mid 149.012669 83.030669)
		(end 148.966 83.05)
		(width 0.168)
		(layer "In4.Cu")
		(net 85)
	)
	(arc
		(start 157.73912 85.814413)
		(mid 157.917492 85.383784)
		(end 157.739121 84.953156)
		(width 0.168)
		(layer "In4.Cu")
		(net 85)
	)
	(arc
		(start 155.653157 86.177864)
		(mid 155.558405 86.217112)
		(end 155.463652 86.177865)
		(width 0.168)
		(layer "In4.Cu")
		(net 85)
	)
	(arc
		(start 163.852938 99.246351)
		(mid 163.867583 99.210995)
		(end 163.852938 99.175639)
		(width 0.168)
		(layer "In4.Cu")
		(net 85)
	)
	(arc
		(start 147.016 83.05)
		(mid 146.969331 83.030669)
		(end 146.95 82.984)
		(width 0.168)
		(layer "In4.Cu")
		(net 85)
	)
	(arc
		(start 155.463652 86.177865)
		(mid 155.424404 86.083113)
		(end 155.463652 85.988361)
		(width 0.168)
		(layer "In4.Cu")
		(net 85)
	)
	(arc
		(start 145.25 81.916)
		(mid 145.093595 81.538405)
		(end 144.716 81.382)
		(width 0.168)
		(layer "In4.Cu")
		(net 85)
	)
	(arc
		(start 147.332 82.984)
		(mid 147.312669 83.030669)
		(end 147.266 83.05)
		(width 0.168)
		(layer "In4.Cu")
		(net 85)
	)
	(arc
		(start 148.716 83.05)
		(mid 148.669331 83.030669)
		(end 148.65 82.984)
		(width 0.168)
		(layer "In4.Cu")
		(net 85)
	)
	(arc
		(start 163.734144 99.056846)
		(mid 163.698789 99.042201)
		(end 163.663433 99.056845)
		(width 0.168)
		(layer "In4.Cu")
		(net 85)
	)
	(arc
		(start 156.688362 84.763655)
		(mid 156.866734 84.333026)
		(end 156.688363 83.902398)
		(width 0.168)
		(layer "In4.Cu")
		(net 85)
	)
	(arc
		(start 157.739121 84.953156)
		(mid 157.308491 84.774782)
		(end 156.877863 84.953154)
		(width 0.168)
		(layer "In4.Cu")
		(net 85)
	)
	(arc
		(start 133.37 85.1)
		(mid 133.282132 84.887868)
		(end 133.07 84.8)
		(width 0.168)
		(layer "In4.Cu")
		(net 85)
	)
	(arc
		(start 148.65 81.916)
		(mid 148.493595 81.538405)
		(end 148.116 81.382)
		(width 0.168)
		(layer "In4.Cu")
		(net 85)
	)
	(arc
		(start 145.632 82.984)
		(mid 145.612669 83.030669)
		(end 145.566 83.05)
		(width 0.168)
		(layer "In4.Cu")
		(net 85)
	)
	(arc
		(start 157.496933 88.211146)
		(mid 157.457685 88.116394)
		(end 157.496933 88.021642)
		(width 0.168)
		(layer "In4.Cu")
		(net 85)
	)
	(arc
		(start 155.477444 84.252063)
		(mid 155.38269 84.29131)
		(end 155.287936 84.252061)
		(width 0.168)
		(layer "In4.Cu")
		(net 85)
	)
	(arc
		(start 145.316 83.05)
		(mid 145.269331 83.030669)
		(end 145.25 82.984)
		(width 0.168)
		(layer "In4.Cu")
		(net 85)
	)
	(arc
		(start 132.77 85.1)
		(mid 132.682132 85.312132)
		(end 132.47 85.4)
		(width 0.168)
		(layer "In4.Cu")
		(net 85)
	)
	(arc
		(start 157.686438 88.211145)
		(mid 157.591686 88.250393)
		(end 157.496933 88.211146)
		(width 0.168)
		(layer "In4.Cu")
		(net 85)
	)
	(arc
		(start 163.852938 99.317062)
		(mid 163.838293 99.281707)
		(end 163.852937 99.246351)
		(width 0.168)
		(layer "In4.Cu")
		(net 85)
	)
	(arc
		(start 163.663433 99.056846)
		(mid 163.628077 99.071491)
		(end 163.592721 99.056846)
		(width 0.168)
		(layer "In4.Cu")
		(net 85)
	)
	(arc
		(start 144.466 81.382)
		(mid 144.088405 81.538405)
		(end 143.932 81.916)
		(width 0.168)
		(layer "In4.Cu")
		(net 85)
	)
	(arc
		(start 157.442489 86.35358)
		(mid 157.415971 86.364563)
		(end 157.389453 86.353578)
		(width 0.168)
		(layer "In4.Cu")
		(net 85)
	)
	(arc
		(start 157.389456 86.35358)
		(mid 157.350208 86.258828)
		(end 157.389455 86.164075)
		(width 0.168)
		(layer "In4.Cu")
		(net 85)
	)
	(arc
		(start 156.688363 83.902398)
		(mid 156.257735 83.724026)
		(end 155.827107 83.902398)
		(width 0.168)
		(layer "In4.Cu")
		(net 85)
	)
	(arc
		(start 158.47168 87.046896)
		(mid 158.621788 86.684504)
		(end 158.47168 86.322112)
		(width 0.168)
		(layer "In4.Cu")
		(net 85)
	)
	(arc
		(start 133.67 85.4)
		(mid 133.457868 85.312132)
		(end 133.37 85.1)
		(width 0.168)
		(layer "In4.Cu")
		(net 85)
	)
	(arc
		(start 133.07 84.8)
		(mid 132.857868 84.887868)
		(end 132.77 85.1)
		(width 0.168)
		(layer "In4.Cu")
		(net 85)
	)
	(arc
		(start 158.33521 86.185641)
		(mid 157.972817 86.035534)
		(end 157.610425 86.185642)
		(width 0.168)
		(layer "In4.Cu")
		(net 85)
	)
	(arc
		(start 143.932 82.15)
		(mid 143.912669 82.196669)
		(end 143.866 82.216)
		(width 0.168)
		(layer "In4.Cu")
		(net 85)
	)
	(arc
		(start 149.566 82.216)
		(mid 149.188405 82.372405)
		(end 149.032 82.75)
		(width 0.168)
		(layer "In4.Cu")
		(net 85)
	)
	(segment
		(start 167.467 97.534)
		(end 167.333 97.4)
		(width 0.15)
		(layer "F.Cu")
		(net 86)
	)
	(segment
		(start 168.682999 98.878)
		(end 168.358488 98.878)
		(width 0.15)
		(layer "F.Cu")
		(net 86)
	)
	(segment
		(start 131.9 85.5)
		(end 132.465686 85.5)
		(width 0.15)
		(layer "F.Cu")
		(net 86)
	)
	(segment
		(start 168.358488 98.878)
		(end 167.467 97.986512)
		(width 0.15)
		(layer "F.Cu")
		(net 86)
	)
	(segment
		(start 137.587 77.856512)
		(end 137.381237 77.650749)
		(width 0.15)
		(layer "F.Cu")
		(net 86)
	)
	(segment
		(start 169.6 98.895)
		(end 168.699999 98.895)
		(width 0.15)
		(layer "F.Cu")
		(net 86)
	)
	(segment
		(start 137.381237 77.650749)
		(end 137.191731 77.650749)
		(width 0.15)
		(layer "F.Cu")
		(net 86)
	)
	(segment
		(start 134.7268 85.435)
		(end 137.587 82.5748)
		(width 0.15)
		(layer "F.Cu")
		(net 86)
	)
	(segment
		(start 132.465686 85.5)
		(end 132.530686 85.435)
		(width 0.15)
		(layer "F.Cu")
		(net 86)
	)
	(segment
		(start 168.699999 98.895)
		(end 168.682999 98.878)
		(width 0.15)
		(layer "F.Cu")
		(net 86)
	)
	(segment
		(start 167.467 97.986512)
		(end 167.467 97.534)
		(width 0.15)
		(layer "F.Cu")
		(net 86)
	)
	(segment
		(start 131.5 85.9)
		(end 131.9 85.5)
		(width 0.15)
		(layer "F.Cu")
		(net 86)
	)
	(segment
		(start 137.587 82.5748)
		(end 137.587 77.856512)
		(width 0.15)
		(layer "F.Cu")
		(net 86)
	)
	(segment
		(start 132.530686 85.435)
		(end 134.7268 85.435)
		(width 0.15)
		(layer "F.Cu")
		(net 86)
	)
	(via
		(at 137.191731 77.650749)
		(size 0.45)
		(drill 0.2)
		(layers "F.Cu" "B.Cu")
		(remove_unused_layers yes)
		(keep_end_layers yes)
		(zone_layer_connections)
		(net 86)
	)
	(via
		(at 167.333 97.4)
		(size 0.45)
		(drill 0.2)
		(layers "F.Cu" "B.Cu")
		(remove_unused_layers yes)
		(keep_end_layers yes)
		(zone_layer_connections)
		(net 86)
	)
	(segment
		(start 159.969556 77.361102)
		(end 159.969557 77.361102)
		(width 0.168)
		(layer "In4.Cu")
		(net 86)
	)
	(segment
		(start 161.030216 78.616215)
		(end 161.030215 78.616216)
		(width 0.168)
		(layer "In4.Cu")
		(net 86)
	)
	(segment
		(start 161.324418 80.054418)
		(end 160.752419 80.626418)
		(width 0.168)
		(layer "In4.Cu")
		(net 86)
	)
	(segment
		(start 159.775102 77.361103)
		(end 159.468267 77.667937)
		(width 0.168)
		(layer "In4.Cu")
		(net 86)
	)
	(segment
		(start 160.431699 78.825824)
		(end 160.26376 78.99376)
		(width 0.168)
		(layer "In4.Cu")
		(net 86)
	)
	(segment
		(start 159.886214 80.626419)
		(end 159.886215 80.626419)
		(width 0.168)
		(layer "In4.Cu")
		(net 86)
	)
	(segment
		(start 161.030216 78.421761)
		(end 161.030215 78.421761)
		(width 0.168)
		(layer "In4.Cu")
		(net 86)
	)
	(segment
		(start 167.134928 86.412938)
		(end 167.028861 86.306871)
		(width 0.168)
		(layer "In4.Cu")
		(net 86)
	)
	(segment
		(start 158.261624 77.3275)
		(end 140.468376 77.3275)
		(width 0.168)
		(layer "In4.Cu")
		(net 86)
	)
	(segment
		(start 162.090874 79.482419)
		(end 162.090873 79.482419)
		(width 0.168)
		(layer "In4.Cu")
		(net 86)
	)
	(segment
		(start 160.26376 78.99376)
		(end 159.691761 79.56576)
		(width 0.168)
		(layer "In4.Cu")
		(net 86)
	)
	(segment
		(start 137.701624 77.9775)
		(end 137.374873 77.650749)
		(width 0.168)
		(layer "In4.Cu")
		(net 86)
	)
	(segment
		(start 167.333 97.4)
		(end 167.4625 97.2705)
		(width 0.168)
		(layer "In4.Cu")
		(net 86)
	)
	(segment
		(start 159.468267 77.667937)
		(end 159.468269 77.667938)
		(width 0.168)
		(layer "In4.Cu")
		(net 86)
	)
	(segment
		(start 162.090874 79.676873)
		(end 162.090873 79.676874)
		(width 0.168)
		(layer "In4.Cu")
		(net 86)
	)
	(segment
		(start 139.818376 77.9775)
		(end 137.701624 77.9775)
		(width 0.168)
		(layer "In4.Cu")
		(net 86)
	)
	(segment
		(start 158.602061 77.667936)
		(end 158.261624 77.3275)
		(width 0.168)
		(layer "In4.Cu")
		(net 86)
	)
	(segment
		(start 167.134926 86.412937)
		(end 167.134928 86.412938)
		(width 0.168)
		(layer "In4.Cu")
		(net 86)
	)
	(segment
		(start 161.784038 79.983706)
		(end 162.090874 79.676873)
		(width 0.168)
		(layer "In4.Cu")
		(net 86)
	)
	(segment
		(start 161.421647 79.957192)
		(end 161.324418 80.054418)
		(width 0.168)
		(layer "In4.Cu")
		(net 86)
	)
	(segment
		(start 167.4625 86.528376)
		(end 167.347062 86.412938)
		(width 0.168)
		(layer "In4.Cu")
		(net 86)
	)
	(segment
		(start 167.4625 97.2705)
		(end 167.4625 86.528376)
		(width 0.168)
		(layer "In4.Cu")
		(net 86)
	)
	(segment
		(start 159.886214 79.760214)
		(end 161.030216 78.616215)
		(width 0.168)
		(layer "In4.Cu")
		(net 86)
	)
	(segment
		(start 158.825556 78.699556)
		(end 159.969556 77.555556)
		(width 0.168)
		(layer "In4.Cu")
		(net 86)
	)
	(segment
		(start 140.468376 77.3275)
		(end 139.818376 77.9775)
		(width 0.168)
		(layer "In4.Cu")
		(net 86)
	)
	(segment
		(start 160.83576 78.42176)
		(end 160.431699 78.825824)
		(width 0.168)
		(layer "In4.Cu")
		(net 86)
	)
	(segment
		(start 161.896418 79.482418)
		(end 161.421647 79.957192)
		(width 0.168)
		(layer "In4.Cu")
		(net 86)
	)
	(segment
		(start 137.374873 77.650749)
		(end 137.191731 77.650749)
		(width 0.168)
		(layer "In4.Cu")
		(net 86)
	)
	(segment
		(start 167.028861 86.094737)
		(end 167.02886 86.094737)
		(width 0.168)
		(layer "In4.Cu")
		(net 86)
	)
	(segment
		(start 159.969556 77.555556)
		(end 159.969555 77.555557)
		(width 0.168)
		(layer "In4.Cu")
		(net 86)
	)
	(segment
		(start 158.825556 79.565761)
		(end 158.825557 79.565761)
		(width 0.168)
		(layer "In4.Cu")
		(net 86)
	)
	(segment
		(start 167.240995 86.412937)
		(end 167.240994 86.412937)
		(width 0.168)
		(layer "In4.Cu")
		(net 86)
	)
	(segment
		(start 167.02886 86.094737)
		(end 161.784038 80.849912)
		(width 0.168)
		(layer "In4.Cu")
		(net 86)
	)
	(arc
		(start 167.347062 86.412938)
		(mid 167.294028 86.390969)
		(end 167.240995 86.412937)
		(width 0.168)
		(layer "In4.Cu")
		(net 86)
	)
	(arc
		(start 160.752419 80.626418)
		(mid 160.319317 80.805815)
		(end 159.886214 80.626419)
		(width 0.168)
		(layer "In4.Cu")
		(net 86)
	)
	(arc
		(start 161.030215 78.616216)
		(mid 161.070488 78.518989)
		(end 161.030216 78.421761)
		(width 0.168)
		(layer "In4.Cu")
		(net 86)
	)
	(arc
		(start 162.090873 79.482419)
		(mid 161.993646 79.442146)
		(end 161.896418 79.482418)
		(width 0.168)
		(layer "In4.Cu")
		(net 86)
	)
	(arc
		(start 159.886215 80.626419)
		(mid 159.706818 80.193317)
		(end 159.886214 79.760214)
		(width 0.168)
		(layer "In4.Cu")
		(net 86)
	)
	(arc
		(start 167.028861 86.306871)
		(mid 167.006894 86.253838)
		(end 167.028861 86.200805)
		(width 0.168)
		(layer "In4.Cu")
		(net 86)
	)
	(arc
		(start 159.468269 77.667938)
		(mid 159.035166 77.847335)
		(end 158.602061 77.667936)
		(width 0.168)
		(layer "In4.Cu")
		(net 86)
	)
	(arc
		(start 167.240994 86.412937)
		(mid 167.187961 86.434905)
		(end 167.134926 86.412937)
		(width 0.168)
		(layer "In4.Cu")
		(net 86)
	)
	(arc
		(start 161.030215 78.421761)
		(mid 160.932988 78.381488)
		(end 160.83576 78.42176)
		(width 0.168)
		(layer "In4.Cu")
		(net 86)
	)
	(arc
		(start 158.825557 79.565761)
		(mid 158.64616 79.132659)
		(end 158.825556 78.699556)
		(width 0.168)
		(layer "In4.Cu")
		(net 86)
	)
	(arc
		(start 167.028861 86.200805)
		(mid 167.050827 86.14777)
		(end 167.028861 86.094737)
		(width 0.168)
		(layer "In4.Cu")
		(net 86)
	)
	(arc
		(start 159.691761 79.56576)
		(mid 159.258659 79.745157)
		(end 158.825556 79.565761)
		(width 0.168)
		(layer "In4.Cu")
		(net 86)
	)
	(arc
		(start 159.969555 77.555557)
		(mid 160.009828 77.45833)
		(end 159.969556 77.361102)
		(width 0.168)
		(layer "In4.Cu")
		(net 86)
	)
	(arc
		(start 161.784038 80.849912)
		(mid 161.604641 80.416809)
		(end 161.784038 79.983706)
		(width 0.168)
		(layer "In4.Cu")
		(net 86)
	)
	(arc
		(start 159.969557 77.361102)
		(mid 159.872329 77.32083)
		(end 159.775102 77.361103)
		(width 0.168)
		(layer "In4.Cu")
		(net 86)
	)
	(arc
		(start 162.090873 79.676874)
		(mid 162.131146 79.579647)
		(end 162.090874 79.482419)
		(width 0.168)
		(layer "In4.Cu")
		(net 86)
	)
	(segment
		(start 167.933 97.793488)
		(end 167.933 97.534)
		(width 0.15)
		(layer "F.Cu")
		(net 87)
	)
	(segment
		(start 168.699999 98.395)
		(end 168.682999 98.412)
		(width 0.15)
		(layer "F.Cu")
		(net 87)
	)
	(segment
		(start 167.933 97.534)
		(end 168.067 97.4)
		(width 0.15)
		(layer "F.Cu")
		(net 87)
	)
	(segment
		(start 169.6 98.395)
		(end 168.699999 98.395)
		(width 0.15)
		(layer "F.Cu")
		(net 87)
	)
	(segment
		(start 137.710749 77.321237)
		(end 137.710749 77.131731)
		(width 0.15)
		(layer "F.Cu")
		(net 87)
	)
	(segment
		(start 138.053 77.663488)
		(end 137.710749 77.321237)
		(width 0.15)
		(layer "F.Cu")
		(net 87)
	)
	(segment
		(start 168.682999 98.412)
		(end 168.551512 98.412)
		(width 0.15)
		(layer "F.Cu")
		(net 87)
	)
	(segment
		(start 132.315 85.885)
		(end 134.9132 85.885)
		(width 0.15)
		(layer "F.Cu")
		(net 87)
	)
	(segment
		(start 134.9132 85.885)
		(end 138.053 82.7452)
		(width 0.15)
		(layer "F.Cu")
		(net 87)
	)
	(segment
		(start 138.053 82.7452)
		(end 138.053 77.663488)
		(width 0.15)
		(layer "F.Cu")
		(net 87)
	)
	(segment
		(start 168.551512 98.412)
		(end 167.933 97.793488)
		(width 0.15)
		(layer "F.Cu")
		(net 87)
	)
	(via
		(at 168.067 97.4)
		(size 0.45)
		(drill 0.2)
		(layers "F.Cu" "B.Cu")
		(remove_unused_layers yes)
		(keep_end_layers yes)
		(zone_layer_connections)
		(net 87)
	)
	(via
		(at 137.710749 77.131731)
		(size 0.45)
		(drill 0.2)
		(layers "F.Cu" "B.Cu")
		(remove_unused_layers yes)
		(keep_end_layers yes)
		(zone_layer_connections)
		(net 87)
	)
	(segment
		(start 160.416544 80.290543)
		(end 160.416543 80.290544)
		(width 0.168)
		(layer "In4.Cu")
		(net 87)
	)
	(segment
		(start 161.36609 78.952091)
		(end 161.36609 78.95209)
		(width 0.168)
		(layer "In4.Cu")
		(net 87)
	)
	(segment
		(start 159.355886 79.229885)
		(end 159.355885 79.229886)
		(width 0.168)
		(layer "In4.Cu")
		(net 87)
	)
	(segment
		(start 158.458376 76.8525)
		(end 158.937936 77.332061)
		(width 0.168)
		(layer "In4.Cu")
		(net 87)
	)
	(segment
		(start 161.36609 78.95209)
		(end 160.794091 79.52409)
		(width 0.168)
		(layer "In4.Cu")
		(net 87)
	)
	(segment
		(start 139.1475 77.5025)
		(end 139.621624 77.5025)
		(width 0.168)
		(layer "In4.Cu")
		(net 87)
	)
	(segment
		(start 167.9375 97.2705)
		(end 168.067 97.4)
		(width 0.168)
		(layer "In4.Cu")
		(net 87)
	)
	(segment
		(start 138.5975 77.0525)
		(end 138.6475 77.0525)
		(width 0.168)
		(layer "In4.Cu")
		(net 87)
	)
	(segment
		(start 162.426748 80.012749)
		(end 162.426748 80.012748)
		(width 0.168)
		(layer "In4.Cu")
		(net 87)
	)
	(segment
		(start 160.794089 79.524089)
		(end 160.222089 80.096089)
		(width 0.168)
		(layer "In4.Cu")
		(net 87)
	)
	(segment
		(start 160.305432 77.891433)
		(end 160.305432 77.891432)
		(width 0.168)
		(layer "In4.Cu")
		(net 87)
	)
	(segment
		(start 137.898376 77.5025)
		(end 138.1475 77.5025)
		(width 0.168)
		(layer "In4.Cu")
		(net 87)
	)
	(segment
		(start 162.119913 80.514038)
		(end 162.119913 80.514037)
		(width 0.168)
		(layer "In4.Cu")
		(net 87)
	)
	(segment
		(start 159.733433 78.463432)
		(end 159.733431 78.463431)
		(width 0.168)
		(layer "In4.Cu")
		(net 87)
	)
	(segment
		(start 160.794091 79.52409)
		(end 160.794089 79.524089)
		(width 0.168)
		(layer "In4.Cu")
		(net 87)
	)
	(segment
		(start 159.132392 77.332062)
		(end 159.439227 77.025228)
		(width 0.168)
		(layer "In4.Cu")
		(net 87)
	)
	(segment
		(start 160.22209 80.290544)
		(end 160.222089 80.290544)
		(width 0.168)
		(layer "In4.Cu")
		(net 87)
	)
	(segment
		(start 160.416543 80.290544)
		(end 161.085769 79.621314)
		(width 0.168)
		(layer "In4.Cu")
		(net 87)
	)
	(segment
		(start 162.119913 80.514037)
		(end 167.9375 86.331624)
		(width 0.168)
		(layer "In4.Cu")
		(net 87)
	)
	(segment
		(start 161.085769 79.621314)
		(end 161.560543 79.146543)
		(width 0.168)
		(layer "In4.Cu")
		(net 87)
	)
	(segment
		(start 137.710749 77.314873)
		(end 137.898376 77.5025)
		(width 0.168)
		(layer "In4.Cu")
		(net 87)
	)
	(segment
		(start 139.621624 77.5025)
		(end 140.271624 76.8525)
		(width 0.168)
		(layer "In4.Cu")
		(net 87)
	)
	(segment
		(start 159.161432 79.229886)
		(end 159.161431 79.229886)
		(width 0.168)
		(layer "In4.Cu")
		(net 87)
	)
	(segment
		(start 139.0975 77.5025)
		(end 139.1475 77.5025)
		(width 0.168)
		(layer "In4.Cu")
		(net 87)
	)
	(segment
		(start 159.355885 79.229886)
		(end 160.499885 78.085885)
		(width 0.168)
		(layer "In4.Cu")
		(net 87)
	)
	(segment
		(start 137.710749 77.131731)
		(end 137.710749 77.314873)
		(width 0.168)
		(layer "In4.Cu")
		(net 87)
	)
	(segment
		(start 160.305432 77.891432)
		(end 159.733433 78.463432)
		(width 0.168)
		(layer "In4.Cu")
		(net 87)
	)
	(segment
		(start 140.271624 76.8525)
		(end 158.458376 76.8525)
		(width 0.168)
		(layer "In4.Cu")
		(net 87)
	)
	(segment
		(start 167.9375 86.331624)
		(end 167.9375 97.2705)
		(width 0.168)
		(layer "In4.Cu")
		(net 87)
	)
	(segment
		(start 162.426748 79.146544)
		(end 162.426749 79.146544)
		(width 0.168)
		(layer "In4.Cu")
		(net 87)
	)
	(segment
		(start 162.426748 80.012748)
		(end 162.119914 80.319583)
		(width 0.168)
		(layer "In4.Cu")
		(net 87)
	)
	(segment
		(start 161.36609 78.085886)
		(end 161.366091 78.085886)
		(width 0.168)
		(layer "In4.Cu")
		(net 87)
	)
	(segment
		(start 159.132394 77.332063)
		(end 159.132392 77.332062)
		(width 0.168)
		(layer "In4.Cu")
		(net 87)
	)
	(segment
		(start 159.733431 78.463431)
		(end 159.161431 79.035431)
		(width 0.168)
		(layer "In4.Cu")
		(net 87)
	)
	(arc
		(start 160.499885 78.085885)
		(mid 160.932987 77.906488)
		(end 161.36609 78.085886)
		(width 0.168)
		(layer "In4.Cu")
		(net 87)
	)
	(arc
		(start 160.222089 80.096089)
		(mid 160.181817 80.193317)
		(end 160.22209 80.290544)
		(width 0.168)
		(layer "In4.Cu")
		(net 87)
	)
	(arc
		(start 159.161431 79.035431)
		(mid 159.121159 79.132659)
		(end 159.161432 79.229886)
		(width 0.168)
		(layer "In4.Cu")
		(net 87)
	)
	(arc
		(start 162.426749 79.146544)
		(mid 162.606144 79.579646)
		(end 162.426748 80.012749)
		(width 0.168)
		(layer "In4.Cu")
		(net 87)
	)
	(arc
		(start 158.937936 77.332061)
		(mid 159.035165 77.372335)
		(end 159.132394 77.332063)
		(width 0.168)
		(layer "In4.Cu")
		(net 87)
	)
	(arc
		(start 138.1475 77.5025)
		(mid 138.306599 77.436599)
		(end 138.3725 77.2775)
		(width 0.168)
		(layer "In4.Cu")
		(net 87)
	)
	(arc
		(start 161.560543 79.146543)
		(mid 161.993645 78.967146)
		(end 162.426748 79.146544)
		(width 0.168)
		(layer "In4.Cu")
		(net 87)
	)
	(arc
		(start 162.119914 80.319583)
		(mid 162.079641 80.41681)
		(end 162.119913 80.514038)
		(width 0.168)
		(layer "In4.Cu")
		(net 87)
	)
	(arc
		(start 160.305433 77.025228)
		(mid 160.484828 77.45833)
		(end 160.305432 77.891433)
		(width 0.168)
		(layer "In4.Cu")
		(net 87)
	)
	(arc
		(start 138.3725 77.2775)
		(mid 138.438401 77.118401)
		(end 138.5975 77.0525)
		(width 0.168)
		(layer "In4.Cu")
		(net 87)
	)
	(arc
		(start 159.161431 79.229886)
		(mid 159.258659 79.270158)
		(end 159.355886 79.229885)
		(width 0.168)
		(layer "In4.Cu")
		(net 87)
	)
	(arc
		(start 159.439227 77.025228)
		(mid 159.87233 76.845831)
		(end 160.305433 77.025228)
		(width 0.168)
		(layer "In4.Cu")
		(net 87)
	)
	(arc
		(start 160.222089 80.290544)
		(mid 160.319317 80.330816)
		(end 160.416544 80.290543)
		(width 0.168)
		(layer "In4.Cu")
		(net 87)
	)
	(arc
		(start 138.6475 77.0525)
		(mid 138.806599 77.118401)
		(end 138.8725 77.2775)
		(width 0.168)
		(layer "In4.Cu")
		(net 87)
	)
	(arc
		(start 138.8725 77.2775)
		(mid 138.938401 77.436599)
		(end 139.0975 77.5025)
		(width 0.168)
		(layer "In4.Cu")
		(net 87)
	)
	(arc
		(start 161.366091 78.085886)
		(mid 161.545486 78.518988)
		(end 161.36609 78.952091)
		(width 0.168)
		(layer "In4.Cu")
		(net 87)
	)
	(segment
		(start 166.715 96.6)
		(end 166.1 96.6)
		(width 0.15)
		(layer "F.Cu")
		(net 88)
	)
	(segment
		(start 119.3605 92.3)
		(end 120.3 92.3)
		(width 0.15)
		(layer "F.Cu")
		(net 88)
	)
	(segment
		(start 119.36 92.3005)
		(end 119.3605 92.3)
		(width 0.15)
		(layer "F.Cu")
		(net 88)
	)
	(via
		(at 119.36 92.3005)
		(size 0.45)
		(drill 0.2)
		(layers "F.Cu" "B.Cu")
		(remove_unused_layers yes)
		(keep_end_layers yes)
		(free yes)
		(zone_layer_connections)
		(net 88)
	)
	(via
		(at 166.1 96.6)
		(size 0.45)
		(drill 0.2)
		(layers "F.Cu" "B.Cu")
		(remove_unused_layers yes)
		(keep_end_layers yes)
		(zone_layer_connections)
		(net 88)
	)
	(via
		(at 109.8 78.8)
		(size 0.45)
		(drill 0.2)
		(layers "F.Cu" "B.Cu")
		(remove_unused_layers yes)
		(keep_end_layers yes)
		(zone_layer_connections)
		(net 88)
	)
	(segment
		(start 158.37 76.19)
		(end 156.995 74.815)
		(width 0.15)
		(layer "B.Cu")
		(net 88)
	)
	(segment
		(start 164.99 83.99)
		(end 164.99 79.92)
		(width 0.15)
		(layer "B.Cu")
		(net 88)
	)
	(segment
		(start 109.81 75.38)
		(end 109.81 78.79)
		(width 0.15)
		(layer "B.Cu")
		(net 88)
	)
	(segment
		(start 111.59 74.17)
		(end 111.02 74.17)
		(width 0.15)
		(layer "B.Cu")
		(net 88)
	)
	(segment
		(start 169 94.5)
		(end 169 88)
		(width 0.15)
		(layer "B.Cu")
		(net 88)
	)
	(segment
		(start 111.02 74.17)
		(end 109.81 75.38)
		(width 0.15)
		(layer "B.Cu")
		(net 88)
	)
	(segment
		(start 166.9 96.6)
		(end 169 94.5)
		(width 0.15)
		(layer "B.Cu")
		(net 88)
	)
	(segment
		(start 151.065 74.815)
		(end 148.48 72.23)
		(width 0.15)
		(layer "B.Cu")
		(net 88)
	)
	(segment
		(start 112.69 75.27)
		(end 111.59 74.17)
		(width 0.15)
		(layer "B.Cu")
		(net 88)
	)
	(segment
		(start 156.995 74.815)
		(end 151.065 74.815)
		(width 0.15)
		(layer "B.Cu")
		(net 88)
	)
	(segment
		(start 109.81 78.79)
		(end 109.8 78.8)
		(width 0.15)
		(layer "B.Cu")
		(net 88)
	)
	(segment
		(start 166.1 96.6)
		(end 166.9 96.6)
		(width 0.15)
		(layer "B.Cu")
		(net 88)
	)
	(segment
		(start 115.84 75.27)
		(end 112.69 75.27)
		(width 0.15)
		(layer "B.Cu")
		(net 88)
	)
	(segment
		(start 161.26 76.19)
		(end 158.37 76.19)
		(width 0.15)
		(layer "B.Cu")
		(net 88)
	)
	(segment
		(start 164.99 79.92)
		(end 161.26 76.19)
		(width 0.15)
		(layer "B.Cu")
		(net 88)
	)
	(segment
		(start 118.88 72.23)
		(end 115.84 75.27)
		(width 0.15)
		(layer "B.Cu")
		(net 88)
	)
	(segment
		(start 148.48 72.23)
		(end 118.88 72.23)
		(width 0.15)
		(layer "B.Cu")
		(net 88)
	)
	(segment
		(start 169 88)
		(end 164.99 83.99)
		(width 0.15)
		(layer "B.Cu")
		(net 88)
	)
	(segment
		(start 112.2 88.6)
		(end 115.2 91.6)
		(width 0.125)
		(layer "In6.Cu")
		(net 88)
	)
	(segment
		(start 110.9 79.9)
		(end 112.2 81.2)
		(width 0.125)
		(layer "In6.Cu")
		(net 88)
	)
	(segment
		(start 112.2 81.2)
		(end 112.2 88.6)
		(width 0.125)
		(layer "In6.Cu")
		(net 88)
	)
	(segment
		(start 117.9 92.6)
		(end 119.0605 92.6)
		(width 0.125)
		(layer "In6.Cu")
		(net 88)
	)
	(segment
		(start 116.9 91.6)
		(end 117.9 92.6)
		(width 0.125)
		(layer "In6.Cu")
		(net 88)
	)
	(segment
		(start 119.0605 92.6)
		(end 119.36 92.3005)
		(width 0.125)
		(layer "In6.Cu")
		(net 88)
	)
	(segment
		(start 110.9 79.9)
		(end 109.8 78.8)
		(width 0.15)
		(layer "In6.Cu")
		(net 88)
	)
	(segment
		(start 115.2 91.6)
		(end 116.9 91.6)
		(width 0.125)
		(layer "In6.Cu")
		(net 88)
	)
	(segment
		(start 166.715 95.6)
		(end 166.3 95.6)
		(width 0.15)
		(layer "F.Cu")
		(net 89)
	)
	(segment
		(start 125.5 92.7)
		(end 125.1 92.3)
		(width 0.15)
		(layer "F.Cu")
		(net 89)
	)
	(segment
		(start 166.3 95.6)
		(end 166.1 95.8)
		(width 0.15)
		(layer "F.Cu")
		(net 89)
	)
	(via
		(at 166.1 95.8)
		(size 0.45)
		(drill 0.2)
		(layers "F.Cu" "B.Cu")
		(remove_unused_layers yes)
		(keep_end_layers yes)
		(zone_layer_connections)
		(net 89)
	)
	(via
		(at 111.3385 75.241713)
		(size 0.45)
		(drill 0.2)
		(layers "F.Cu" "B.Cu")
		(remove_unused_layers yes)
		(keep_end_layers yes)
		(zone_layer_connections)
		(net 89)
	)
	(via
		(at 125.5 92.7)
		(size 0.45)
		(drill 0.2)
		(layers "F.Cu" "B.Cu")
		(remove_unused_layers yes)
		(keep_end_layers yes)
		(free yes)
		(zone_layer_connections)
		(net 89)
	)
	(segment
		(start 111.421713 75.241713)
		(end 111.3385 75.241713)
		(width 0.15)
		(layer "B.Cu")
		(net 89)
	)
	(segment
		(start 127.36 73.5)
		(end 118.48 73.5)
		(width 0.15)
		(layer "B.Cu")
		(net 89)
	)
	(segment
		(start 118.48 73.5)
		(end 116.01 75.97)
		(width 0.15)
		(layer "B.Cu")
		(net 89)
	)
	(segment
		(start 163.84 82.47)
		(end 156.435 75.065)
		(width 0.15)
		(layer "B.Cu")
		(net 89)
	)
	(segment
		(start 156.435 75.065)
		(end 150.565 75.065)
		(width 0.15)
		(layer "B.Cu")
		(net 89)
	)
	(segment
		(start 168.3 88.62)
		(end 163.84 84.16)
		(width 0.15)
		(layer "B.Cu")
		(net 89)
	)
	(segment
		(start 149 73.5)
		(end 129.430983 73.5)
		(width 0.15)
		(layer "B.Cu")
		(net 89)
	)
	(segment
		(start 127.55 73.31)
		(end 127.36 73.5)
		(width 0.15)
		(layer "B.Cu")
		(net 89)
	)
	(segment
		(start 116.01 75.97)
		(end 112.15 75.97)
		(width 0.15)
		(layer "B.Cu")
		(net 89)
	)
	(segment
		(start 128.77 73.5)
		(end 128.58 73.31)
		(width 0.15)
		(layer "B.Cu")
		(net 89)
	)
	(segment
		(start 129.218017 73.5)
		(end 128.77 73.5)
		(width 0.15)
		(layer "B.Cu")
		(net 89)
	)
	(segment
		(start 112.15 75.97)
		(end 111.421713 75.241713)
		(width 0.15)
		(layer "B.Cu")
		(net 89)
	)
	(segment
		(start 129.430983 73.5)
		(end 129.425983 73.505)
		(width 0.15)
		(layer "B.Cu")
		(net 89)
	)
	(segment
		(start 163.84 84.16)
		(end 163.84 82.47)
		(width 0.15)
		(layer "B.Cu")
		(net 89)
	)
	(segment
		(start 128.58 73.31)
		(end 127.55 73.31)
		(width 0.15)
		(layer "B.Cu")
		(net 89)
	)
	(segment
		(start 150.565 75.065)
		(end 149 73.5)
		(width 0.15)
		(layer "B.Cu")
		(net 89)
	)
	(segment
		(start 129.223017 73.505)
		(end 129.218017 73.5)
		(width 0.15)
		(layer "B.Cu")
		(net 89)
	)
	(segment
		(start 129.425983 73.505)
		(end 129.223017 73.505)
		(width 0.15)
		(layer "B.Cu")
		(net 89)
	)
	(segment
		(start 168.3 93.6)
		(end 168.3 88.62)
		(width 0.15)
		(layer "B.Cu")
		(net 89)
	)
	(segment
		(start 166.1 95.8)
		(end 168.3 93.6)
		(width 0.15)
		(layer "B.Cu")
		(net 89)
	)
	(segment
		(start 122.1 93)
		(end 117.7 93)
		(width 0.125)
		(layer "In6.Cu")
		(net 89)
	)
	(segment
		(start 125.0875 92.2875)
		(end 122.8125 92.2875)
		(width 0.125)
		(layer "In6.Cu")
		(net 89)
	)
	(segment
		(start 115 92)
		(end 111.8 88.8)
		(width 0.125)
		(layer "In6.Cu")
		(net 89)
	)
	(segment
		(start 111.8 88.8)
		(end 111.8 81.5)
		(width 0.125)
		(layer "In6.Cu")
		(net 89)
	)
	(segment
		(start 109.3 79)
		(end 109.3 77.280213)
		(width 0.125)
		(layer "In6.Cu")
		(net 89)
	)
	(segment
		(start 116.7 92)
		(end 115 92)
		(width 0.125)
		(layer "In6.Cu")
		(net 89)
	)
	(segment
		(start 122.8125 92.2875)
		(end 122.1 93)
		(width 0.125)
		(layer "In6.Cu")
		(net 89)
	)
	(segment
		(start 125.5 92.7)
		(end 125.0875 92.2875)
		(width 0.125)
		(layer "In6.Cu")
		(net 89)
	)
	(segment
		(start 117.7 93)
		(end 116.7 92)
		(width 0.125)
		(layer "In6.Cu")
		(net 89)
	)
	(segment
		(start 109.3 77.280213)
		(end 111.3385 75.241713)
		(width 0.125)
		(layer "In6.Cu")
		(net 89)
	)
	(segment
		(start 111.8 81.5)
		(end 109.3 79)
		(width 0.125)
		(layer "In6.Cu")
		(net 89)
	)
	(segment
		(start 120.3 91.5)
		(end 119.95 91.15)
		(width 0.15)
		(layer "F.Cu")
		(net 90)
	)
	(segment
		(start 119.95 91.15)
		(end 116.2285 91.15)
		(width 0.15)
		(layer "F.Cu")
		(net 90)
	)
	(segment
		(start 166.6825 94.6)
		(end 166.0825 95.2)
		(width 0.15)
		(layer "F.Cu")
		(net 90)
	)
	(segment
		(start 116.2285 91.15)
		(end 116.21 91.1315)
		(width 0.15)
		(layer "F.Cu")
		(net 90)
	)
	(via
		(at 116.21 91.1315)
		(size 0.45)
		(drill 0.2)
		(layers "F.Cu" "B.Cu")
		(remove_unused_layers yes)
		(keep_end_layers yes)
		(zone_layer_connections)
		(net 90)
	)
	(via
		(at 166.0825 95.2)
		(size 0.45)
		(drill 0.2)
		(layers "F.Cu" "B.Cu")
		(remove_unused_layers yes)
		(keep_end_layers yes)
		(zone_layer_connections)
		(net 90)
	)
	(via
		(at 110.802874 79.192874)
		(size 0.45)
		(drill 0.2)
		(layers "F.Cu" "B.Cu")
		(remove_unused_layers yes)
		(keep_end_layers yes)
		(zone_layer_connections)
		(net 90)
	)
	(segment
		(start 165.6 93.88)
		(end 165.6 92.29)
		(width 0.15)
		(layer "B.Cu")
		(net 90)
	)
	(segment
		(start 116.507126 79.192874)
		(end 110.802874 79.192874)
		(width 0.15)
		(layer "B.Cu")
		(net 90)
	)
	(segment
		(start 166.0825 95.2)
		(end 166.3 94.9825)
		(width 0.15)
		(layer "B.Cu")
		(net 90)
	)
	(segment
		(start 159.84 86.53)
		(end 159.84 83.415686)
		(width 0.15)
		(layer "B.Cu")
		(net 90)
	)
	(segment
		(start 165.6 92.29)
		(end 159.84 86.53)
		(width 0.15)
		(layer "B.Cu")
		(net 90)
	)
	(segment
		(start 159.84 83.415686)
		(end 154.174314 77.75)
		(width 0.15)
		(layer "B.Cu")
		(net 90)
	)
	(segment
		(start 165.93 94.06)
		(end 165.78 94.06)
		(width 0.15)
		(layer "B.Cu")
		(net 90)
	)
	(segment
		(start 166.3 94.9825)
		(end 166.3 94.43)
		(width 0.15)
		(layer "B.Cu")
		(net 90)
	)
	(segment
		(start 165.78 94.06)
		(end 165.6 93.88)
		(width 0.15)
		(layer "B.Cu")
		(net 90)
	)
	(segment
		(start 138.285 76.25)
		(end 119.45 76.25)
		(width 0.15)
		(layer "B.Cu")
		(net 90)
	)
	(segment
		(start 154.174314 77.75)
		(end 148.016949 77.75)
		(width 0.15)
		(layer "B.Cu")
		(net 90)
	)
	(segment
		(start 139.11 77.075)
		(end 138.285 76.25)
		(width 0.15)
		(layer "B.Cu")
		(net 90)
	)
	(segment
		(start 147.341949 77.075)
		(end 139.11 77.075)
		(width 0.15)
		(layer "B.Cu")
		(net 90)
	)
	(segment
		(start 119.45 76.25)
		(end 116.507126 79.192874)
		(width 0.15)
		(layer "B.Cu")
		(net 90)
	)
	(segment
		(start 148.016949 77.75)
		(end 147.341949 77.075)
		(width 0.15)
		(layer "B.Cu")
		(net 90)
	)
	(segment
		(start 166.3 94.43)
		(end 165.93 94.06)
		(width 0.15)
		(layer "B.Cu")
		(net 90)
	)
	(segment
		(start 112.6 88.4)
		(end 115.3315 91.1315)
		(width 0.125)
		(layer "In6.Cu")
		(net 90)
	)
	(segment
		(start 112.6 80.99)
		(end 112.6 88.4)
		(width 0.125)
		(layer "In6.Cu")
		(net 90)
	)
	(segment
		(start 115.3315 91.1315)
		(end 116.21 91.1315)
		(width 0.125)
		(layer "In6.Cu")
		(net 90)
	)
	(segment
		(start 110.802874 79.192874)
		(end 112.6 80.99)
		(width 0.125)
		(layer "In6.Cu")
		(net 90)
	)
	(segment
		(start 124.7 91.9)
		(end 124.69 91.9)
		(width 0.15)
		(layer "F.Cu")
		(net 91)
	)
	(segment
		(start 166.715 93.6)
		(end 166.106 93.6)
		(width 0.15)
		(layer "F.Cu")
		(net 91)
	)
	(segment
		(start 124.69 91.9)
		(end 124.3 91.51)
		(width 0.15)
		(layer "F.Cu")
		(net 91)
	)
	(via
		(at 124.7 91.9)
		(size 0.45)
		(drill 0.2)
		(layers "F.Cu" "B.Cu")
		(remove_unused_layers yes)
		(keep_end_layers yes)
		(free yes)
		(zone_layer_connections)
		(net 91)
	)
	(via
		(at 111.17 76.65)
		(size 0.45)
		(drill 0.2)
		(layers "F.Cu" "B.Cu")
		(remove_unused_layers yes)
		(keep_end_layers yes)
		(zone_layer_connections)
		(net 91)
	)
	(via
		(at 166.106 93.6)
		(size 0.45)
		(drill 0.2)
		(layers "F.Cu" "B.Cu")
		(remove_unused_layers yes)
		(keep_end_layers yes)
		(zone_layer_connections)
		(net 91)
	)
	(segment
		(start 162.77 84.97)
		(end 162.77 82.07)
		(width 0.15)
		(layer "B.Cu")
		(net 91)
	)
	(segment
		(start 166.106 93.6)
		(end 166.106 93.594)
		(width 0.15)
		(layer "B.Cu")
		(net 91)
	)
	(segment
		(start 160.145 79.501483)
		(end 160.145 79.445)
		(width 0.15)
		(layer "B.Cu")
		(net 91)
	)
	(segment
		(start 160.288517 79.645)
		(end 160.145 79.501483)
		(width 0.15)
		(layer "B.Cu")
		(net 91)
	)
	(segment
		(start 148.948223 74.25)
		(end 128.21 74.25)
		(width 0.15)
		(layer "B.Cu")
		(net 91)
	)
	(segment
		(start 166.106 93.594)
		(end 167.6 92.1)
		(width 0.15)
		(layer "B.Cu")
		(net 91)
	)
	(segment
		(start 162.77 82.07)
		(end 160.345 79.645)
		(width 0.15)
		(layer "B.Cu")
		(net 91)
	)
	(segment
		(start 155.63 75.79)
		(end 155.2 76.22)
		(width 0.15)
		(layer "B.Cu")
		(net 91)
	)
	(segment
		(start 116.1 76.65)
		(end 111.17 76.65)
		(width 0.15)
		(layer "B.Cu")
		(net 91)
	)
	(segment
		(start 156.49 75.79)
		(end 155.63 75.79)
		(width 0.15)
		(layer "B.Cu")
		(net 91)
	)
	(segment
		(start 160.345 79.645)
		(end 160.288517 79.645)
		(width 0.15)
		(layer "B.Cu")
		(net 91)
	)
	(segment
		(start 160.145 79.445)
		(end 156.49 75.79)
		(width 0.15)
		(layer "B.Cu")
		(net 91)
	)
	(segment
		(start 167.6 89.8)
		(end 162.77 84.97)
		(width 0.15)
		(layer "B.Cu")
		(net 91)
	)
	(segment
		(start 155.2 76.22)
		(end 150.918223 76.22)
		(width 0.15)
		(layer "B.Cu")
		(net 91)
	)
	(segment
		(start 128.21 74.25)
		(end 128.06 74.1)
		(width 0.15)
		(layer "B.Cu")
		(net 91)
	)
	(segment
		(start 150.918223 76.22)
		(end 148.948223 74.25)
		(width 0.15)
		(layer "B.Cu")
		(net 91)
	)
	(segment
		(start 167.6 92.1)
		(end 167.6 89.8)
		(width 0.15)
		(layer "B.Cu")
		(net 91)
	)
	(segment
		(start 128.06 74.1)
		(end 118.65 74.1)
		(width 0.15)
		(layer "B.Cu")
		(net 91)
	)
	(segment
		(start 118.65 74.1)
		(end 116.1 76.65)
		(width 0.15)
		(layer "B.Cu")
		(net 91)
	)
	(segment
		(start 116.1 89.5)
		(end 114.2 87.6)
		(width 0.125)
		(layer "In6.Cu")
		(net 91)
	)
	(segment
		(start 114.2 87.6)
		(end 114.2 79.68)
		(width 0.125)
		(layer "In6.Cu")
		(net 91)
	)
	(segment
		(start 122 90.7)
		(end 121.7 90.4)
		(width 0.125)
		(layer "In6.Cu")
		(net 91)
	)
	(segment
		(start 123.6 91.5)
		(end 123.5 91.4)
		(width 0.125)
		(layer "In6.Cu")
		(net 91)
	)
	(segment
		(start 124.7 91.9)
		(end 124.3 91.5)
		(width 0.125)
		(layer "In6.Cu")
		(net 91)
	)
	(segment
		(start 123.3 90.7)
		(end 122 90.7)
		(width 0.125)
		(layer "In6.Cu")
		(net 91)
	)
	(segment
		(start 124.3 91.5)
		(end 123.6 91.5)
		(width 0.125)
		(layer "In6.Cu")
		(net 91)
	)
	(segment
		(start 116.876846 89.5)
		(end 116.1 89.5)
		(width 0.125)
		(layer "In6.Cu")
		(net 91)
	)
	(segment
		(start 123.5 91.4)
		(end 123.5 90.9)
		(width 0.125)
		(layer "In6.Cu")
		(net 91)
	)
	(segment
		(start 123.5 90.9)
		(end 123.3 90.7)
		(width 0.125)
		(layer "In6.Cu")
		(net 91)
	)
	(segment
		(start 118.176847 90.8)
		(end 116.876846 89.5)
		(width 0.125)
		(layer "In6.Cu")
		(net 91)
	)
	(segment
		(start 120.3 90.4)
		(end 119.9 90.8)
		(width 0.125)
		(layer "In6.Cu")
		(net 91)
	)
	(segment
		(start 121.7 90.4)
		(end 120.3 90.4)
		(width 0.125)
		(layer "In6.Cu")
		(net 91)
	)
	(segment
		(start 114.2 79.68)
		(end 111.17 76.65)
		(width 0.125)
		(layer "In6.Cu")
		(net 91)
	)
	(segment
		(start 119.9 90.8)
		(end 118.176847 90.8)
		(width 0.125)
		(layer "In6.Cu")
		(net 91)
	)
	(segment
		(start 166.715 92.6)
		(end 166.106 92.6)
		(width 0.15)
		(layer "F.Cu")
		(net 92)
	)
	(segment
		(start 123.1 91.9)
		(end 123.5 91.5)
		(width 0.15)
		(layer "F.Cu")
		(net 92)
	)
	(segment
		(start 123.076766 91.9)
		(end 123.1 91.9)
		(width 0.15)
		(layer "F.Cu")
		(net 92)
	)
	(via
		(at 123.076766 91.9)
		(size 0.45)
		(drill 0.2)
		(layers "F.Cu" "B.Cu")
		(remove_unused_layers yes)
		(keep_end_layers yes)
		(free yes)
		(zone_layer_connections)
		(net 92)
	)
	(via
		(at 111.15 77.3)
		(size 0.45)
		(drill 0.2)
		(layers "F.Cu" "B.Cu")
		(remove_unused_layers yes)
		(keep_end_layers yes)
		(zone_layer_connections)
		(net 92)
	)
	(via
		(at 166.106 92.6)
		(size 0.45)
		(drill 0.2)
		(layers "F.Cu" "B.Cu")
		(remove_unused_layers yes)
		(keep_end_layers yes)
		(zone_layer_connections)
		(net 92)
	)
	(segment
		(start 148.72 74.72)
		(end 150.47 76.47)
		(width 0.15)
		(layer "B.Cu")
		(net 92)
	)
	(segment
		(start 111.15 77.3)
		(end 116.18 77.32)
		(width 0.15)
		(layer "B.Cu")
		(net 92)
	)
	(segment
		(start 161.97 82.16)
		(end 161.97 85.37)
		(width 0.15)
		(layer "B.Cu")
		(net 92)
	)
	(segment
		(start 166.96 91.64)
		(end 166.106 92.494)
		(width 0.15)
		(layer "B.Cu")
		(net 92)
	)
	(segment
		(start 127.5 75)
		(end 128 75)
		(width 0.15)
		(layer "B.Cu")
		(net 92)
	)
	(segment
		(start 156.28 76.47)
		(end 161.97 82.16)
		(width 0.15)
		(layer "B.Cu")
		(net 92)
	)
	(segment
		(start 116.18 77.32)
		(end 118.78 74.72)
		(width 0.15)
		(layer "B.Cu")
		(net 92)
	)
	(segment
		(start 127.22 74.72)
		(end 127.5 75)
		(width 0.15)
		(layer "B.Cu")
		(net 92)
	)
	(segment
		(start 161.97 85.37)
		(end 166.96 90.36)
		(width 0.15)
		(layer "B.Cu")
		(net 92)
	)
	(segment
		(start 166.106 92.494)
		(end 166.106 92.6)
		(width 0.15)
		(layer "B.Cu")
		(net 92)
	)
	(segment
		(start 166.96 90.36)
		(end 166.96 91.64)
		(width 0.15)
		(layer "B.Cu")
		(net 92)
	)
	(segment
		(start 150.47 76.47)
		(end 156.28 76.47)
		(width 0.15)
		(layer "B.Cu")
		(net 92)
	)
	(segment
		(start 118.78 74.72)
		(end 127.22 74.72)
		(width 0.15)
		(layer "B.Cu")
		(net 92)
	)
	(segment
		(start 128.28 74.72)
		(end 148.72 74.72)
		(width 0.15)
		(layer "B.Cu")
		(net 92)
	)
	(segment
		(start 128 75)
		(end 128.28 74.72)
		(width 0.15)
		(layer "B.Cu")
		(net 92)
	)
	(segment
		(start 121.6 90.7)
		(end 121.9 91)
		(width 0.125)
		(layer "In6.Cu")
		(net 92)
	)
	(segment
		(start 111.15 77.3)
		(end 113.8 79.95)
		(width 0.125)
		(layer "In6.Cu")
		(net 92)
	)
	(segment
		(start 121.9 91.3)
		(end 122.0625 91.4625)
		(width 0.125)
		(layer "In6.Cu")
		(net 92)
	)
	(segment
		(start 122.0625 91.4625)
		(end 122.639266 91.4625)
		(width 0.125)
		(layer "In6.Cu")
		(net 92)
	)
	(segment
		(start 120.05 91.15)
		(end 120.5 90.7)
		(width 0.125)
		(layer "In6.Cu")
		(net 92)
	)
	(segment
		(start 120.5 90.7)
		(end 121.6 90.7)
		(width 0.125)
		(layer "In6.Cu")
		(net 92)
	)
	(segment
		(start 113.8 87.8)
		(end 115.9 89.9)
		(width 0.125)
		(layer "In6.Cu")
		(net 92)
	)
	(segment
		(start 113.8 79.95)
		(end 113.8 87.8)
		(width 0.125)
		(layer "In6.Cu")
		(net 92)
	)
	(segment
		(start 121.9 91)
		(end 121.9 91.3)
		(width 0.125)
		(layer "In6.Cu")
		(net 92)
	)
	(segment
		(start 115.9 89.9)
		(end 116.7 89.9)
		(width 0.125)
		(layer "In6.Cu")
		(net 92)
	)
	(segment
		(start 122.639266 91.4625)
		(end 123.076766 91.9)
		(width 0.125)
		(layer "In6.Cu")
		(net 92)
	)
	(segment
		(start 117.95 91.15)
		(end 120.05 91.15)
		(width 0.125)
		(layer "In6.Cu")
		(net 92)
	)
	(segment
		(start 116.7 89.9)
		(end 117.95 91.15)
		(width 0.125)
		(layer "In6.Cu")
		(net 92)
	)
	(segment
		(start 122.299999 91.923234)
		(end 122.299999 91.900001)
		(width 0.15)
		(layer "F.Cu")
		(net 93)
	)
	(segment
		(start 166.715 91.6)
		(end 166.106 91.6)
		(width 0.15)
		(layer "F.Cu")
		(net 93)
	)
	(segment
		(start 122.299999 91.900001)
		(end 122.7 91.5)
		(width 0.15)
		(layer "F.Cu")
		(net 93)
	)
	(via
		(at 111.17 78)
		(size 0.45)
		(drill 0.2)
		(layers "F.Cu" "B.Cu")
		(remove_unused_layers yes)
		(keep_end_layers yes)
		(zone_layer_connections)
		(net 93)
	)
	(via
		(at 166.106 91.6)
		(size 0.45)
		(drill 0.2)
		(layers "F.Cu" "B.Cu")
		(remove_unused_layers yes)
		(keep_end_layers yes)
		(zone_layer_connections)
		(net 93)
	)
	(via
		(at 122.299999 91.923234)
		(size 0.45)
		(drill 0.2)
		(layers "F.Cu" "B.Cu")
		(remove_unused_layers yes)
		(keep_end_layers yes)
		(free yes)
		(zone_layer_connections)
		(net 93)
	)
	(segment
		(start 128.59 75.11)
		(end 148.62 75.11)
		(width 0.15)
		(layer "B.Cu")
		(net 93)
	)
	(segment
		(start 148.62 75.11)
		(end 150.31 76.8)
		(width 0.15)
		(layer "B.Cu")
		(net 93)
	)
	(segment
		(start 161.28 82.6)
		(end 161.28 85.69)
		(width 0.15)
		(layer "B.Cu")
		(net 93)
	)
	(segment
		(start 166.106 90.516)
		(end 166.106 91.6)
		(width 0.15)
		(layer "B.Cu")
		(net 93)
	)
	(segment
		(start 126.91 75.11)
		(end 127.2 75.4)
		(width 0.15)
		(layer "B.Cu")
		(net 93)
	)
	(segment
		(start 119.14 75.11)
		(end 126.91 75.11)
		(width 0.15)
		(layer "B.Cu")
		(net 93)
	)
	(segment
		(start 128.3 75.4)
		(end 128.59 75.11)
		(width 0.15)
		(layer "B.Cu")
		(net 93)
	)
	(segment
		(start 111.17 78)
		(end 116.25 78)
		(width 0.15)
		(layer "B.Cu")
		(net 93)
	)
	(segment
		(start 150.31 76.8)
		(end 155.48 76.8)
		(width 0.15)
		(layer "B.Cu")
		(net 93)
	)
	(segment
		(start 116.25 78)
		(end 119.14 75.11)
		(width 0.15)
		(layer "B.Cu")
		(net 93)
	)
	(segment
		(start 127.2 75.4)
		(end 128.3 75.4)
		(width 0.15)
		(layer "B.Cu")
		(net 93)
	)
	(segment
		(start 161.28 85.69)
		(end 166.106 90.516)
		(width 0.15)
		(layer "B.Cu")
		(net 93)
	)
	(segment
		(start 155.48 76.8)
		(end 161.28 82.6)
		(width 0.15)
		(layer "B.Cu")
		(net 93)
	)
	(segment
		(start 113.4 88)
		(end 113.4 80.23)
		(width 0.125)
		(layer "In6.Cu")
		(net 93)
	)
	(segment
		(start 115.7 90.3)
		(end 113.4 88)
		(width 0.125)
		(layer "In6.Cu")
		(net 93)
	)
	(segment
		(start 122.299999 91.923234)
		(end 122.173234 91.923234)
		(width 0.125)
		(layer "In6.Cu")
		(net 93)
	)
	(segment
		(start 122.173234 91.923234)
		(end 121.7425 91.4925)
		(width 0.125)
		(layer "In6.Cu")
		(net 93)
	)
	(segment
		(start 113.4 80.23)
		(end 111.17 78)
		(width 0.125)
		(layer "In6.Cu")
		(net 93)
	)
	(segment
		(start 121.7425 91.4925)
		(end 117.7925 91.4925)
		(width 0.125)
		(layer "In6.Cu")
		(net 93)
	)
	(segment
		(start 116.6 90.3)
		(end 115.7 90.3)
		(width 0.125)
		(layer "In6.Cu")
		(net 93)
	)
	(segment
		(start 117.7925 91.4925)
		(end 116.6 90.3)
		(width 0.125)
		(layer "In6.Cu")
		(net 93)
	)
	(segment
		(start 121.52 91.88)
		(end 121.9 91.5)
		(width 0.15)
		(layer "F.Cu")
		(net 94)
	)
	(segment
		(start 164.6 90.6)
		(end 166.715 90.6)
		(width 0.15)
		(layer "F.Cu")
		(net 94)
	)
	(via
		(at 121.52 91.88)
		(size 0.45)
		(drill 0.2)
		(layers "F.Cu" "B.Cu")
		(remove_unused_layers yes)
		(keep_end_layers yes)
		(free yes)
		(zone_layer_connections)
		(net 94)
	)
	(via
		(at 111.11 78.62)
		(size 0.45)
		(drill 0.2)
		(layers "F.Cu" "B.Cu")
		(remove_unused_layers yes)
		(keep_end_layers yes)
		(zone_layer_connections)
		(net 94)
	)
	(via
		(at 164.6 90.6)
		(size 0.45)
		(drill 0.2)
		(layers "F.Cu" "B.Cu")
		(remove_unused_layers yes)
		(keep_end_layers yes)
		(zone_layer_connections)
		(net 94)
	)
	(segment
		(start 111.11 78.62)
		(end 116.38 78.62)
		(width 0.15)
		(layer "B.Cu")
		(net 94)
	)
	(segment
		(start 140.47 75.75)
		(end 146.42 75.75)
		(width 0.15)
		(layer "B.Cu")
		(net 94)
	)
	(segment
		(start 116.38 78.62)
		(end 119.25 75.75)
		(width 0.15)
		(layer "B.Cu")
		(net 94)
	)
	(segment
		(start 147.195 76.525)
		(end 147.87 77.2)
		(width 0.15)
		(layer "B.Cu")
		(net 94)
	)
	(segment
		(start 154.86 77.2)
		(end 160.53 82.87)
		(width 0.15)
		(layer "B.Cu")
		(net 94)
	)
	(segment
		(start 147.87 77.2)
		(end 154.86 77.2)
		(width 0.15)
		(layer "B.Cu")
		(net 94)
	)
	(segment
		(start 164.6 90.1)
		(end 164.6 90.6)
		(width 0.15)
		(layer "B.Cu")
		(net 94)
	)
	(segment
		(start 147.193248 76.525)
		(end 147.195 76.525)
		(width 0.15)
		(layer "B.Cu")
		(net 94)
	)
	(segment
		(start 160.53 82.87)
		(end 160.53 86.03)
		(width 0.15)
		(layer "B.Cu")
		(net 94)
	)
	(segment
		(start 146.915 76.245)
		(end 146.915 76.246752)
		(width 0.15)
		(layer "B.Cu")
		(net 94)
	)
	(segment
		(start 160.53 86.03)
		(end 164.6 90.1)
		(width 0.15)
		(layer "B.Cu")
		(net 94)
	)
	(segment
		(start 146.42 75.75)
		(end 146.915 76.245)
		(width 0.15)
		(layer "B.Cu")
		(net 94)
	)
	(segment
		(start 140.12 76.1)
		(end 140.47 75.75)
		(width 0.15)
		(layer "B.Cu")
		(net 94)
	)
	(segment
		(start 119.25 75.75)
		(end 138.34 75.75)
		(width 0.15)
		(layer "B.Cu")
		(net 94)
	)
	(segment
		(start 146.915 76.246752)
		(end 147.193248 76.525)
		(width 0.15)
		(layer "B.Cu")
		(net 94)
	)
	(segment
		(start 138.34 75.75)
		(end 138.69 76.1)
		(width 0.15)
		(layer "B.Cu")
		(net 94)
	)
	(segment
		(start 138.69 76.1)
		(end 140.12 76.1)
		(width 0.15)
		(layer "B.Cu")
		(net 94)
	)
	(segment
		(start 111.11 78.62)
		(end 111.12 78.62)
		(width 0.125)
		(layer "In6.Cu")
		(net 94)
	)
	(segment
		(start 116.5 90.7)
		(end 117.649 91.849)
		(width 0.125)
		(layer "In6.Cu")
		(net 94)
	)
	(segment
		(start 111.12 78.62)
		(end 113 80.5)
		(width 0.125)
		(layer "In6.Cu")
		(net 94)
	)
	(segment
		(start 117.649 91.849)
		(end 121.489 91.849)
		(width 0.125)
		(layer "In6.Cu")
		(net 94)
	)
	(segment
		(start 115.5 90.7)
		(end 116.5 90.7)
		(width 0.125)
		(layer "In6.Cu")
		(net 94)
	)
	(segment
		(start 113 88.2)
		(end 115.5 90.7)
		(width 0.125)
		(layer "In6.Cu")
		(net 94)
	)
	(segment
		(start 113 80.5)
		(end 113 88.2)
		(width 0.125)
		(layer "In6.Cu")
		(net 94)
	)
	(segment
		(start 121.489 91.849)
		(end 121.52 91.88)
		(width 0.125)
		(layer "In6.Cu")
		(net 94)
	)
	(segment
		(start 118.879 92.7)
		(end 122.3 92.7)
		(width 0.15)
		(layer "F.Cu")
		(net 99)
	)
	(segment
		(start 122.7 93.1)
		(end 122.3 92.7)
		(width 0.15)
		(layer "F.Cu")
		(net 99)
	)
	(segment
		(start 125.508557 116.291443)
		(end 125.967114 116.75)
		(width 0.15)
		(layer "F.Cu")
		(net 99)
	)
	(segment
		(start 125.967114 116.75)
		(end 132.3 116.75)
		(width 0.15)
		(layer "F.Cu")
		(net 99)
	)
	(segment
		(start 118.879 92.7)
		(end 118.3905 92.2115)
		(width 0.15)
		(layer "F.Cu")
		(net 99)
	)
	(segment
		(start 132.3 116.75)
		(end 132.75 116.3)
		(width 0.15)
		(layer "F.Cu")
		(net 99)
	)
	(via
		(at 125.508557 116.291443)
		(size 0.45)
		(drill 0.2)
		(layers "F.Cu" "B.Cu")
		(remove_unused_layers yes)
		(keep_end_layers yes)
		(zone_layer_connections)
		(net 99)
	)
	(via
		(at 118.3905 92.2115)
		(size 0.45)
		(drill 0.2)
		(layers "F.Cu" "B.Cu")
		(remove_unused_layers yes)
		(keep_end_layers yes)
		(zone_layer_connections)
		(net 99)
	)
	(segment
		(start 118 92.7)
		(end 118.3905 92.3095)
		(width 0.125)
		(layer "B.Cu")
		(net 99)
	)
	(segment
		(start 125.12 116.19)
		(end 125.01 116.19)
		(width 0.15)
		(layer "B.Cu")
		(net 99)
	)
	(segment
		(start 125.508557 116.291443)
		(end 125.221443 116.291443)
		(width 0.15)
		(layer "B.Cu")
		(net 99)
	)
	(segment
		(start 118 109.18)
		(end 118 92.7)
		(width 0.125)
		(layer "B.Cu")
		(net 99)
	)
	(segment
		(start 118.3905 92.3095)
		(end 118.3905 92.2115)
		(width 0.125)
		(layer "B.Cu")
		(net 99)
	)
	(segment
		(start 118.46 109.64)
		(end 118 109.18)
		(width 0.125)
		(layer "B.Cu")
		(net 99)
	)
	(segment
		(start 125.221443 116.291443)
		(end 125.12 116.19)
		(width 0.15)
		(layer "B.Cu")
		(net 99)
	)
	(segment
		(start 125.01 116.19)
		(end 118.46 109.64)
		(width 0.15)
		(layer "B.Cu")
		(net 99)
	)
	(segment
		(start 124.11 101.25)
		(end 124.13 101.23)
		(width 0.15)
		(layer "F.Cu")
		(net 100)
	)
	(segment
		(start 125.112058 91.5)
		(end 125.491558 91.8795)
		(width 0.15)
		(layer "F.Cu")
		(net 100)
	)
	(segment
		(start 130.7 103.9)
		(end 129.42 105.18)
		(width 0.15)
		(layer "F.Cu")
		(net 100)
	)
	(segment
		(start 124.13 101.37)
		(end 124.13 101.23)
		(width 0.15)
		(layer "F.Cu")
		(net 100)
	)
	(segment
		(start 154.52 76.6)
		(end 157.59 76.6)
		(width 0.15)
		(layer "F.Cu")
		(net 100)
	)
	(segment
		(start 124.13 100.33)
		(end 124.1 100.3)
		(width 0.15)
		(layer "F.Cu")
		(net 100)
	)
	(segment
		(start 122.75 101.25)
		(end 124.11 101.25)
		(width 0.15)
		(layer "F.Cu")
		(net 100)
	)
	(segment
		(start 124.13 101.13)
		(end 124.01 101.25)
		(width 0.15)
		(layer "F.Cu")
		(net 100)
	)
	(segment
		(start 152.97 78.15)
		(end 154.52 76.6)
		(width 0.15)
		(layer "F.Cu")
		(net 100)
	)
	(segment
		(start 104.59 108.7)
		(end 104.59 107.9)
		(width 0.15)
		(layer "F.Cu")
		(net 100)
	)
	(segment
		(start 123.14 101.25)
		(end 123.05 101.25)
		(width 0.15)
		(layer "F.Cu")
		(net 100)
	)
	(segment
		(start 113.59 109.8)
		(end 105.69 109.8)
		(width 0.15)
		(layer "F.Cu")
		(net 100)
	)
	(segment
		(start 131.75 104.45)
		(end 131.75 116.265)
		(width 0.15)
		(layer "F.Cu")
		(net 100)
	)
	(segment
		(start 123.95 101.25)
		(end 124.11 101.25)
		(width 0.13)
		(layer "F.Cu")
		(net 100)
	)
	(segment
		(start 124.13 101.03)
		(end 124.13 101.13)
		(width 0.15)
		(layer "F.Cu")
		(net 100)
	)
	(segment
		(start 122.75 101.25)
		(end 122.14 101.25)
		(width 0.15)
		(layer "F.Cu")
		(net 100)
	)
	(segment
		(start 124.13 101.23)
		(end 124.13 101.03)
		(width 0.15)
		(layer "F.Cu")
		(net 100)
	)
	(segment
		(start 123.95 101.25)
		(end 124.01 101.25)
		(width 0.15)
		(layer "F.Cu")
		(net 100)
	)
	(segment
		(start 123.14 101.25)
		(end 123.95 101.25)
		(width 0.13)
		(layer "F.Cu")
		(net 100)
	)
	(segment
		(start 123.05 101.25)
		(end 122.75 101.25)
		(width 0.15)
		(layer "F.Cu")
		(net 100)
	)
	(segment
		(start 152.97 79.75)
		(end 152.97 78.15)
		(width 0.15)
		(layer "F.Cu")
		(net 100)
	)
	(segment
		(start 132.3 103.9)
		(end 131.75 104.45)
		(width 0.15)
		(layer "F.Cu")
		(net 100)
	)
	(segment
		(start 129.42 105.18)
		(end 125.66 105.18)
		(width 0.15)
		(layer "F.Cu")
		(net 100)
	)
	(segment
		(start 124.13 103.65)
		(end 124.13 101.37)
		(width 0.15)
		(layer "F.Cu")
		(net 100)
	)
	(segment
		(start 123.05 101.25)
		(end 124.11 101.25)
		(width 0.13)
		(layer "F.Cu")
		(net 100)
	)
	(segment
		(start 125.66 105.18)
		(end 124.13 103.65)
		(width 0.15)
		(layer "F.Cu")
		(net 100)
	)
	(segment
		(start 124.01 101.25)
		(end 124.13 101.37)
		(width 0.15)
		(layer "F.Cu")
		(net 100)
	)
	(segment
		(start 105.69 109.8)
		(end 104.59 108.7)
		(width 0.15)
		(layer "F.Cu")
		(net 100)
	)
	(segment
		(start 124.13 101.03)
		(end 124.13 100.33)
		(width 0.15)
		(layer "F.Cu")
		(net 100)
	)
	(segment
		(start 132.3 103.9)
		(end 130.7 103.9)
		(width 0.15)
		(layer "F.Cu")
		(net 100)
	)
	(segment
		(start 122.14 101.25)
		(end 113.59 109.8)
		(width 0.15)
		(layer "F.Cu")
		(net 100)
	)
	(via
		(at 152.97 79.75)
		(size 0.45)
		(drill 0.2)
		(layers "F.Cu" "B.Cu")
		(remove_unused_layers yes)
		(keep_end_layers yes)
		(zone_layer_connections)
		(net 100)
	)
	(via
		(at 132.3 103.9)
		(size 0.45)
		(drill 0.2)
		(layers "F.Cu" "B.Cu")
		(remove_unused_layers yes)
		(keep_end_layers yes)
		(zone_layer_connections)
		(net 100)
	)
	(via
		(at 125.491558 91.8795)
		(size 0.45)
		(drill 0.2)
		(layers "F.Cu" "B.Cu")
		(remove_unused_layers yes)
		(keep_end_layers yes)
		(zone_layer_connections)
		(net 100)
	)
	(via
		(at 124.1 100.3)
		(size 0.45)
		(drill 0.2)
		(layers "F.Cu" "B.Cu")
		(net 100)
	)
	(segment
		(start 136.15 103.9)
		(end 138.35 101.7)
		(width 0.15)
		(layer "B.Cu")
		(net 100)
	)
	(segment
		(start 124.848008 93.1)
		(end 124.5 93.1)
		(width 0.125)
		(layer "B.Cu")
		(net 100)
	)
	(segment
		(start 152.97 79.77)
		(end 154.4 81.2)
		(width 0.15)
		(layer "B.Cu")
		(net 100)
	)
	(segment
		(start 154.4 85.8)
		(end 154.4 81.2)
		(width 0.15)
		(layer "B.Cu")
		(net 100)
	)
	(segment
		(start 123.1 97.2)
		(end 121.9925 98.3075)
		(width 0.125)
		(layer "B.Cu")
		(net 100)
	)
	(segment
		(start 142.1 101.7)
		(end 150.25 93.55)
		(width 0.15)
		(layer "B.Cu")
		(net 100)
	)
	(segment
		(start 124.5 93.1)
		(end 123.1 94.5)
		(width 0.125)
		(layer "B.Cu")
		(net 100)
	)
	(segment
		(start 123.1 94.5)
		(end 123.1 97.2)
		(width 0.125)
		(layer "B.Cu")
		(net 100)
	)
	(segment
		(start 123.3 101.1)
		(end 124.1 100.3)
		(width 0.125)
		(layer "B.Cu")
		(net 100)
	)
	(segment
		(start 152.97 79.75)
		(end 152.97 79.77)
		(width 0.15)
		(layer "B.Cu")
		(net 100)
	)
	(segment
		(start 150.25 93.55)
		(end 150.25 89.95)
		(width 0.15)
		(layer "B.Cu")
		(net 100)
	)
	(segment
		(start 125.491558 91.8795)
		(end 125.0875 92.283558)
		(width 0.125)
		(layer "B.Cu")
		(net 100)
	)
	(segment
		(start 121.9925 100.8925)
		(end 122.2 101.1)
		(width 0.125)
		(layer "B.Cu")
		(net 100)
	)
	(segment
		(start 125.0875 92.283558)
		(end 125.0875 92.860508)
		(width 0.125)
		(layer "B.Cu")
		(net 100)
	)
	(segment
		(start 125.0875 92.860508)
		(end 124.848008 93.1)
		(width 0.125)
		(layer "B.Cu")
		(net 100)
	)
	(segment
		(start 122.2 101.1)
		(end 123.3 101.1)
		(width 0.125)
		(layer "B.Cu")
		(net 100)
	)
	(segment
		(start 150.25 89.95)
		(end 154.4 85.8)
		(width 0.15)
		(layer "B.Cu")
		(net 100)
	)
	(segment
		(start 121.9925 98.3075)
		(end 121.9925 100.8925)
		(width 0.125)
		(layer "B.Cu")
		(net 100)
	)
	(segment
		(start 138.35 101.7)
		(end 142.1 101.7)
		(width 0.15)
		(layer "B.Cu")
		(net 100)
	)
	(segment
		(start 132.3 103.9)
		(end 136.15 103.9)
		(width 0.15)
		(layer "B.Cu")
		(net 100)
	)
	(segment
		(start 155.04 78.25)
		(end 155.09 78.2)
		(width 0.15)
		(layer "F.Cu")
		(net 101)
	)
	(segment
		(start 123.29 100.2)
		(end 122.84 99.75)
		(width 0.15)
		(layer "F.Cu")
		(net 101)
	)
	(segment
		(start 130.75 116.265)
		(end 130.75 105.75)
		(width 0.15)
		(layer "F.Cu")
		(net 101)
	)
	(segment
		(start 122.34 99.75)
		(end 112.99 109.1)
		(width 0.15)
		(layer "F.Cu")
		(net 101)
	)
	(segment
		(start 126.3 91.9)
		(end 126.29 91.9)
		(width 0.15)
		(layer "F.Cu")
		(net 101)
	)
	(segment
		(start 130.75 105.75)
		(end 130.135 105.135)
		(width 0.15)
		(layer "F.Cu")
		(net 101)
	)
	(segment
		(start 123.63 103.95)
		(end 125.39 105.71)
		(width 0.15)
		(layer "F.Cu")
		(net 101)
	)
	(segment
		(start 106.49 109.1)
		(end 106.09 108.7)
		(width 0.15)
		(layer "F.Cu")
		(net 101)
	)
	(segment
		(start 125.39 105.71)
		(end 129.56 105.71)
		(width 0.15)
		(layer "F.Cu")
		(net 101)
	)
	(segment
		(start 155.09 78.2)
		(end 157.59 78.2)
		(width 0.15)
		(layer "F.Cu")
		(net 101)
	)
	(segment
		(start 112.99 109.1)
		(end 106.49 109.1)
		(width 0.15)
		(layer "F.Cu")
		(net 101)
	)
	(segment
		(start 122.84 99.75)
		(end 122.34 99.75)
		(width 0.15)
		(layer "F.Cu")
		(net 101)
	)
	(segment
		(start 126.29 91.9)
		(end 125.9 91.51)
		(width 0.15)
		(layer "F.Cu")
		(net 101)
	)
	(segment
		(start 129.56 105.71)
		(end 130.135 105.135)
		(width 0.15)
		(layer "F.Cu")
		(net 101)
	)
	(segment
		(start 130.92 104.35)
		(end 130.94 104.35)
		(width 0.15)
		(layer "F.Cu")
		(net 101)
	)
	(segment
		(start 130.135 105.135)
		(end 130.92 104.35)
		(width 0.15)
		(layer "F.Cu")
		(net 101)
	)
	(segment
		(start 153.73 78.25)
		(end 155.04 78.25)
		(width 0.15)
		(layer "F.Cu")
		(net 101)
	)
	(segment
		(start 106.09 108.7)
		(end 106.09 107.9)
		(width 0.15)
		(layer "F.Cu")
		(net 101)
	)
	(segment
		(start 123.63 103.55)
		(end 123.63 103.95)
		(width 0.15)
		(layer "F.Cu")
		(net 101)
	)
	(via
		(at 130.94 104.35)
		(size 0.45)
		(drill 0.2)
		(layers "F.Cu" "B.Cu")
		(remove_unused_layers yes)
		(keep_end_layers yes)
		(zone_layer_connections)
		(net 101)
	)
	(via
		(at 123.29 100.2)
		(size 0.45)
		(drill 0.2)
		(layers "F.Cu" "B.Cu")
		(remove_unused_layers yes)
		(keep_end_layers yes)
		(zone_layer_connections)
		(net 101)
	)
	(via
		(at 126.3 91.9)
		(size 0.45)
		(drill 0.2)
		(layers "F.Cu" "B.Cu")
		(remove_unused_layers yes)
		(keep_end_layers yes)
		(free yes)
		(zone_layer_connections)
		(net 101)
	)
	(via
		(at 123.63 103.55)
		(size 0.45)
		(drill 0.2)
		(layers "F.Cu" "B.Cu")
		(remove_unused_layers yes)
		(keep_end_layers yes)
		(zone_layer_connections)
		(net 101)
	)
	(via
		(at 153.73 78.25)
		(size 0.45)
		(drill 0.2)
		(layers "F.Cu" "B.Cu")
		(remove_unused_layers yes)
		(keep_end_layers yes)
		(zone_layer_connections)
		(net 101)
	)
	(segment
		(start 131.79 103.5)
		(end 135.95 103.5)
		(width 0.15)
		(layer "B.Cu")
		(net 101)
	)
	(segment
		(start 125.9 92.9)
		(end 125.9 92.3)
		(width 0.125)
		(layer "B.Cu")
		(net 101)
	)
	(segment
		(start 125.1 93.648008)
		(end 124.848008 93.9)
		(width 0.125)
		(layer "B.Cu")
		(net 101)
	)
	(segment
		(start 123.63 101.47)
		(end 124.5 100.6)
		(width 0.125)
		(layer "B.Cu")
		(net 101)
	)
	(segment
		(start 123.63 103.55)
		(end 123.63 101.47)
		(width 0.125)
		(layer "B.Cu")
		(net 101)
	)
	(segment
		(start 123.69 99.8)
		(end 123.29 100.2)
		(width 0.125)
		(layer "B.Cu")
		(net 101)
	)
	(segment
		(start 124.1 99.8)
		(end 124 99.8)
		(width 0.125)
		(layer "B.Cu")
		(net 101)
	)
	(segment
		(start 124 99.8)
		(end 123.9 99.7)
		(width 0.125)
		(layer "B.Cu")
		(net 101)
	)
	(segment
		(start 123.9 94.9)
		(end 123.9 99.7)
		(width 0.125)
		(layer "B.Cu")
		(net 101)
	)
	(segment
		(start 141.6 100.55)
		(end 149.5 92.65)
		(width 0.15)
		(layer "B.Cu")
		(net 101)
	)
	(segment
		(start 153.2 81.4)
		(end 151.8 80)
		(width 0.15)
		(layer "B.Cu")
		(net 101)
	)
	(segment
		(start 123.9 99.7)
		(end 123.9 99.8)
		(width 0.125)
		(layer "B.Cu")
		(net 101)
	)
	(segment
		(start 130.94 104.35)
		(end 131.79 103.5)
		(width 0.15)
		(layer "B.Cu")
		(net 101)
	)
	(segment
		(start 135.95 103.5)
		(end 138.9 100.55)
		(width 0.15)
		(layer "B.Cu")
		(net 101)
	)
	(segment
		(start 149.5 92.65)
		(end 149.5 89.5)
		(width 0.15)
		(layer "B.Cu")
		(net 101)
	)
	(segment
		(start 125.7 93.1)
		(end 125.9 92.9)
		(width 0.125)
		(layer "B.Cu")
		(net 101)
	)
	(segment
		(start 125.1 93.3)
		(end 125.3 93.1)
		(width 0.125)
		(layer "B.Cu")
		(net 101)
	)
	(segment
		(start 123.8 99.8)
		(end 123.9 99.7)
		(width 0.125)
		(layer "B.Cu")
		(net 101)
	)
	(segment
		(start 125.9 92.3)
		(end 126.3 91.9)
		(width 0.125)
		(layer "B.Cu")
		(net 101)
	)
	(segment
		(start 124.3 94.5)
		(end 123.9 94.9)
		(width 0.125)
		(layer "B.Cu")
		(net 101)
	)
	(segment
		(start 151.8 79)
		(end 152.55 78.25)
		(width 0.15)
		(layer "B.Cu")
		(net 101)
	)
	(segment
		(start 138.9 100.55)
		(end 141.6 100.55)
		(width 0.15)
		(layer "B.Cu")
		(net 101)
	)
	(segment
		(start 124.3 99.8)
		(end 124.1 99.8)
		(width 0.125)
		(layer "B.Cu")
		(net 101)
	)
	(segment
		(start 124.1 99.8)
		(end 123.9 99.8)
		(width 0.125)
		(layer "B.Cu")
		(net 101)
	)
	(segment
		(start 124.5 100)
		(end 124.5 100.6)
		(width 0.125)
		(layer "B.Cu")
		(net 101)
	)
	(segment
		(start 125.3 93.1)
		(end 125.7 93.1)
		(width 0.125)
		(layer "B.Cu")
		(net 101)
	)
	(segment
		(start 153.2 85.8)
		(end 153.2 81.4)
		(width 0.15)
		(layer "B.Cu")
		(net 101)
	)
	(segment
		(start 123.8 99.8)
		(end 123.69 99.8)
		(width 0.125)
		(layer "B.Cu")
		(net 101)
	)
	(segment
		(start 125.1 93.3)
		(end 125.1 93.648008)
		(width 0.125)
		(layer "B.Cu")
		(net 101)
	)
	(segment
		(start 124.848008 93.9)
		(end 124.561992 93.9)
		(width 0.125)
		(layer "B.Cu")
		(net 101)
	)
	(segment
		(start 151.8 80)
		(end 151.8 79)
		(width 0.15)
		(layer "B.Cu")
		(net 101)
	)
	(segment
		(start 152.55 78.25)
		(end 153.73 78.25)
		(width 0.15)
		(layer "B.Cu")
		(net 101)
	)
	(segment
		(start 149.5 89.5)
		(end 153.2 85.8)
		(width 0.15)
		(layer "B.Cu")
		(net 101)
	)
	(segment
		(start 124.561992 93.9)
		(end 124.3 94.161992)
		(width 0.125)
		(layer "B.Cu")
		(net 101)
	)
	(segment
		(start 124.3 94.161992)
		(end 124.3 94.5)
		(width 0.125)
		(layer "B.Cu")
		(net 101)
	)
	(segment
		(start 124.3 99.8)
		(end 124.5 100)
		(width 0.125)
		(layer "B.Cu")
		(net 101)
	)
	(segment
		(start 123.9 99.8)
		(end 123.8 99.8)
		(width 0.125)
		(layer "B.Cu")
		(net 101)
	)
	(segment
		(start 129.75 116.265)
		(end 129.75 111.384)
		(width 0.15)
		(layer "F.Cu")
		(net 106)
	)
	(segment
		(start 124.7 92.7)
		(end 125.1 93.1)
		(width 0.15)
		(layer "F.Cu")
		(net 106)
	)
	(segment
		(start 129.75 111.384)
		(end 129.596 111.23)
		(width 0.15)
		(layer "F.Cu")
		(net 106)
	)
	(via
		(at 124.7 92.7)
		(size 0.45)
		(drill 0.2)
		(layers "F.Cu" "B.Cu")
		(remove_unused_layers yes)
		(keep_end_layers yes)
		(free yes)
		(zone_layer_connections)
		(net 106)
	)
	(via
		(at 129.596 111.23)
		(size 0.45)
		(drill 0.2)
		(layers "F.Cu" "B.Cu")
		(remove_unused_layers yes)
		(keep_end_layers yes)
		(zone_layer_connections)
		(net 106)
	)
	(segment
		(start 124.7 92.7)
		(end 124.5 92.7)
		(width 0.125)
		(layer "B.Cu")
		(net 106)
	)
	(segment
		(start 124.5 92.7)
		(end 122.3 94.9)
		(width 0.125)
		(layer "B.Cu")
		(net 106)
	)
	(segment
		(start 121.6 98.1)
		(end 121.6 103.25)
		(width 0.125)
		(layer "B.Cu")
		(net 106)
	)
	(segment
		(start 122.3 94.9)
		(end 122.3 97.4)
		(width 0.125)
		(layer "B.Cu")
		(net 106)
	)
	(segment
		(start 122.3 97.4)
		(end 121.6 98.1)
		(width 0.125)
		(layer "B.Cu")
		(net 106)
	)
	(segment
		(start 121.6 103.25)
		(end 122.37 104.02)
		(width 0.125)
		(layer "B.Cu")
		(net 106)
	)
	(segment
		(start 124.66 106.09)
		(end 124.44 106.09)
		(width 0.15)
		(layer "B.Cu")
		(net 106)
	)
	(segment
		(start 129.596 111.026)
		(end 124.66 106.09)
		(width 0.15)
		(layer "B.Cu")
		(net 106)
	)
	(segment
		(start 124.44 106.09)
		(end 122.37 104.02)
		(width 0.15)
		(layer "B.Cu")
		(net 106)
	)
	(segment
		(start 129.596 111.23)
		(end 129.596 111.026)
		(width 0.15)
		(layer "B.Cu")
		(net 106)
	)
	(segment
		(start 129.196 111.395686)
		(end 129.2 111.399686)
		(width 0.15)
		(layer "F.Cu")
		(net 107)
	)
	(segment
		(start 129.2 115.815)
		(end 128.75 116.265)
		(width 0.15)
		(layer "F.Cu")
		(net 107)
	)
	(segment
		(start 125.478201 93.5)
		(end 125.878201 93.1)
		(width 0.15)
		(layer "F.Cu")
		(net 107)
	)
	(segment
		(start 129.596 110.24549)
		(end 129.196 110.64549)
		(width 0.15)
		(layer "F.Cu")
		(net 107)
	)
	(segment
		(start 129.2 111.399686)
		(end 129.2 115.815)
		(width 0.15)
		(layer "F.Cu")
		(net 107)
	)
	(segment
		(start 129.196 110.64549)
		(end 129.196 111.395686)
		(width 0.15)
		(layer "F.Cu")
		(net 107)
	)
	(via
		(at 129.596 110.24549)
		(size 0.45)
		(drill 0.2)
		(layers "F.Cu" "B.Cu")
		(remove_unused_layers yes)
		(keep_end_layers yes)
		(zone_layer_connections)
		(net 107)
	)
	(via
		(at 125.5 93.5)
		(size 0.45)
		(drill 0.2)
		(layers "F.Cu" "B.Cu")
		(remove_unused_layers yes)
		(keep_end_layers yes)
		(free yes)
		(zone_layer_connections)
		(net 107)
	)
	(segment
		(start 126.5 96.7)
		(end 126.5 107.14949)
		(width 0.125)
		(layer "B.Cu")
		(net 107)
	)
	(segment
		(start 126.2 96.4)
		(end 126.5 96.7)
		(width 0.125)
		(layer "B.Cu")
		(net 107)
	)
	(segment
		(start 125.3 96.4)
		(end 126.2 96.4)
		(width 0.125)
		(layer "B.Cu")
		(net 107)
	)
	(segment
		(start 125.5 93.5)
		(end 125.5 93.6)
		(width 0.125)
		(layer "B.Cu")
		(net 107)
	)
	(segment
		(start 125.5 93.6)
		(end 125.1125 93.9875)
		(width 0.125)
		(layer "B.Cu")
		(net 107)
	)
	(segment
		(start 125.1125 93.9875)
		(end 125.1125 96.2125)
		(width 0.125)
		(layer "B.Cu")
		(net 107)
	)
	(segment
		(start 125.1125 96.2125)
		(end 125.3 96.4)
		(width 0.125)
		(layer "B.Cu")
		(net 107)
	)
	(segment
		(start 126.5 107.14949)
		(end 129.596 110.24549)
		(width 0.125)
		(layer "B.Cu")
		(net 107)
	)
	(segment
		(start 127.75 115.6)
		(end 128.8 114.55)
		(width 0.15)
		(layer "F.Cu")
		(net 108)
	)
	(segment
		(start 128.8 114.55)
		(end 128.8 110.166)
		(width 0.15)
		(layer "F.Cu")
		(net 108)
	)
	(segment
		(start 128.8 110.166)
		(end 129.596 109.37)
		(width 0.15)
		(layer "F.Cu")
		(net 108)
	)
	(segment
		(start 127.75 116.265)
		(end 127.75 115.6)
		(width 0.15)
		(layer "F.Cu")
		(net 108)
	)
	(segment
		(start 126.3 92.7)
		(end 125.973688 92.373688)
		(width 0.15)
		(layer "F.Cu")
		(net 108)
	)
	(via
		(at 126.3 92.7)
		(size 0.45)
		(drill 0.2)
		(layers "F.Cu" "B.Cu")
		(remove_unused_layers yes)
		(keep_end_layers yes)
		(free yes)
		(zone_layer_connections)
		(net 108)
	)
	(via
		(at 129.596 109.37)
		(size 0.45)
		(drill 0.2)
		(layers "F.Cu" "B.Cu")
		(remove_unused_layers yes)
		(keep_end_layers yes)
		(zone_layer_connections)
		(net 108)
	)
	(segment
		(start 126.7 94.15)
		(end 126.9 94.35)
		(width 0.125)
		(layer "B.Cu")
		(net 108)
	)
	(segment
		(start 126.7 93.1)
		(end 126.7 94.15)
		(width 0.125)
		(layer "B.Cu")
		(net 108)
	)
	(segment
		(start 126.3 92.7)
		(end 126.7 93.1)
		(width 0.125)
		(layer "B.Cu")
		(net 108)
	)
	(segment
		(start 126.9 106.674)
		(end 129.596 109.37)
		(width 0.125)
		(layer "B.Cu")
		(net 108)
	)
	(segment
		(start 126.9 94.35)
		(end 126.9 106.674)
		(width 0.125)
		(layer "B.Cu")
		(net 108)
	)
	(segment
		(start 129.19 96.39)
		(end 129.19 96.61)
		(width 0.15)
		(layer "F.Cu")
		(net 110)
	)
	(segment
		(start 129.183 99.483)
		(end 129.183 104.488541)
		(width 0.15)
		(layer "F.Cu")
		(net 110)
	)
	(segment
		(start 129.19 96.61)
		(end 129.183 96.617)
		(width 0.15)
		(layer "F.Cu")
		(net 110)
	)
	(segment
		(start 126.655 119.2832)
		(end 127.123199 118.815001)
		(width 0.15)
		(layer "F.Cu")
		(net 110)
	)
	(segment
		(start 129.183 99.433)
		(end 129.183 99.483)
		(width 0.15)
		(layer "F.Cu")
		(net 110)
	)
	(segment
		(start 127.280609 118.815001)
		(end 127.434108 118.9685)
		(width 0.15)
		(layer "F.Cu")
		(net 110)
	)
	(segment
		(start 126.655 119.65)
		(end 126.655 119.2832)
		(width 0.15)
		(layer "F.Cu")
		(net 110)
	)
	(segment
		(start 129.183 96.617)
		(end 129.183 98.233)
		(width 0.15)
		(layer "F.Cu")
		(net 110)
	)
	(segment
		(start 129.183 104.488541)
		(end 129.225 104.530541)
		(width 0.15)
		(layer "F.Cu")
		(net 110)
	)
	(segment
		(start 127.123199 118.815001)
		(end 127.280609 118.815001)
		(width 0.15)
		(layer "F.Cu")
		(net 110)
	)
	(via
		(at 127.434108 118.9685)
		(size 0.45)
		(drill 0.2)
		(layers "F.Cu" "B.Cu")
		(remove_unused_layers yes)
		(keep_end_layers yes)
		(zone_layer_connections)
		(net 110)
	)
	(via
		(at 129.225 104.530541)
		(size 0.45)
		(drill 0.2)
		(layers "F.Cu" "B.Cu")
		(remove_unused_layers yes)
		(keep_end_layers yes)
		(zone_layer_connections)
		(net 110)
	)
	(arc
		(start 129.483 99.133)
		(mid 129.270868 99.220868)
		(end 129.183 99.433)
		(width 0.15)
		(layer "F.Cu")
		(net 110)
	)
	(arc
		(start 129.183 98.233)
		(mid 129.270868 98.445132)
		(end 129.483 98.533)
		(width 0.15)
		(layer "F.Cu")
		(net 110)
	)
	(arc
		(start 129.783 98.833)
		(mid 129.695132 99.045132)
		(end 129.483 99.133)
		(width 0.15)
		(layer "F.Cu")
		(net 110)
	)
	(arc
		(start 129.483 98.533)
		(mid 129.695132 98.620868)
		(end 129.783 98.833)
		(width 0.15)
		(layer "F.Cu")
		(net 110)
	)
	(segment
		(start 129.1875 108.2725)
		(end 129.1875 113.5525)
		(width 0.168)
		(layer "In4.Cu")
		(net 110)
	)
	(segment
		(start 128.1625 106.86)
		(end 129.7375 106.86)
		(width 0.168)
		(layer "In4.Cu")
		(net 110)
	)
	(segment
		(start 129.5 105.285)
		(end 129.7375 105.285)
		(width 0.168)
		(layer "In4.Cu")
		(net 110)
	)
	(segment
		(start 129.1875 115.7815)
		(end 129.1875 118.368376)
		(width 0.168)
		(layer "In4.Cu")
		(net 110)
	)
	(segment
		(start 127.575108 118.8275)
		(end 127.434108 118.9685)
		(width 0.168)
		(layer "In4.Cu")
		(net 110)
	)
	(segment
		(start 129.225 104.530541)
		(end 129.1875 104.568041)
		(width 0.168)
		(layer "In4.Cu")
		(net 110)
	)
	(segment
		(start 129.1875 104.568041)
		(end 129.1875 104.9725)
		(width 0.168)
		(layer "In4.Cu")
		(net 110)
	)
	(segment
		(start 128.171732 114.9045)
		(end 129.728268 114.9045)
		(width 0.168)
		(layer "In4.Cu")
		(net 110)
	)
	(segment
		(start 129.3215 113.6865)
		(end 129.728268 113.6865)
		(width 0.168)
		(layer "In4.Cu")
		(net 110)
	)
	(segment
		(start 128.1625 107.485)
		(end 128.4 107.485)
		(width 0.168)
		(layer "In4.Cu")
		(net 110)
	)
	(segment
		(start 128.728376 118.8275)
		(end 127.575108 118.8275)
		(width 0.168)
		(layer "In4.Cu")
		(net 110)
	)
	(segment
		(start 129.1875 118.368376)
		(end 128.728376 118.8275)
		(width 0.168)
		(layer "In4.Cu")
		(net 110)
	)
	(segment
		(start 128.171732 115.1725)
		(end 128.5785 115.1725)
		(width 0.168)
		(layer "In4.Cu")
		(net 110)
	)
	(arc
		(start 129.728268 113.6865)
		(mid 130.158896 113.864872)
		(end 130.337268 114.2955)
		(width 0.168)
		(layer "In4.Cu")
		(net 110)
	)
	(arc
		(start 128.171732 114.9045)
		(mid 128.07698 114.943748)
		(end 128.037732 115.0385)
		(width 0.168)
		(layer "In4.Cu")
		(net 110)
	)
	(arc
		(start 127.85 107.1725)
		(mid 127.941529 107.393471)
		(end 128.1625 107.485)
		(width 0.168)
		(layer "In4.Cu")
		(net 110)
	)
	(arc
		(start 128.037732 115.0385)
		(mid 128.07698 115.133252)
		(end 128.171732 115.1725)
		(width 0.168)
		(layer "In4.Cu")
		(net 110)
	)
	(arc
		(start 128.5785 115.1725)
		(mid 129.009128 115.350872)
		(end 129.1875 115.7815)
		(width 0.168)
		(layer "In4.Cu")
		(net 110)
	)
	(arc
		(start 130.525 106.0725)
		(mid 130.294347 106.629347)
		(end 129.7375 106.86)
		(width 0.168)
		(layer "In4.Cu")
		(net 110)
	)
	(arc
		(start 129.1875 104.9725)
		(mid 129.279029 105.193471)
		(end 129.5 105.285)
		(width 0.168)
		(layer "In4.Cu")
		(net 110)
	)
	(arc
		(start 128.1625 106.86)
		(mid 127.941529 106.951529)
		(end 127.85 107.1725)
		(width 0.168)
		(layer "In4.Cu")
		(net 110)
	)
	(arc
		(start 128.4 107.485)
		(mid 128.956847 107.715653)
		(end 129.1875 108.2725)
		(width 0.168)
		(layer "In4.Cu")
		(net 110)
	)
	(arc
		(start 130.337268 114.2955)
		(mid 130.158896 114.726128)
		(end 129.728268 114.9045)
		(width 0.168)
		(layer "In4.Cu")
		(net 110)
	)
	(arc
		(start 129.1875 113.5525)
		(mid 129.226748 113.647252)
		(end 129.3215 113.6865)
		(width 0.168)
		(layer "In4.Cu")
		(net 110)
	)
	(arc
		(start 129.7375 105.285)
		(mid 130.294347 105.515653)
		(end 130.525 106.0725)
		(width 0.168)
		(layer "In4.Cu")
		(net 110)
	)
	(segment
		(start 128.7 96.783)
		(end 128.7 95.9)
		(width 0.15)
		(layer "F.Cu")
		(net 111)
	)
	(segment
		(start 127.280609 118.364999)
		(end 127.434108 118.2115)
		(width 0.15)
		(layer "F.Cu")
		(net 111)
	)
	(segment
		(start 126.936801 118.364999)
		(end 127.280609 118.364999)
		(width 0.15)
		(layer "F.Cu")
		(net 111)
	)
	(segment
		(start 128.7 95.9)
		(end 129.1 95.5)
		(width 0.15)
		(layer "F.Cu")
		(net 111)
	)
	(segment
		(start 126.205 119.65)
		(end 126.205 119.0968)
		(width 0.15)
		(layer "F.Cu")
		(net 111)
	)
	(segment
		(start 126.205 119.0968)
		(end 126.936801 118.364999)
		(width 0.15)
		(layer "F.Cu")
		(net 111)
	)
	(segment
		(start 128.717 96.8)
		(end 128.7 96.783)
		(width 0.15)
		(layer "F.Cu")
		(net 111)
	)
	(segment
		(start 128.717 104.488541)
		(end 128.717 96.8)
		(width 0.15)
		(layer "F.Cu")
		(net 111)
	)
	(segment
		(start 128.675 104.530541)
		(end 128.717 104.488541)
		(width 0.15)
		(layer "F.Cu")
		(net 111)
	)
	(via
		(at 127.434108 118.2115)
		(size 0.45)
		(drill 0.2)
		(layers "F.Cu" "B.Cu")
		(remove_unused_layers yes)
		(keep_end_layers yes)
		(zone_layer_connections)
		(net 111)
	)
	(via
		(at 128.675 104.530541)
		(size 0.45)
		(drill 0.2)
		(layers "F.Cu" "B.Cu")
		(remove_unused_layers yes)
		(keep_end_layers yes)
		(zone_layer_connections)
		(net 111)
	)
	(segment
		(start 128.171732 114.4295)
		(end 129.728268 114.4295)
		(width 0.168)
		(layer "In4.Cu")
		(net 111)
	)
	(segment
		(start 128.1625 106.385)
		(end 129.7375 106.385)
		(width 0.168)
		(layer "In4.Cu")
		(net 111)
	)
	(segment
		(start 128.7125 115.7815)
		(end 128.7125 118.171624)
		(width 0.168)
		(layer "In4.Cu")
		(net 111)
	)
	(segment
		(start 128.7125 104.568041)
		(end 128.7125 104.9725)
		(width 0.168)
		(layer "In4.Cu")
		(net 111)
	)
	(segment
		(start 127.575108 118.3525)
		(end 127.434108 118.2115)
		(width 0.168)
		(layer "In4.Cu")
		(net 111)
	)
	(segment
		(start 129.5 105.76)
		(end 129.7375 105.76)
		(width 0.168)
		(layer "In4.Cu")
		(net 111)
	)
	(segment
		(start 128.7125 108.2725)
		(end 128.7125 113.5525)
		(width 0.168)
		(layer "In4.Cu")
		(net 111)
	)
	(segment
		(start 128.7125 118.171624)
		(end 128.531624 118.3525)
		(width 0.168)
		(layer "In4.Cu")
		(net 111)
	)
	(segment
		(start 128.531624 118.3525)
		(end 127.575108 118.3525)
		(width 0.168)
		(layer "In4.Cu")
		(net 111)
	)
	(segment
		(start 128.675 104.530541)
		(end 128.7125 104.568041)
		(width 0.168)
		(layer "In4.Cu")
		(net 111)
	)
	(segment
		(start 128.171732 115.6475)
		(end 128.5785 115.6475)
		(width 0.168)
		(layer "In4.Cu")
		(net 111)
	)
	(segment
		(start 128.1625 107.96)
		(end 128.4 107.96)
		(width 0.168)
		(layer "In4.Cu")
		(net 111)
	)
	(segment
		(start 129.3215 114.1615)
		(end 129.728268 114.1615)
		(width 0.168)
		(layer "In4.Cu")
		(net 111)
	)
	(arc
		(start 128.5785 115.6475)
		(mid 128.673252 115.686748)
		(end 128.7125 115.7815)
		(width 0.168)
		(layer "In4.Cu")
		(net 111)
	)
	(arc
		(start 127.562732 115.0385)
		(mid 127.741104 115.469128)
		(end 128.171732 115.6475)
		(width 0.168)
		(layer "In4.Cu")
		(net 111)
	)
	(arc
		(start 129.728268 114.1615)
		(mid 129.82302 114.200748)
		(end 129.862268 114.2955)
		(width 0.168)
		(layer "In4.Cu")
		(net 111)
	)
	(arc
		(start 128.7125 113.5525)
		(mid 128.890872 113.983128)
		(end 129.3215 114.1615)
		(width 0.168)
		(layer "In4.Cu")
		(net 111)
	)
	(arc
		(start 127.375 107.1725)
		(mid 127.605653 107.729347)
		(end 128.1625 107.96)
		(width 0.168)
		(layer "In4.Cu")
		(net 111)
	)
	(arc
		(start 130.05 106.0725)
		(mid 129.958471 106.293471)
		(end 129.7375 106.385)
		(width 0.168)
		(layer "In4.Cu")
		(net 111)
	)
	(arc
		(start 128.7125 104.9725)
		(mid 128.943153 105.529347)
		(end 129.5 105.76)
		(width 0.168)
		(layer "In4.Cu")
		(net 111)
	)
	(arc
		(start 128.171732 114.4295)
		(mid 127.741104 114.607872)
		(end 127.562732 115.0385)
		(width 0.168)
		(layer "In4.Cu")
		(net 111)
	)
	(arc
		(start 129.7375 105.76)
		(mid 129.958471 105.851529)
		(end 130.05 106.0725)
		(width 0.168)
		(layer "In4.Cu")
		(net 111)
	)
	(arc
		(start 128.4 107.96)
		(mid 128.620971 108.051529)
		(end 128.7125 108.2725)
		(width 0.168)
		(layer "In4.Cu")
		(net 111)
	)
	(arc
		(start 128.1625 106.385)
		(mid 127.605653 106.615653)
		(end 127.375 107.1725)
		(width 0.168)
		(layer "In4.Cu")
		(net 111)
	)
	(arc
		(start 129.862268 114.2955)
		(mid 129.82302 114.390252)
		(end 129.728268 114.4295)
		(width 0.168)
		(layer "In4.Cu")
		(net 111)
	)
	(segment
		(start 125.163 119.207999)
		(end 125.163 118.226512)
		(width 0.15)
		(layer "F.Cu")
		(net 112)
	)
	(segment
		(start 130.7 101.9)
		(end 130.515 101.715)
		(width 0.15)
		(layer "F.Cu")
		(net 112)
	)
	(segment
		(start 130.515 98.208555)
		(end 129.981426 97.674981)
		(width 0.15)
		(layer "F.Cu")
		(net 112)
	)
	(segment
		(start 125.163 118.226512)
		(end 125.610003 117.779509)
		(width 0.15)
		(layer "F.Cu")
		(net 112)
	)
	(segment
		(start 125.610003 117.779509)
		(end 125.799509 117.779509)
		(width 0.15)
		(layer "F.Cu")
		(net 112)
	)
	(segment
		(start 130.515 101.715)
		(end 130.515 98.208555)
		(width 0.15)
		(layer "F.Cu")
		(net 112)
	)
	(segment
		(start 129.981426 97.674981)
		(end 129.981426 96.48)
		(width 0.15)
		(layer "F.Cu")
		(net 112)
	)
	(segment
		(start 125.18 120.125)
		(end 125.18 119.224999)
		(width 0.15)
		(layer "F.Cu")
		(net 112)
	)
	(segment
		(start 125.18 119.224999)
		(end 125.163 119.207999)
		(width 0.15)
		(layer "F.Cu")
		(net 112)
	)
	(via
		(at 125.799509 117.779509)
		(size 0.45)
		(drill 0.2)
		(layers "F.Cu" "B.Cu")
		(remove_unused_layers yes)
		(keep_end_layers yes)
		(zone_layer_connections)
		(net 112)
	)
	(via
		(at 130.7 101.9)
		(size 0.45)
		(drill 0.2)
		(layers "F.Cu" "B.Cu")
		(remove_unused_layers yes)
		(keep_end_layers yes)
		(zone_layer_connections)
		(net 112)
	)
	(segment
		(start 129.605122 103.300758)
		(end 129.605121 103.300758)
		(width 0.168)
		(layer "In4.Cu")
		(net 112)
	)
	(segment
		(start 127.405566 111.6345)
		(end 126.9715 111.6345)
		(width 0.168)
		(layer "In4.Cu")
		(net 112)
	)
	(segment
		(start 125.794434 113.3885)
		(end 126.2285 113.3885)
		(width 0.168)
		(layer "In4.Cu")
		(net 112)
	)
	(segment
		(start 126.8375 113.9975)
		(end 126.8375 116.558376)
		(width 0.168)
		(layer "In4.Cu")
		(net 112)
	)
	(segment
		(start 126.8375 116.558376)
		(end 125.799509 117.596367)
		(width 0.168)
		(layer "In4.Cu")
		(net 112)
	)
	(segment
		(start 126.9715 110.4165)
		(end 127.405566 110.4165)
		(width 0.168)
		(layer "In4.Cu")
		(net 112)
	)
	(segment
		(start 130.382938 102.911848)
		(end 130.382937 102.911848)
		(width 0.168)
		(layer "In4.Cu")
		(net 112)
	)
	(segment
		(start 128.828376 104.0775)
		(end 128.048376 104.0775)
		(width 0.168)
		(layer "In4.Cu")
		(net 112)
	)
	(segment
		(start 130.418292 103.336113)
		(end 130.418294 103.336112)
		(width 0.168)
		(layer "In4.Cu")
		(net 112)
	)
	(segment
		(start 125.794434 113.1205)
		(end 127.405566 113.1205)
		(width 0.168)
		(layer "In4.Cu")
		(net 112)
	)
	(segment
		(start 125.799509 117.596367)
		(end 125.799509 117.779509)
		(width 0.168)
		(layer "In4.Cu")
		(net 112)
	)
	(segment
		(start 130.6375 101.9625)
		(end 130.6375 102.268376)
		(width 0.168)
		(layer "In4.Cu")
		(net 112)
	)
	(segment
		(start 126.8375 105.288376)
		(end 126.8375 110.2825)
		(width 0.168)
		(layer "In4.Cu")
		(net 112)
	)
	(segment
		(start 130.029386 103.336112)
		(end 129.994031 103.300757)
		(width 0.168)
		(layer "In4.Cu")
		(net 112)
	)
	(segment
		(start 130.7 101.9)
		(end 130.6375 101.9625)
		(width 0.168)
		(layer "In4.Cu")
		(net 112)
	)
	(segment
		(start 130.6375 102.268376)
		(end 130.382938 102.522938)
		(width 0.168)
		(layer "In4.Cu")
		(net 112)
	)
	(segment
		(start 126.9715 111.9025)
		(end 127.405566 111.9025)
		(width 0.168)
		(layer "In4.Cu")
		(net 112)
	)
	(segment
		(start 129.605121 103.300758)
		(end 128.828376 104.0775)
		(width 0.168)
		(layer "In4.Cu")
		(net 112)
	)
	(segment
		(start 130.382937 102.911848)
		(end 130.418293 102.947204)
		(width 0.168)
		(layer "In4.Cu")
		(net 112)
	)
	(segment
		(start 128.048376 104.0775)
		(end 126.8375 105.288376)
		(width 0.168)
		(layer "In4.Cu")
		(net 112)
	)
	(arc
		(start 125.660434 113.2545)
		(mid 125.699682 113.349252)
		(end 125.794434 113.3885)
		(width 0.168)
		(layer "In4.Cu")
		(net 112)
	)
	(arc
		(start 127.405566 110.4165)
		(mid 127.836194 110.594872)
		(end 128.014566 111.0255)
		(width 0.168)
		(layer "In4.Cu")
		(net 112)
	)
	(arc
		(start 130.418294 103.336112)
		(mid 130.223839 103.416658)
		(end 130.029386 103.336112)
		(width 0.168)
		(layer "In4.Cu")
		(net 112)
	)
	(arc
		(start 126.2285 113.3885)
		(mid 126.659128 113.566872)
		(end 126.8375 113.9975)
		(width 0.168)
		(layer "In4.Cu")
		(net 112)
	)
	(arc
		(start 126.8375 110.2825)
		(mid 126.876748 110.377252)
		(end 126.9715 110.4165)
		(width 0.168)
		(layer "In4.Cu")
		(net 112)
	)
	(arc
		(start 130.382938 102.522938)
		(mid 130.302391 102.717394)
		(end 130.382938 102.911848)
		(width 0.168)
		(layer "In4.Cu")
		(net 112)
	)
	(arc
		(start 127.405566 111.9025)
		(mid 127.836194 112.080872)
		(end 128.014566 112.5115)
		(width 0.168)
		(layer "In4.Cu")
		(net 112)
	)
	(arc
		(start 125.794434 113.1205)
		(mid 125.699682 113.159748)
		(end 125.660434 113.2545)
		(width 0.168)
		(layer "In4.Cu")
		(net 112)
	)
	(arc
		(start 128.014566 112.5115)
		(mid 127.836194 112.942128)
		(end 127.405566 113.1205)
		(width 0.168)
		(layer "In4.Cu")
		(net 112)
	)
	(arc
		(start 126.8375 111.7685)
		(mid 126.876748 111.863252)
		(end 126.9715 111.9025)
		(width 0.168)
		(layer "In4.Cu")
		(net 112)
	)
	(arc
		(start 130.418293 102.947204)
		(mid 130.498838 103.141659)
		(end 130.418292 103.336113)
		(width 0.168)
		(layer "In4.Cu")
		(net 112)
	)
	(arc
		(start 129.994031 103.300757)
		(mid 129.799576 103.220212)
		(end 129.605122 103.300758)
		(width 0.168)
		(layer "In4.Cu")
		(net 112)
	)
	(arc
		(start 128.014566 111.0255)
		(mid 127.836194 111.456128)
		(end 127.405566 111.6345)
		(width 0.168)
		(layer "In4.Cu")
		(net 112)
	)
	(arc
		(start 126.9715 111.6345)
		(mid 126.876748 111.673748)
		(end 126.8375 111.7685)
		(width 0.168)
		(layer "In4.Cu")
		(net 112)
	)
	(segment
		(start 130.1 101.9)
		(end 130.06 101.86)
		(width 0.15)
		(layer "F.Cu")
		(net 113)
	)
	(segment
		(start 129.6 95.8)
		(end 129.6 96.034314)
		(width 0.15)
		(layer "F.Cu")
		(net 113)
	)
	(segment
		(start 129.5 96.134314)
		(end 129.5 96.465686)
		(width 0.15)
		(layer "F.Cu")
		(net 113)
	)
	(segment
		(start 129.9 95.5)
		(end 129.6 95.8)
		(width 0.15)
		(layer "F.Cu")
		(net 113)
	)
	(segment
		(start 124.68 120.125)
		(end 124.68 119.224999)
		(width 0.15)
		(layer "F.Cu")
		(net 113)
	)
	(segment
		(start 124.697 119.207999)
		(end 124.697 118.033488)
		(width 0.15)
		(layer "F.Cu")
		(net 113)
	)
	(segment
		(start 124.697 118.033488)
		(end 125.280491 117.449997)
		(width 0.15)
		(layer "F.Cu")
		(net 113)
	)
	(segment
		(start 130.06 101.86)
		(end 130.06 98.37)
		(width 0.15)
		(layer "F.Cu")
		(net 113)
	)
	(segment
		(start 129.6 96.034314)
		(end 129.5 96.134314)
		(width 0.15)
		(layer "F.Cu")
		(net 113)
	)
	(segment
		(start 129.515426 97.825426)
		(end 129.515426 96.48)
		(width 0.15)
		(layer "F.Cu")
		(net 113)
	)
	(segment
		(start 125.280491 117.449997)
		(end 125.280491 117.260491)
		(width 0.15)
		(layer "F.Cu")
		(net 113)
	)
	(segment
		(start 130.06 98.37)
		(end 129.515426 97.825426)
		(width 0.15)
		(layer "F.Cu")
		(net 113)
	)
	(segment
		(start 124.68 119.224999)
		(end 124.697 119.207999)
		(width 0.15)
		(layer "F.Cu")
		(net 113)
	)
	(via
		(at 125.280491 117.260491)
		(size 0.45)
		(drill 0.2)
		(layers "F.Cu" "B.Cu")
		(remove_unused_layers yes)
		(keep_end_layers yes)
		(zone_layer_connections)
		(net 113)
	)
	(via
		(at 130.1 101.9)
		(size 0.45)
		(drill 0.2)
		(layers "F.Cu" "B.Cu")
		(remove_unused_layers yes)
		(keep_end_layers yes)
		(zone_layer_connections)
		(net 113)
	)
	(segment
		(start 128.631624 103.6025)
		(end 127.851624 103.6025)
		(width 0.168)
		(layer "In4.Cu")
		(net 113)
	)
	(segment
		(start 125.463633 117.260491)
		(end 125.280491 117.260491)
		(width 0.168)
		(layer "In4.Cu")
		(net 113)
	)
	(segment
		(start 125.794434 113.8635)
		(end 126.2285 113.8635)
		(width 0.168)
		(layer "In4.Cu")
		(net 113)
	)
	(segment
		(start 125.794434 112.6455)
		(end 127.405566 112.6455)
		(width 0.168)
		(layer "In4.Cu")
		(net 113)
	)
	(segment
		(start 127.405566 111.1595)
		(end 126.9715 111.1595)
		(width 0.168)
		(layer "In4.Cu")
		(net 113)
	)
	(segment
		(start 126.9715 112.3775)
		(end 127.405566 112.3775)
		(width 0.168)
		(layer "In4.Cu")
		(net 113)
	)
	(segment
		(start 126.3625 113.9975)
		(end 126.3625 116.361624)
		(width 0.168)
		(layer "In4.Cu")
		(net 113)
	)
	(segment
		(start 126.3625 116.361624)
		(end 125.463633 117.260491)
		(width 0.168)
		(layer "In4.Cu")
		(net 113)
	)
	(segment
		(start 126.9715 110.8915)
		(end 127.405566 110.8915)
		(width 0.168)
		(layer "In4.Cu")
		(net 113)
	)
	(segment
		(start 130.1625 101.9625)
		(end 130.1625 102.071624)
		(width 0.168)
		(layer "In4.Cu")
		(net 113)
	)
	(segment
		(start 127.851624 103.6025)
		(end 126.3625 105.091624)
		(width 0.168)
		(layer "In4.Cu")
		(net 113)
	)
	(segment
		(start 126.3625 105.091624)
		(end 126.3625 110.2825)
		(width 0.168)
		(layer "In4.Cu")
		(net 113)
	)
	(segment
		(start 130.1 101.9)
		(end 130.1625 101.9625)
		(width 0.168)
		(layer "In4.Cu")
		(net 113)
	)
	(segment
		(start 130.1625 102.071624)
		(end 128.631624 103.6025)
		(width 0.168)
		(layer "In4.Cu")
		(net 113)
	)
	(arc
		(start 126.2285 113.8635)
		(mid 126.323252 113.902748)
		(end 126.3625 113.9975)
		(width 0.168)
		(layer "In4.Cu")
		(net 113)
	)
	(arc
		(start 127.539566 111.0255)
		(mid 127.500318 111.120252)
		(end 127.405566 111.1595)
		(width 0.168)
		(layer "In4.Cu")
		(net 113)
	)
	(arc
		(start 127.405566 110.8915)
		(mid 127.500318 110.930748)
		(end 127.539566 111.0255)
		(width 0.168)
		(layer "In4.Cu")
		(net 113)
	)
	(arc
		(start 125.185434 113.2545)
		(mid 125.363806 113.685128)
		(end 125.794434 113.8635)
		(width 0.168)
		(layer "In4.Cu")
		(net 113)
	)
	(arc
		(start 125.794434 112.6455)
		(mid 125.363806 112.823872)
		(end 125.185434 113.2545)
		(width 0.168)
		(layer "In4.Cu")
		(net 113)
	)
	(arc
		(start 126.9715 111.1595)
		(mid 126.540872 111.337872)
		(end 126.3625 111.7685)
		(width 0.168)
		(layer "In4.Cu")
		(net 113)
	)
	(arc
		(start 127.405566 112.3775)
		(mid 127.500318 112.416748)
		(end 127.539566 112.5115)
		(width 0.168)
		(layer "In4.Cu")
		(net 113)
	)
	(arc
		(start 126.3625 110.2825)
		(mid 126.540872 110.713128)
		(end 126.9715 110.8915)
		(width 0.168)
		(layer "In4.Cu")
		(net 113)
	)
	(arc
		(start 127.539566 112.5115)
		(mid 127.500318 112.606252)
		(end 127.405566 112.6455)
		(width 0.168)
		(layer "In4.Cu")
		(net 113)
	)
	(arc
		(start 126.3625 111.7685)
		(mid 126.540872 112.199128)
		(end 126.9715 112.3775)
		(width 0.168)
		(layer "In4.Cu")
		(net 113)
	)
	(segment
		(start 124.163 117.602529)
		(end 124.297 117.468529)
		(width 0.15)
		(layer "F.Cu")
		(net 114)
	)
	(segment
		(start 128.3 96.534)
		(end 128.316 96.55)
		(width 0.15)
		(layer "F.Cu")
		(net 114)
	)
	(segment
		(start 128.3 96.3)
		(end 128.3 96.534)
		(width 0.15)
		(layer "F.Cu")
		(net 114)
	)
	(segment
		(start 124.18 119.224999)
		(end 124.163 119.207999)
		(width 0.15)
		(layer "F.Cu")
		(net 114)
	)
	(segment
		(start 124.163 119.207999)
		(end 124.163 117.602529)
		(width 0.15)
		(layer "F.Cu")
		(net 114)
	)
	(segment
		(start 127.066 102.253613)
		(end 127.066 99.643614)
		(width 0.15)
		(layer "F.Cu")
		(net 114)
	)
	(segment
		(start 128.316 98.393614)
		(end 128.316 96.55)
		(width 0.15)
		(layer "F.Cu")
		(net 114)
	)
	(segment
		(start 127.066 99.643614)
		(end 128.316 98.393614)
		(width 0.15)
		(layer "F.Cu")
		(net 114)
	)
	(segment
		(start 125.564455 103.755158)
		(end 127.066 102.253613)
		(width 0.15)
		(layer "F.Cu")
		(net 114)
	)
	(segment
		(start 124.18 120.125)
		(end 124.18 119.224999)
		(width 0.15)
		(layer "F.Cu")
		(net 114)
	)
	(via
		(at 125.61 103.79)
		(size 0.45)
		(drill 0.2)
		(layers "F.Cu" "B.Cu")
		(remove_unused_layers yes)
		(keep_end_layers yes)
		(zone_layer_connections)
		(net 114)
	)
	(via
		(at 124.297 117.468529)
		(size 0.45)
		(drill 0.2)
		(layers "F.Cu" "B.Cu")
		(remove_unused_layers yes)
		(keep_end_layers yes)
		(zone_layer_connections)
		(net 114)
	)
	(segment
		(start 124.1675 115.016015)
		(end 124.164 115.012515)
		(width 0.168)
		(layer "In4.Cu")
		(net 114)
	)
	(segment
		(start 124.6675 107.325)
		(end 124.43 107.325)
		(width 0.168)
		(layer "In4.Cu")
		(net 114)
	)
	(segment
		(start 122.93 112.0625)
		(end 122.93 111.8125)
		(width 0.168)
		(layer "In4.Cu")
		(net 114)
	)
	(segment
		(start 124.1675 117.339029)
		(end 124.1675 115.016015)
		(width 0.168)
		(layer "In4.Cu")
		(net 114)
	)
	(segment
		(start 123.1925 109.825)
		(end 124.6675 109.825)
		(width 0.168)
		(layer "In4.Cu")
		(net 114)
	)
	(segment
		(start 123.43 112.325)
		(end 123.1925 112.325)
		(width 0.168)
		(layer "In4.Cu")
		(net 114)
	)
	(segment
		(start 125.148527 104.17147)
		(end 125.148528 104.171471)
		(width 0.168)
		(layer "In4.Cu")
		(net 114)
	)
	(segment
		(start 125.219238 104.666444)
		(end 125.219238 104.666445)
		(width 0.168)
		(layer "In4.Cu")
		(net 114)
	)
	(segment
		(start 125.148528 104.171471)
		(end 125.53 103.79)
		(width 0.168)
		(layer "In4.Cu")
		(net 114)
	)
	(segment
		(start 123.1925 109.05)
		(end 124.6675 109.05)
		(width 0.168)
		(layer "In4.Cu")
		(net 114)
	)
	(segment
		(start 124.724264 105.02)
		(end 124.794974 105.09071)
		(width 0.168)
		(layer "In4.Cu")
		(net 114)
	)
	(segment
		(start 122.93 109.5625)
		(end 122.93 109.3125)
		(width 0.168)
		(layer "In4.Cu")
		(net 114)
	)
	(segment
		(start 123.1925 111.55)
		(end 124.6675 111.55)
		(width 0.168)
		(layer "In4.Cu")
		(net 114)
	)
	(segment
		(start 125.219238 104.666445)
		(end 125.148527 104.595734)
		(width 0.168)
		(layer "In4.Cu")
		(net 114)
	)
	(segment
		(start 124.1675 115.009015)
		(end 124.1675 113.0625)
		(width 0.168)
		(layer "In4.Cu")
		(net 114)
	)
	(segment
		(start 124.297 117.468529)
		(end 124.1675 117.339029)
		(width 0.168)
		(layer "In4.Cu")
		(net 114)
	)
	(segment
		(start 124.1675 105.1525)
		(end 124.3 105.02)
		(width 0.168)
		(layer "In4.Cu")
		(net 114)
	)
	(segment
		(start 124.164 115.012515)
		(end 124.1675 115.009015)
		(width 0.168)
		(layer "In4.Cu")
		(net 114)
	)
	(segment
		(start 125.405 110.8125)
		(end 125.405 110.5625)
		(width 0.168)
		(layer "In4.Cu")
		(net 114)
	)
	(segment
		(start 125.405 108.3125)
		(end 125.405 108.0625)
		(width 0.168)
		(layer "In4.Cu")
		(net 114)
	)
	(segment
		(start 125.53 103.79)
		(end 125.61 103.79)
		(width 0.168)
		(layer "In4.Cu")
		(net 114)
	)
	(segment
		(start 124.1675 107.0625)
		(end 124.1675 105.1525)
		(width 0.168)
		(layer "In4.Cu")
		(net 114)
	)
	(arc
		(start 124.794974 105.09071)
		(mid 125.007106 105.178578)
		(end 125.219238 105.09071)
		(width 0.168)
		(layer "In4.Cu")
		(net 114)
	)
	(arc
		(start 124.6675 111.55)
		(mid 125.188991 111.333991)
		(end 125.405 110.8125)
		(width 0.168)
		(layer "In4.Cu")
		(net 114)
	)
	(arc
		(start 125.148527 104.595734)
		(mid 125.060659 104.383602)
		(end 125.148527 104.17147)
		(width 0.168)
		(layer "In4.Cu")
		(net 114)
	)
	(arc
		(start 122.93 111.8125)
		(mid 123.006884 111.626884)
		(end 123.1925 111.55)
		(width 0.168)
		(layer "In4.Cu")
		(net 114)
	)
	(arc
		(start 123.1925 109.825)
		(mid 123.006884 109.748116)
		(end 122.93 109.5625)
		(width 0.168)
		(layer "In4.Cu")
		(net 114)
	)
	(arc
		(start 122.93 109.3125)
		(mid 123.006884 109.126884)
		(end 123.1925 109.05)
		(width 0.168)
		(layer "In4.Cu")
		(net 114)
	)
	(arc
		(start 125.405 110.5625)
		(mid 125.188991 110.041009)
		(end 124.6675 109.825)
		(width 0.168)
		(layer "In4.Cu")
		(net 114)
	)
	(arc
		(start 124.1675 113.0625)
		(mid 123.951491 112.541009)
		(end 123.43 112.325)
		(width 0.168)
		(layer "In4.Cu")
		(net 114)
	)
	(arc
		(start 124.3 105.02)
		(mid 124.512132 104.932132)
		(end 124.724264 105.02)
		(width 0.168)
		(layer "In4.Cu")
		(net 114)
	)
	(arc
		(start 125.405 108.0625)
		(mid 125.188991 107.541009)
		(end 124.6675 107.325)
		(width 0.168)
		(layer "In4.Cu")
		(net 114)
	)
	(arc
		(start 123.1925 112.325)
		(mid 123.006884 112.248116)
		(end 122.93 112.0625)
		(width 0.168)
		(layer "In4.Cu")
		(net 114)
	)
	(arc
		(start 124.6675 109.05)
		(mid 125.188991 108.833991)
		(end 125.405 108.3125)
		(width 0.168)
		(layer "In4.Cu")
		(net 114)
	)
	(arc
		(start 125.219238 105.09071)
		(mid 125.307106 104.878577)
		(end 125.219238 104.666444)
		(width 0.168)
		(layer "In4.Cu")
		(net 114)
	)
	(arc
		(start 124.43 107.325)
		(mid 124.244384 107.248116)
		(end 124.1675 107.0625)
		(width 0.168)
		(layer "In4.Cu")
		(net 114)
	)
	(segment
		(start 125.244842 103.435545)
		(end 125.178324 103.435545)
		(width 0.15)
		(layer "F.Cu")
		(net 115)
	)
	(segment
		(start 127.9 95.9)
		(end 128.3 95.5)
		(width 0.15)
		(layer "F.Cu")
		(net 115)
	)
	(segment
		(start 123.68 119.224999)
		(end 123.697 119.207999)
		(width 0.15)
		(layer "F.Cu")
		(net 115)
	)
	(segment
		(start 127.9 96.525451)
		(end 127.9 95.9)
		(width 0.15)
		(layer "F.Cu")
		(net 115)
	)
	(segment
		(start 123.68 120.125)
		(end 123.68 119.224999)
		(width 0.15)
		(layer "F.Cu")
		(net 115)
	)
	(segment
		(start 125.178324 103.435545)
		(end 125.148579 103.46529)
		(width 0.15)
		(layer "F.Cu")
		(net 115)
	)
	(segment
		(start 126.614 99.456386)
		(end 127.864 98.206386)
		(width 0.15)
		(layer "F.Cu")
		(net 115)
	)
	(segment
		(start 127.864 98.206386)
		(end 127.864 96.55)
		(width 0.15)
		(layer "F.Cu")
		(net 115)
	)
	(segment
		(start 123.697 117.602529)
		(end 123.563 117.468529)
		(width 0.15)
		(layer "F.Cu")
		(net 115)
	)
	(segment
		(start 123.697 119.207999)
		(end 123.697 117.602529)
		(width 0.15)
		(layer "F.Cu")
		(net 115)
	)
	(segment
		(start 126.614 102.066387)
		(end 126.614 99.456386)
		(width 0.15)
		(layer "F.Cu")
		(net 115)
	)
	(segment
		(start 127.9 96.525451)
		(end 127.888549 96.525451)
		(width 0.15)
		(layer "F.Cu")
		(net 115)
	)
	(segment
		(start 125.244842 103.435545)
		(end 126.614 102.066387)
		(width 0.15)
		(layer "F.Cu")
		(net 115)
	)
	(segment
		(start 127.888549 96.525451)
		(end 127.864 96.55)
		(width 0.15)
		(layer "F.Cu")
		(net 115)
	)
	(via
		(at 125.148579 103.46529)
		(size 0.45)
		(drill 0.2)
		(layers "F.Cu" "B.Cu")
		(remove_unused_layers yes)
		(keep_end_layers yes)
		(zone_layer_connections)
		(net 115)
	)
	(via
		(at 123.563 117.468529)
		(size 0.45)
		(drill 0.2)
		(layers "F.Cu" "B.Cu")
		(remove_unused_layers yes)
		(keep_end_layers yes)
		(zone_layer_connections)
		(net 115)
	)
	(segment
		(start 122.455 111.8125)
		(end 122.455 112.0625)
		(width 0.168)
		(layer "In4.Cu")
		(net 115)
	)
	(segment
		(start 124.93 108.0625)
		(end 124.93 108.3125)
		(width 0.168)
		(layer "In4.Cu")
		(net 115)
	)
	(segment
		(start 123.6925 117.339029)
		(end 123.563 117.468529)
		(width 0.168)
		(layer "In4.Cu")
		(net 115)
	)
	(segment
		(start 123.1925 108.575)
		(end 124.6675 108.575)
		(width 0.168)
		(layer "In4.Cu")
		(net 115)
	)
	(segment
		(start 124.43 107.8)
		(end 124.6675 107.8)
		(width 0.168)
		(layer "In4.Cu")
		(net 115)
	)
	(segment
		(start 123.6925 115.009015)
		(end 123.696 115.012515)
		(width 0.168)
		(layer "In4.Cu")
		(net 115)
	)
	(segment
		(start 123.1925 110.3)
		(end 124.6675 110.3)
		(width 0.168)
		(layer "In4.Cu")
		(net 115)
	)
	(segment
		(start 123.1925 111.075)
		(end 124.6675 111.075)
		(width 0.168)
		(layer "In4.Cu")
		(net 115)
	)
	(segment
		(start 123.1925 112.8)
		(end 123.43 112.8)
		(width 0.168)
		(layer "In4.Cu")
		(net 115)
	)
	(segment
		(start 122.455 109.3125)
		(end 122.455 109.5625)
		(width 0.168)
		(layer "In4.Cu")
		(net 115)
	)
	(segment
		(start 123.6925 115.016015)
		(end 123.6925 117.339029)
		(width 0.168)
		(layer "In4.Cu")
		(net 115)
	)
	(segment
		(start 124.93 110.5625)
		(end 124.93 110.8125)
		(width 0.168)
		(layer "In4.Cu")
		(net 115)
	)
	(segment
		(start 123.6925 104.971624)
		(end 123.6925 107.0625)
		(width 0.168)
		(layer "In4.Cu")
		(net 115)
	)
	(segment
		(start 125.175545 103.488579)
		(end 123.6925 104.971624)
		(width 0.168)
		(layer "In4.Cu")
		(net 115)
	)
	(segment
		(start 123.6925 113.0625)
		(end 123.6925 115.009015)
		(width 0.168)
		(layer "In4.Cu")
		(net 115)
	)
	(segment
		(start 123.696 115.012515)
		(end 123.6925 115.016015)
		(width 0.168)
		(layer "In4.Cu")
		(net 115)
	)
	(arc
		(start 123.6925 107.0625)
		(mid 123.908509 107.583991)
		(end 124.43 107.8)
		(width 0.168)
		(layer "In4.Cu")
		(net 115)
	)
	(arc
		(start 122.455 112.0625)
		(mid 122.671009 112.583991)
		(end 123.1925 112.8)
		(width 0.168)
		(layer "In4.Cu")
		(net 115)
	)
	(arc
		(start 124.93 108.3125)
		(mid 124.853116 108.498116)
		(end 124.6675 108.575)
		(width 0.168)
		(layer "In4.Cu")
		(net 115)
	)
	(arc
		(start 124.6675 110.3)
		(mid 124.853116 110.376884)
		(end 124.93 110.5625)
		(width 0.168)
		(layer "In4.Cu")
		(net 115)
	)
	(arc
		(start 123.1925 108.575)
		(mid 122.671009 108.791009)
		(end 122.455 109.3125)
		(width 0.168)
		(layer "In4.Cu")
		(net 115)
	)
	(arc
		(start 123.43 112.8)
		(mid 123.615616 112.876884)
		(end 123.6925 113.0625)
		(width 0.168)
		(layer "In4.Cu")
		(net 115)
	)
	(arc
		(start 122.455 109.5625)
		(mid 122.671009 110.083991)
		(end 123.1925 110.3)
		(width 0.168)
		(layer "In4.Cu")
		(net 115)
	)
	(arc
		(start 123.1925 111.075)
		(mid 122.671009 111.291009)
		(end 122.455 111.8125)
		(width 0.168)
		(layer "In4.Cu")
		(net 115)
	)
	(arc
		(start 124.6675 107.8)
		(mid 124.853116 107.876884)
		(end 124.93 108.0625)
		(width 0.168)
		(layer "In4.Cu")
		(net 115)
	)
	(arc
		(start 124.93 110.8125)
		(mid 124.853116 110.998116)
		(end 124.6675 111.075)
		(width 0.168)
		(layer "In4.Cu")
		(net 115)
	)
	(segment
		(start 123.18 119.224999)
		(end 123.163 119.207999)
		(width 0.15)
		(layer "F.Cu")
		(net 116)
	)
	(segment
		(start 122.889509 117.499997)
		(end 122.889509 117.310491)
		(width 0.15)
		(layer "F.Cu")
		(net 116)
	)
	(segment
		(start 132.133 98.933)
		(end 132.133 98.523488)
		(width 0.15)
		(layer "F.Cu")
		(net 116)
	)
	(segment
		(start 130.788756 97.179244)
		(end 130.788756 96.519478)
		(width 0.15)
		(layer "F.Cu")
		(net 116)
	)
	(segment
		(start 123.163 117.773488)
		(end 122.889509 117.499997)
		(width 0.15)
		(layer "F.Cu")
		(net 116)
	)
	(segment
		(start 123.18 120.125)
		(end 123.18 119.224999)
		(width 0.15)
		(layer "F.Cu")
		(net 116)
	)
	(segment
		(start 123.163 119.207999)
		(end 123.163 117.773488)
		(width 0.15)
		(layer "F.Cu")
		(net 116)
	)
	(segment
		(start 132.133 98.523488)
		(end 130.788756 97.179244)
		(width 0.15)
		(layer "F.Cu")
		(net 116)
	)
	(segment
		(start 132.2 99)
		(end 132.133 98.933)
		(width 0.15)
		(layer "F.Cu")
		(net 116)
	)
	(via
		(at 122.889509 117.310491)
		(size 0.45)
		(drill 0.2)
		(layers "F.Cu" "B.Cu")
		(remove_unused_layers yes)
		(keep_end_layers yes)
		(zone_layer_connections)
		(net 116)
	)
	(via
		(at 132.2 99)
		(size 0.45)
		(drill 0.2)
		(layers "F.Cu" "B.Cu")
		(remove_unused_layers yes)
		(keep_end_layers yes)
		(zone_layer_connections)
		(net 116)
	)
	(segment
		(start 130.444 100.484)
		(end 130.444 100.434)
		(width 0.168)
		(layer "In4.Cu")
		(net 116)
	)
	(segment
		(start 130.144 100.184)
		(end 129.896 100.184)
		(width 0.168)
		(layer "In4.Cu")
		(net 116)
	)
	(segment
		(start 131.526075 100.184)
		(end 131.194 100.184)
		(width 0.168)
		(layer "In4.Cu")
		(net 116)
	)
	(segment
		(start 130.194 100.184)
		(end 130.144 100.184)
		(width 0.168)
		(layer "In4.Cu")
		(net 116)
	)
	(segment
		(start 129.896 100.184)
		(end 127.4425 102.6375)
		(width 0.168)
		(layer "In4.Cu")
		(net 116)
	)
	(segment
		(start 127.4425 102.6375)
		(end 123.698376 102.6375)
		(width 0.168)
		(layer "In4.Cu")
		(net 116)
	)
	(segment
		(start 122.706367 117.310491)
		(end 122.889509 117.310491)
		(width 0.168)
		(layer "In4.Cu")
		(net 116)
	)
	(segment
		(start 121.5775 116.181624)
		(end 122.706367 117.310491)
		(width 0.168)
		(layer "In4.Cu")
		(net 116)
	)
	(segment
		(start 132.134 99.066)
		(end 132.134 99.576075)
		(width 0.168)
		(layer "In4.Cu")
		(net 116)
	)
	(segment
		(start 123.698376 102.6375)
		(end 121.5775 104.758376)
		(width 0.168)
		(layer "In4.Cu")
		(net 116)
	)
	(segment
		(start 132.2 99)
		(end 132.134 99.066)
		(width 0.168)
		(layer "In4.Cu")
		(net 116)
	)
	(segment
		(start 132.134 99.576075)
		(end 131.526075 100.184)
		(width 0.168)
		(layer "In4.Cu")
		(net 116)
	)
	(segment
		(start 121.5775 104.758376)
		(end 121.5775 116.181624)
		(width 0.168)
		(layer "In4.Cu")
		(net 116)
	)
	(segment
		(start 130.944 100.434)
		(end 130.944 100.484)
		(width 0.168)
		(layer "In4.Cu")
		(net 116)
	)
	(arc
		(start 130.444 100.434)
		(mid 130.370777 100.257223)
		(end 130.194 100.184)
		(width 0.168)
		(layer "In4.Cu")
		(net 116)
	)
	(arc
		(start 130.694 100.734)
		(mid 130.517223 100.660777)
		(end 130.444 100.484)
		(width 0.168)
		(layer "In4.Cu")
		(net 116)
	)
	(arc
		(start 130.944 100.484)
		(mid 130.870777 100.660777)
		(end 130.694 100.734)
		(width 0.168)
		(layer "In4.Cu")
		(net 116)
	)
	(arc
		(start 131.194 100.184)
		(mid 131.017223 100.257223)
		(end 130.944 100.434)
		(width 0.168)
		(layer "In4.Cu")
		(net 116)
	)
	(segment
		(start 131.667 98.933)
		(end 131.667 98.716512)
		(width 0.15)
		(layer "F.Cu")
		(net 117)
	)
	(segment
		(start 131.667 98.716512)
		(end 130.322756 97.372268)
		(width 0.15)
		(layer "F.Cu")
		(net 117)
	)
	(segment
		(start 131.6 99)
		(end 131.667 98.933)
		(width 0.15)
		(layer "F.Cu")
		(net 117)
	)
	(segment
		(start 130.7 95.5)
		(end 130.3 95.9)
		(width 0.15)
		(layer "F.Cu")
		(net 117)
	)
	(segment
		(start 122.559997 117.829509)
		(end 122.370491 117.829509)
		(width 0.15)
		(layer "F.Cu")
		(net 117)
	)
	(segment
		(start 122.68 120.125)
		(end 122.68 119.224999)
		(width 0.15)
		(layer "F.Cu")
		(net 117)
	)
	(segment
		(start 122.68 119.224999)
		(end 122.697 119.207999)
		(width 0.15)
		(layer "F.Cu")
		(net 117)
	)
	(segment
		(start 130.3 95.9)
		(end 130.3 96.51)
		(width 0.15)
		(layer "F.Cu")
		(net 117)
	)
	(segment
		(start 130.322756 97.372268)
		(end 130.322756 96.519478)
		(width 0.15)
		(layer "F.Cu")
		(net 117)
	)
	(segment
		(start 122.697 117.966512)
		(end 122.559997 117.829509)
		(width 0.15)
		(layer "F.Cu")
		(net 117)
	)
	(segment
		(start 122.697 119.207999)
		(end 122.697 117.966512)
		(width 0.15)
		(layer "F.Cu")
		(net 117)
	)
	(via
		(at 122.370491 117.829509)
		(size 0.45)
		(drill 0.2)
		(layers "F.Cu" "B.Cu")
		(remove_unused_layers yes)
		(keep_end_layers yes)
		(zone_layer_connections)
		(net 117)
	)
	(via
		(at 131.6 99)
		(size 0.45)
		(drill 0.2)
		(layers "F.Cu" "B.Cu")
		(remove_unused_layers yes)
		(keep_end_layers yes)
		(zone_layer_connections)
		(net 117)
	)
	(segment
		(start 129.694 99.716)
		(end 131.332223 99.716)
		(width 0.168)
		(layer "In4.Cu")
		(net 117)
	)
	(segment
		(start 131.666 99.066)
		(end 131.6 99)
		(width 0.168)
		(layer "In4.Cu")
		(net 117)
	)
	(segment
		(start 131.332223 99.716)
		(end 131.666 99.382223)
		(width 0.168)
		(layer "In4.Cu")
		(net 117)
	)
	(segment
		(start 121.1025 116.378376)
		(end 121.1025 104.561624)
		(width 0.168)
		(layer "In4.Cu")
		(net 117)
	)
	(segment
		(start 121.1025 104.561624)
		(end 123.501624 102.1625)
		(width 0.168)
		(layer "In4.Cu")
		(net 117)
	)
	(segment
		(start 122.370491 117.646367)
		(end 121.1025 116.378376)
		(width 0.168)
		(layer "In4.Cu")
		(net 117)
	)
	(segment
		(start 131.666 99.382223)
		(end 131.666 99.066)
		(width 0.168)
		(layer "In4.Cu")
		(net 117)
	)
	(segment
		(start 123.501624 102.1625)
		(end 127.2475 102.1625)
		(width 0.168)
		(layer "In4.Cu")
		(net 117)
	)
	(segment
		(start 127.2475 102.1625)
		(end 129.694 99.716)
		(width 0.168)
		(layer "In4.Cu")
		(net 117)
	)
	(segment
		(start 122.370491 117.829509)
		(end 122.370491 117.646367)
		(width 0.168)
		(layer "In4.Cu")
		(net 117)
	)
	(segment
		(start 127.559872 97.798328)
		(end 126.093 99.2652)
		(width 0.15)
		(layer "F.Cu")
		(net 118)
	)
	(segment
		(start 127.56 96.36)
		(end 127.56 96.59)
		(width 0.15)
		(layer "F.Cu")
		(net 118)
	)
	(segment
		(start 122.163 118.783488)
		(end 121.849509 118.469997)
		(width 0.15)
		(layer "F.Cu")
		(net 118)
	)
	(segment
		(start 126.093 99.2652)
		(end 126.093 100.806512)
		(width 0.15)
		(layer "F.Cu")
		(net 118)
	)
	(segment
		(start 122.163 119.207999)
		(end 122.163 118.783488)
		(width 0.15)
		(layer "F.Cu")
		(net 118)
	)
	(segment
		(start 127.559872 96.590128)
		(end 127.559872 97.798328)
		(width 0.15)
		(layer "F.Cu")
		(net 118)
	)
	(segment
		(start 126.093 100.806512)
		(end 125.744455 101.155057)
		(width 0.15)
		(layer "F.Cu")
		(net 118)
	)
	(segment
		(start 122.18 120.125)
		(end 122.18 119.224999)
		(width 0.15)
		(layer "F.Cu")
		(net 118)
	)
	(segment
		(start 125.744455 101.155057)
		(end 125.744455 101.214455)
		(width 0.15)
		(layer "F.Cu")
		(net 118)
	)
	(segment
		(start 127.56 96.59)
		(end 127.559872 96.590128)
		(width 0.15)
		(layer "F.Cu")
		(net 118)
	)
	(segment
		(start 121.849509 118.469997)
		(end 121.849509 118.280491)
		(width 0.15)
		(layer "F.Cu")
		(net 118)
	)
	(segment
		(start 122.18 119.224999)
		(end 122.163 119.207999)
		(width 0.15)
		(layer "F.Cu")
		(net 118)
	)
	(via
		(at 125.744455 101.214455)
		(size 0.45)
		(drill 0.2)
		(layers "F.Cu" "B.Cu")
		(remove_unused_layers yes)
		(keep_end_layers yes)
		(zone_layer_connections)
		(net 118)
	)
	(via
		(at 121.849509 118.280491)
		(size 0.45)
		(drill 0.2)
		(layers "F.Cu" "B.Cu")
		(remove_unused_layers yes)
		(keep_end_layers yes)
		(zone_layer_connections)
		(net 118)
	)
	(segment
		(start 119.4375 117.376574)
		(end 119.693426 117.6325)
		(width 0.168)
		(layer "In4.Cu")
		(net 118)
	)
	(segment
		(start 122.2875 101.8375)
		(end 122.2875 101.9875)
		(width 0.168)
		(layer "In4.Cu")
		(net 118)
	)
	(segment
		(start 121.018376 117.6325)
		(end 121.666367 118.280491)
		(width 0.168)
		(layer "In4.Cu")
		(net 118)
	)
	(segment
		(start 125.363426 101.5375)
		(end 122.5875 101.5375)
		(width 0.168)
		(layer "In4.Cu")
		(net 118)
	)
	(segment
		(start 121.3375 101.5375)
		(end 119.998376 101.5375)
		(width 0.168)
		(layer "In4.Cu")
		(net 118)
	)
	(segment
		(start 121.6875 101.9875)
		(end 121.6875 101.8375)
		(width 0.168)
		(layer "In4.Cu")
		(net 118)
	)
	(segment
		(start 125.686471 101.214455)
		(end 125.363426 101.5375)
		(width 0.168)
		(layer "In4.Cu")
		(net 118)
	)
	(segment
		(start 125.744455 101.214455)
		(end 125.686471 101.214455)
		(width 0.168)
		(layer "In4.Cu")
		(net 118)
	)
	(segment
		(start 125.691421 101.214455)
		(end 125.744455 101.214455)
		(width 0.168)
		(layer "In4.Cu")
		(net 118)
	)
	(segment
		(start 119.693426 117.6325)
		(end 121.018376 117.6325)
		(width 0.168)
		(layer "In4.Cu")
		(net 118)
	)
	(segment
		(start 119.998376 101.5375)
		(end 119.4375 102.098376)
		(width 0.168)
		(layer "In4.Cu")
		(net 118)
	)
	(segment
		(start 121.3875 101.5375)
		(end 121.3375 101.5375)
		(width 0.168)
		(layer "In4.Cu")
		(net 118)
	)
	(segment
		(start 121.666367 118.280491)
		(end 121.849509 118.280491)
		(width 0.168)
		(layer "In4.Cu")
		(net 118)
	)
	(segment
		(start 119.4375 102.098376)
		(end 119.4375 117.376574)
		(width 0.168)
		(layer "In4.Cu")
		(net 118)
	)
	(arc
		(start 122.2875 101.9875)
		(mid 122.199632 102.199632)
		(end 121.9875 102.2875)
		(width 0.168)
		(layer "In4.Cu")
		(net 118)
	)
	(arc
		(start 122.5875 101.5375)
		(mid 122.375368 101.625368)
		(end 122.2875 101.8375)
		(width 0.168)
		(layer "In4.Cu")
		(net 118)
	)
	(arc
		(start 121.6875 101.8375)
		(mid 121.599632 101.625368)
		(end 121.3875 101.5375)
		(width 0.168)
		(layer "In4.Cu")
		(net 118)
	)
	(arc
		(start 121.9875 102.2875)
		(mid 121.775368 102.199632)
		(end 121.6875 101.9875)
		(width 0.168)
		(layer "In4.Cu")
		(net 118)
	)
	(segment
		(start 125.414943 100.825545)
		(end 125.355545 100.825545)
		(width 0.15)
		(layer "F.Cu")
		(net 119)
	)
	(segment
		(start 121.68 119.224999)
		(end 121.697 119.207999)
		(width 0.15)
		(layer "F.Cu")
		(net 119)
	)
	(segment
		(start 121.697 119.207999)
		(end 121.697 118.976512)
		(width 0.15)
		(layer "F.Cu")
		(net 119)
	)
	(segment
		(start 127.5 95.5)
		(end 127.1 95.9)
		(width 0.15)
		(layer "F.Cu")
		(net 119)
	)
	(segment
		(start 121.519997 118.799509)
		(end 121.330491 118.799509)
		(width 0.15)
		(layer "F.Cu")
		(net 119)
	)
	(segment
		(start 127.1 97.6218)
		(end 125.627 99.0948)
		(width 0.15)
		(layer "F.Cu")
		(net 119)
	)
	(segment
		(start 127.1 95.9)
		(end 127.1 97.6218)
		(width 0.15)
		(layer "F.Cu")
		(net 119)
	)
	(segment
		(start 121.697 118.976512)
		(end 121.519997 118.799509)
		(width 0.15)
		(layer "F.Cu")
		(net 119)
	)
	(segment
		(start 125.627 99.0948)
		(end 125.627 100.613488)
		(width 0.15)
		(layer "F.Cu")
		(net 119)
	)
	(segment
		(start 121.68 120.125)
		(end 121.68 119.224999)
		(width 0.15)
		(layer "F.Cu")
		(net 119)
	)
	(segment
		(start 125.627 100.613488)
		(end 125.414943 100.825545)
		(width 0.15)
		(layer "F.Cu")
		(net 119)
	)
	(via
		(at 121.330491 118.799509)
		(size 0.45)
		(drill 0.2)
		(layers "F.Cu" "B.Cu")
		(remove_unused_layers yes)
		(keep_end_layers yes)
		(zone_layer_connections)
		(net 119)
	)
	(via
		(at 125.355545 100.825545)
		(size 0.45)
		(drill 0.2)
		(layers "F.Cu" "B.Cu")
		(remove_unused_layers yes)
		(keep_end_layers yes)
		(zone_layer_connections)
		(net 119)
	)
	(segment
		(start 118.9625 117.563426)
		(end 118.9625 101.901624)
		(width 0.168)
		(layer "In4.Cu")
		(net 119)
	)
	(segment
		(start 118.9625 101.901624)
		(end 119.801624 101.0625)
		(width 0.168)
		(layer "In4.Cu")
		(net 119)
	)
	(segment
		(start 119.506574 118.1075)
		(end 118.9625 117.563426)
		(width 0.168)
		(layer "In4.Cu")
		(net 119)
	)
	(segment
		(start 121.330491 118.616367)
		(end 120.821624 118.1075)
		(width 0.168)
		(layer "In4.Cu")
		(net 119)
	)
	(segment
		(start 125.176574 101.0625)
		(end 125.355545 100.883529)
		(width 0.168)
		(layer "In4.Cu")
		(net 119)
	)
	(segment
		(start 120.721624 118.2075)
		(end 120.471624 118.2075)
		(width 0.168)
		(layer "In4.Cu")
		(net 119)
	)
	(segment
		(start 119.506574 118.1075)
		(end 120.371624 118.1075)
		(width 0.168)
		(layer "In4.Cu")
		(net 119)
	)
	(segment
		(start 119.801624 101.0625)
		(end 125.176574 101.0625)
		(width 0.168)
		(layer "In4.Cu")
		(net 119)
	)
	(segment
		(start 121.330491 118.799509)
		(end 121.330491 118.616367)
		(width 0.168)
		(layer "In4.Cu")
		(net 119)
	)
	(segment
		(start 125.355545 100.883529)
		(end 125.355545 100.825545)
		(width 0.168)
		(layer "In4.Cu")
		(net 119)
	)
	(arc
		(start 120.471624 118.2075)
		(mid 120.436269 118.192855)
		(end 120.421624 118.1575)
		(width 0.168)
		(layer "In4.Cu")
		(net 119)
	)
	(arc
		(start 120.771624 118.1575)
		(mid 120.756979 118.192855)
		(end 120.721624 118.2075)
		(width 0.168)
		(layer "In4.Cu")
		(net 119)
	)
	(arc
		(start 120.421624 118.1575)
		(mid 120.406979 118.122145)
		(end 120.371624 118.1075)
		(width 0.168)
		(layer "In4.Cu")
		(net 119)
	)
	(arc
		(start 120.821624 118.1075)
		(mid 120.786269 118.122145)
		(end 120.771624 118.1575)
		(width 0.168)
		(layer "In4.Cu")
		(net 119)
	)
	(segment
		(start 98.46 116.15)
		(end 98.46 117.9225)
		(width 0.15)
		(layer "F.Cu")
		(net 134)
	)
	(segment
		(start 98.94 115.67)
		(end 98.46 116.15)
		(width 0.15)
		(layer "F.Cu")
		(net 134)
	)
	(segment
		(start 99.73 117.9225)
		(end 99.73 115.88)
		(width 0.15)
		(layer "F.Cu")
		(net 135)
	)
	(segment
		(start 101 117.9225)
		(end 101 115.73)
		(width 0.15)
		(layer "F.Cu")
		(net 136)
	)
	(segment
		(start 102.27 116)
		(end 101.94 115.67)
		(width 0.15)
		(layer "F.Cu")
		(net 138)
	)
	(segment
		(start 102.27 117.9225)
		(end 102.27 116)
		(width 0.15)
		(layer "F.Cu")
		(net 138)
	)
	(segment
		(start 103.54 116.27)
		(end 102.94 115.67)
		(width 0.15)
		(layer "F.Cu")
		(net 139)
	)
	(segment
		(start 103.54 117.9225)
		(end 103.54 116.27)
		(width 0.15)
		(layer "F.Cu")
		(net 139)
	)
	(segment
		(start 165.79 65.15)
		(end 166.64 65.15)
		(width 0.3)
		(layer "F.Cu")
		(net 140)
	)
	(segment
		(start 166.64 65.15)
		(end 167.09 64.7)
		(width 0.3)
		(layer "F.Cu")
		(net 140)
	)
	(segment
		(start 162.43 103.35)
		(end 162.43 104.38)
		(width 0.15)
		(layer "B.Cu")
		(net 141)
	)
	(segment
		(start 163.43 95.15)
		(end 162.63 94.35)
		(width 0.15)
		(layer "B.Cu")
		(net 141)
	)
	(segment
		(start 156.88 104)
		(end 157.53 104.65)
		(width 0.15)
		(layer "B.Cu")
		(net 141)
	)
	(segment
		(start 163.23 103.35)
		(end 163.43 103.15)
		(width 0.15)
		(layer "B.Cu")
		(net 141)
	)
	(segment
		(start 160.3925 103.35)
		(end 159.03 103.35)
		(width 0.15)
		(layer "B.Cu")
		(net 141)
	)
	(segment
		(start 154.6675 97.15)
		(end 156.03 97.15)
		(width 0.15)
		(layer "B.Cu")
		(net 141)
	)
	(segment
		(start 154.6675 105.3)
		(end 156.88 105.3)
		(width 0.15)
		(layer "B.Cu")
		(net 141)
	)
	(segment
		(start 156.88 105.3)
		(end 157.53 104.65)
		(width 0.15)
		(layer "B.Cu")
		(net 141)
	)
	(segment
		(start 160.3925 95.2)
		(end 159.58 95.2)
		(width 0.15)
		(layer "B.Cu")
		(net 141)
	)
	(segment
		(start 159.03 103.35)
		(end 158.53 103.85)
		(width 0.15)
		(layer "B.Cu")
		(net 141)
	)
	(segment
		(start 158.53 103.85)
		(end 158.53 104.65)
		(width 0.15)
		(layer "B.Cu")
		(net 141)
	)
	(segment
		(start 160.83 94.35)
		(end 160.3925 94.7875)
		(width 0.15)
		(layer "B.Cu")
		(net 141)
	)
	(segment
		(start 162.63 94.35)
		(end 160.83 94.35)
		(width 0.15)
		(layer "B.Cu")
		(net 141)
	)
	(segment
		(start 154.6675 104)
		(end 156.88 104)
		(width 0.15)
		(layer "B.Cu")
		(net 141)
	)
	(segment
		(start 158.53 104.65)
		(end 160.3925 104.65)
		(width 0.15)
		(layer "B.Cu")
		(net 141)
	)
	(segment
		(start 163.43 103.15)
		(end 163.43 95.15)
		(width 0.15)
		(layer "B.Cu")
		(net 141)
	)
	(segment
		(start 155.93 95.85)
		(end 154.6675 95.85)
		(width 0.15)
		(layer "B.Cu")
		(net 141)
	)
	(segment
		(start 159.58 95.2)
		(end 158.23 96.55)
		(width 0.15)
		(layer "B.Cu")
		(net 141)
	)
	(segment
		(start 160.3925 103.35)
		(end 162.23 103.35)
		(width 0.15)
		(layer "B.Cu")
		(net 141)
	)
	(segment
		(start 156.03 97.15)
		(end 156.63 96.55)
		(width 0.15)
		(layer "B.Cu")
		(net 141)
	)
	(segment
		(start 157.53 104.65)
		(end 158.53 104.65)
		(width 0.15)
		(layer "B.Cu")
		(net 141)
	)
	(segment
		(start 160.3925 94.7875)
		(end 160.3925 95.2)
		(width 0.15)
		(layer "B.Cu")
		(net 141)
	)
	(segment
		(start 162.53 103.35)
		(end 163.23 103.35)
		(width 0.15)
		(layer "B.Cu")
		(net 141)
	)
	(segment
		(start 158.23 96.55)
		(end 156.63 96.55)
		(width 0.15)
		(layer "B.Cu")
		(net 141)
	)
	(segment
		(start 156.63 96.55)
		(end 155.93 95.85)
		(width 0.15)
		(layer "B.Cu")
		(net 141)
	)
	(segment
		(start 125.301999 84.098001)
		(end 125.302 83.472)
		(width 0.2)
		(layer "F.Cu")
		(net 142)
	)
	(segment
		(start 125.302 83.472)
		(end 125.184812 83.354812)
		(width 0.2)
		(layer "F.Cu")
		(net 142)
	)
	(segment
		(start 123.16 64.14)
		(end 122.66 64.14)
		(width 0.182)
		(layer "F.Cu")
		(net 142)
	)
	(segment
		(start 125.1 84.3)
		(end 125.301999 84.098001)
		(width 0.2)
		(layer "F.Cu")
		(net 142)
	)
	(via
		(at 125.184812 83.354812)
		(size 0.45)
		(drill 0.2)
		(layers "F.Cu" "B.Cu")
		(remove_unused_layers yes)
		(keep_end_layers yes)
		(zone_layer_connections)
		(net 142)
	)
	(via
		(at 123.16 64.14)
		(size 0.45)
		(drill 0.2)
		(layers "F.Cu" "B.Cu")
		(remove_unused_layers yes)
		(keep_end_layers yes)
		(zone_layer_connections)
		(net 142)
	)
	(segment
		(start 123.11 64.19)
		(end 123.16 64.14)
		(width 0.15)
		(layer "B.Cu")
		(net 142)
	)
	(segment
		(start 122.59 64.19)
		(end 123.11 64.19)
		(width 0.15)
		(layer "B.Cu")
		(net 142)
	)
	(segment
		(start 123.903761 81.91151)
		(end 122.878004 82.937264)
		(width 0.162)
		(layer "In2.Cu")
		(net 142)
	)
	(segment
		(start 121.907146 81.966405)
		(end 124.293117 79.580433)
		(width 0.162)
		(layer "In2.Cu")
		(net 142)
	)
	(segment
		(start 123.991182 79.278498)
		(end 122.798195 80.471484)
		(width 0.162)
		(layer "In2.Cu")
		(net 142)
	)
	(segment
		(start 125.087201 80.72807)
		(end 125.087201 80.728071)
		(width 0.162)
		(layer "In2.Cu")
		(net 142)
	)
	(segment
		(start 120.452038 64.2835)
		(end 123.0165 64.2835)
		(width 0.162)
		(layer "In2.Cu")
		(net 142)
	)
	(segment
		(start 121.907145 81.966406)
		(end 121.907146 81.966405)
		(width 0.162)
		(layer "In2.Cu")
		(net 142)
	)
	(segment
		(start 122.798195 80.471484)
		(end 122.798194 80.471482)
		(width 0.162)
		(layer "In2.Cu")
		(net 142)
	)
	(segment
		(start 124.691125 81.728016)
		(end 124.691125 81.728017)
		(width 0.162)
		(layer "In2.Cu")
		(net 142)
	)
	(segment
		(start 120.236342 78.244092)
		(end 118.9435 76.95125)
		(width 0.162)
		(layer "In2.Cu")
		(net 142)
	)
	(segment
		(start 121.525398 79.198686)
		(end 121.374432 79.349655)
		(width 0.162)
		(layer "In2.Cu")
		(net 142)
	)
	(segment
		(start 123.020321 78.005701)
		(end 123.020321 78.005702)
		(width 0.162)
		(layer "In2.Cu")
		(net 142)
	)
	(segment
		(start 125.184812 83.354812)
		(end 125.249155 83.290469)
		(width 0.162)
		(layer "In2.Cu")
		(net 142)
	)
	(segment
		(start 122.798194 80.471482)
		(end 122.630965 80.638714)
		(width 0.162)
		(layer "In2.Cu")
		(net 142)
	)
	(segment
		(start 122.630965 80.638714)
		(end 121.605208 81.664468)
		(width 0.162)
		(layer "In2.Cu")
		(net 142)
	)
	(segment
		(start 124.07099 81.744278)
		(end 123.903761 81.91151)
		(width 0.162)
		(layer "In2.Cu")
		(net 142)
	)
	(segment
		(start 123.991182 79.278497)
		(end 123.991182 79.278498)
		(width 0.162)
		(layer "In2.Cu")
		(net 142)
	)
	(segment
		(start 125.249155 83.290469)
		(end 125.249155 83.256905)
		(width 0.162)
		(layer "In2.Cu")
		(net 142)
	)
	(segment
		(start 119.962594 78.819773)
		(end 120.236342 78.546026)
		(width 0.162)
		(layer "In2.Cu")
		(net 142)
	)
	(segment
		(start 121.525399 79.198688)
		(end 121.525398 79.198686)
		(width 0.162)
		(layer "In2.Cu")
		(net 142)
	)
	(segment
		(start 119.962593 78.819774)
		(end 119.962594 78.819773)
		(width 0.162)
		(layer "In2.Cu")
		(net 142)
	)
	(segment
		(start 120.634349 80.69361)
		(end 120.63435 80.693609)
		(width 0.162)
		(layer "In2.Cu")
		(net 142)
	)
	(segment
		(start 124.070991 81.74428)
		(end 124.07099 81.744278)
		(width 0.162)
		(layer "In2.Cu")
		(net 142)
	)
	(segment
		(start 118.9435 65.792038)
		(end 120.452038 64.2835)
		(width 0.162)
		(layer "In2.Cu")
		(net 142)
	)
	(segment
		(start 120.63435 81.664468)
		(end 120.63435 81.664467)
		(width 0.162)
		(layer "In2.Cu")
		(net 142)
	)
	(segment
		(start 118.9435 76.95125)
		(end 118.9435 65.792038)
		(width 0.162)
		(layer "In2.Cu")
		(net 142)
	)
	(segment
		(start 121.374432 79.349655)
		(end 121.2072 79.516884)
		(width 0.162)
		(layer "In2.Cu")
		(net 142)
	)
	(segment
		(start 122.718386 78.005701)
		(end 122.718386 78.005702)
		(width 0.162)
		(layer "In2.Cu")
		(net 142)
	)
	(segment
		(start 120.236341 78.244091)
		(end 120.236342 78.244092)
		(width 0.162)
		(layer "In2.Cu")
		(net 142)
	)
	(segment
		(start 120.63435 80.693609)
		(end 123.020321 78.307637)
		(width 0.162)
		(layer "In2.Cu")
		(net 142)
	)
	(segment
		(start 122.718386 78.005702)
		(end 121.525399 79.198688)
		(width 0.162)
		(layer "In2.Cu")
		(net 142)
	)
	(segment
		(start 121.907146 82.937264)
		(end 121.907146 82.937263)
		(width 0.162)
		(layer "In2.Cu")
		(net 142)
	)
	(segment
		(start 124.691125 81.728017)
		(end 125.389136 81.030005)
		(width 0.162)
		(layer "In2.Cu")
		(net 142)
	)
	(segment
		(start 121.2072 79.516884)
		(end 120.933454 79.790633)
		(width 0.162)
		(layer "In2.Cu")
		(net 142)
	)
	(segment
		(start 125.249155 83.256905)
		(end 124.691125 82.698874)
		(width 0.162)
		(layer "In2.Cu")
		(net 142)
	)
	(segment
		(start 124.293117 79.278497)
		(end 124.293117 79.278498)
		(width 0.162)
		(layer "In2.Cu")
		(net 142)
	)
	(segment
		(start 125.087201 80.728071)
		(end 124.070991 81.74428)
		(width 0.162)
		(layer "In2.Cu")
		(net 142)
	)
	(segment
		(start 123.0165 64.2835)
		(end 123.16 64.14)
		(width 0.162)
		(layer "In2.Cu")
		(net 142)
	)
	(segment
		(start 125.389135 80.72807)
		(end 125.389136 80.728071)
		(width 0.162)
		(layer "In2.Cu")
		(net 142)
	)
	(arc
		(start 123.020321 78.005702)
		(mid 122.869354 77.943169)
		(end 122.718386 78.005701)
		(width 0.162)
		(layer "In2.Cu")
		(net 142)
	)
	(arc
		(start 124.293117 79.580433)
		(mid 124.35565 79.429465)
		(end 124.293117 79.278497)
		(width 0.162)
		(layer "In2.Cu")
		(net 142)
	)
	(arc
		(start 123.020321 78.307637)
		(mid 123.082854 78.156669)
		(end 123.020321 78.005701)
		(width 0.162)
		(layer "In2.Cu")
		(net 142)
	)
	(arc
		(start 120.63435 81.664467)
		(mid 120.433278 81.179039)
		(end 120.634349 80.69361)
		(width 0.162)
		(layer "In2.Cu")
		(net 142)
	)
	(arc
		(start 125.389136 81.030005)
		(mid 125.451668 80.879037)
		(end 125.389135 80.72807)
		(width 0.162)
		(layer "In2.Cu")
		(net 142)
	)
	(arc
		(start 121.907146 82.937263)
		(mid 121.706074 82.451835)
		(end 121.907145 81.966406)
		(width 0.162)
		(layer "In2.Cu")
		(net 142)
	)
	(arc
		(start 121.605208 81.664468)
		(mid 121.119779 81.865539)
		(end 120.63435 81.664468)
		(width 0.162)
		(layer "In2.Cu")
		(net 142)
	)
	(arc
		(start 120.236342 78.546026)
		(mid 120.298874 78.395058)
		(end 120.236341 78.244091)
		(width 0.162)
		(layer "In2.Cu")
		(net 142)
	)
	(arc
		(start 119.962594 79.790631)
		(mid 119.761522 79.305203)
		(end 119.962593 78.819774)
		(width 0.162)
		(layer "In2.Cu")
		(net 142)
	)
	(arc
		(start 124.293117 79.278498)
		(mid 124.14215 79.215965)
		(end 123.991182 79.278497)
		(width 0.162)
		(layer "In2.Cu")
		(net 142)
	)
	(arc
		(start 124.691125 82.698874)
		(mid 124.490054 82.213445)
		(end 124.691125 81.728016)
		(width 0.162)
		(layer "In2.Cu")
		(net 142)
	)
	(arc
		(start 122.878004 82.937264)
		(mid 122.392575 83.138335)
		(end 121.907146 82.937264)
		(width 0.162)
		(layer "In2.Cu")
		(net 142)
	)
	(arc
		(start 120.933454 79.790633)
		(mid 120.448025 79.991704)
		(end 119.962594 79.790631)
		(width 0.162)
		(layer "In2.Cu")
		(net 142)
	)
	(arc
		(start 125.389136 80.728071)
		(mid 125.238169 80.665538)
		(end 125.087201 80.72807)
		(width 0.162)
		(layer "In2.Cu")
		(net 142)
	)
	(segment
		(start 125.698 83.463159)
		(end 125.796423 83.364736)
		(width 0.2)
		(layer "F.Cu")
		(net 143)
	)
	(segment
		(start 125.9 84.3)
		(end 125.698001 84.098001)
		(width 0.2)
		(layer "F.Cu")
		(net 143)
	)
	(segment
		(start 125.698001 84.098001)
		(end 125.698 83.463159)
		(width 0.2)
		(layer "F.Cu")
		(net 143)
	)
	(segment
		(start 123.16 64.94)
		(end 122.66 64.94)
		(width 0.182)
		(layer "F.Cu")
		(net 143)
	)
	(via
		(at 123.16 64.94)
		(size 0.45)
		(drill 0.2)
		(layers "F.Cu" "B.Cu")
		(remove_unused_layers yes)
		(keep_end_layers yes)
		(zone_layer_connections)
		(net 143)
	)
	(via
		(at 125.796423 83.364736)
		(size 0.45)
		(drill 0.2)
		(layers "F.Cu" "B.Cu")
		(remove_unused_layers yes)
		(keep_end_layers yes)
		(zone_layer_connections)
		(net 143)
	)
	(segment
		(start 123.05 64.83)
		(end 123.16 64.94)
		(width 0.15)
		(layer "B.Cu")
		(net 143)
	)
	(segment
		(start 122.59 64.83)
		(end 123.05 64.83)
		(width 0.15)
		(layer "B.Cu")
		(net 143)
	)
	(segment
		(start 125.025586 82.062478)
		(end 125.025586 82.062477)
		(width 0.162)
		(layer "In2.Cu")
		(net 143)
	)
	(segment
		(start 120.968811 81.330006)
		(end 120.968811 81.330007)
		(width 0.162)
		(layer "In2.Cu")
		(net 143)
	)
	(segment
		(start 122.241608 82.300868)
		(end 122.241606 82.300867)
		(width 0.162)
		(layer "In2.Cu")
		(net 143)
	)
	(segment
		(start 120.337692 77.676517)
		(end 120.570803 77.909628)
		(width 0.162)
		(layer "In2.Cu")
		(net 143)
	)
	(segment
		(start 120.350077 77.31058)
		(end 120.337691 77.322965)
		(width 0.162)
		(layer "In2.Cu")
		(net 143)
	)
	(segment
		(start 123.16 64.94)
		(end 122.9765 64.7565)
		(width 0.162)
		(layer "In2.Cu")
		(net 143)
	)
	(segment
		(start 120.968812 81.028072)
		(end 120.96881 81.028071)
		(width 0.162)
		(layer "In2.Cu")
		(net 143)
	)
	(segment
		(start 120.59899 79.456169)
		(end 120.872739 79.182423)
		(width 0.162)
		(layer "In2.Cu")
		(net 143)
	)
	(segment
		(start 122.543543 82.602803)
		(end 124.752739 80.393609)
		(width 0.162)
		(layer "In2.Cu")
		(net 143)
	)
	(segment
		(start 125.025586 82.364413)
		(end 125.722155 83.060981)
		(width 0.162)
		(layer "In2.Cu")
		(net 143)
	)
	(segment
		(start 124.752739 80.393609)
		(end 124.75274 80.393608)
		(width 0.162)
		(layer "In2.Cu")
		(net 143)
	)
	(segment
		(start 125.723597 81.364466)
		(end 125.025586 82.062478)
		(width 0.162)
		(layer "In2.Cu")
		(net 143)
	)
	(segment
		(start 125.722155 83.290468)
		(end 125.796423 83.364736)
		(width 0.162)
		(layer "In2.Cu")
		(net 143)
	)
	(segment
		(start 119.984139 76.969412)
		(end 119.996524 76.957028)
		(width 0.162)
		(layer "In2.Cu")
		(net 143)
	)
	(segment
		(start 124.627578 79.914894)
		(end 122.241608 82.300868)
		(width 0.162)
		(layer "In2.Cu")
		(net 143)
	)
	(segment
		(start 123.65672 78.944037)
		(end 123.656721 78.944036)
		(width 0.162)
		(layer "In2.Cu")
		(net 143)
	)
	(segment
		(start 120.350077 76.957029)
		(end 120.350076 76.957027)
		(width 0.162)
		(layer "In2.Cu")
		(net 143)
	)
	(segment
		(start 120.872739 79.182423)
		(end 121.039968 79.015191)
		(width 0.162)
		(layer "In2.Cu")
		(net 143)
	)
	(segment
		(start 124.627578 78.944037)
		(end 124.627578 78.944036)
		(width 0.162)
		(layer "In2.Cu")
		(net 143)
	)
	(segment
		(start 121.039968 79.015191)
		(end 122.383925 77.67124)
		(width 0.162)
		(layer "In2.Cu")
		(net 143)
	)
	(segment
		(start 123.354782 78.642098)
		(end 120.968812 81.028072)
		(width 0.162)
		(layer "In2.Cu")
		(net 143)
	)
	(segment
		(start 120.647962 64.7565)
		(end 119.4165 65.987962)
		(width 0.162)
		(layer "In2.Cu")
		(net 143)
	)
	(segment
		(start 119.4165 76.755326)
		(end 119.630587 76.969413)
		(width 0.162)
		(layer "In2.Cu")
		(net 143)
	)
	(segment
		(start 119.98414 76.969412)
		(end 119.984139 76.969412)
		(width 0.162)
		(layer "In2.Cu")
		(net 143)
	)
	(segment
		(start 120.297057 79.154235)
		(end 120.297055 79.154234)
		(width 0.162)
		(layer "In2.Cu")
		(net 143)
	)
	(segment
		(start 125.723597 80.393609)
		(end 125.723597 80.393608)
		(width 0.162)
		(layer "In2.Cu")
		(net 143)
	)
	(segment
		(start 119.4165 65.987962)
		(end 119.4165 76.755326)
		(width 0.162)
		(layer "In2.Cu")
		(net 143)
	)
	(segment
		(start 121.270747 81.330007)
		(end 123.65672 78.944037)
		(width 0.162)
		(layer "In2.Cu")
		(net 143)
	)
	(segment
		(start 120.337691 77.676519)
		(end 120.337692 77.676517)
		(width 0.162)
		(layer "In2.Cu")
		(net 143)
	)
	(segment
		(start 123.354782 77.671241)
		(end 123.354782 77.67124)
		(width 0.162)
		(layer "In2.Cu")
		(net 143)
	)
	(segment
		(start 122.9765 64.7565)
		(end 120.647962 64.7565)
		(width 0.162)
		(layer "In2.Cu")
		(net 143)
	)
	(segment
		(start 125.722155 83.060981)
		(end 125.722155 83.290468)
		(width 0.162)
		(layer "In2.Cu")
		(net 143)
	)
	(segment
		(start 120.570803 78.880486)
		(end 120.297057 79.154235)
		(width 0.162)
		(layer "In2.Cu")
		(net 143)
	)
	(segment
		(start 122.241607 82.602802)
		(end 122.241607 82.602803)
		(width 0.162)
		(layer "In2.Cu")
		(net 143)
	)
	(arc
		(start 120.337691 77.322965)
		(mid 120.264468 77.499742)
		(end 120.337691 77.676519)
		(width 0.162)
		(layer "In2.Cu")
		(net 143)
	)
	(arc
		(start 120.570803 77.909628)
		(mid 120.771874 78.395057)
		(end 120.570803 78.880486)
		(width 0.162)
		(layer "In2.Cu")
		(net 143)
	)
	(arc
		(start 120.96881 81.028071)
		(mid 120.906278 81.179039)
		(end 120.968811 81.330006)
		(width 0.162)
		(layer "In2.Cu")
		(net 143)
	)
	(arc
		(start 122.383925 77.67124)
		(mid 122.869354 77.470169)
		(end 123.354782 77.671241)
		(width 0.162)
		(layer "In2.Cu")
		(net 143)
	)
	(arc
		(start 120.297055 79.154234)
		(mid 120.234523 79.305202)
		(end 120.297056 79.456169)
		(width 0.162)
		(layer "In2.Cu")
		(net 143)
	)
	(arc
		(start 120.350076 76.957027)
		(mid 120.423301 77.133804)
		(end 120.350077 77.31058)
		(width 0.162)
		(layer "In2.Cu")
		(net 143)
	)
	(arc
		(start 120.968811 81.330007)
		(mid 121.119778 81.392539)
		(end 121.270747 81.330007)
		(width 0.162)
		(layer "In2.Cu")
		(net 143)
	)
	(arc
		(start 123.656721 78.944036)
		(mid 124.14215 78.742965)
		(end 124.627578 78.944037)
		(width 0.162)
		(layer "In2.Cu")
		(net 143)
	)
	(arc
		(start 124.75274 80.393608)
		(mid 125.238169 80.192537)
		(end 125.723597 80.393609)
		(width 0.162)
		(layer "In2.Cu")
		(net 143)
	)
	(arc
		(start 119.630587 76.969413)
		(mid 119.807364 77.042636)
		(end 119.98414 76.969412)
		(width 0.162)
		(layer "In2.Cu")
		(net 143)
	)
	(arc
		(start 125.025586 82.062477)
		(mid 124.963053 82.213445)
		(end 125.025586 82.364413)
		(width 0.162)
		(layer "In2.Cu")
		(net 143)
	)
	(arc
		(start 124.627578 78.944036)
		(mid 124.828649 79.429465)
		(end 124.627578 79.914894)
		(width 0.162)
		(layer "In2.Cu")
		(net 143)
	)
	(arc
		(start 120.297056 79.456169)
		(mid 120.448023 79.518702)
		(end 120.59899 79.456169)
		(width 0.162)
		(layer "In2.Cu")
		(net 143)
	)
	(arc
		(start 119.996524 76.957028)
		(mid 120.173301 76.883805)
		(end 120.350077 76.957029)
		(width 0.162)
		(layer "In2.Cu")
		(net 143)
	)
	(arc
		(start 122.241607 82.602803)
		(mid 122.392574 82.665335)
		(end 122.543543 82.602803)
		(width 0.162)
		(layer "In2.Cu")
		(net 143)
	)
	(arc
		(start 123.354782 77.67124)
		(mid 123.555853 78.156669)
		(end 123.354782 78.642098)
		(width 0.162)
		(layer "In2.Cu")
		(net 143)
	)
	(arc
		(start 122.241606 82.300867)
		(mid 122.179074 82.451835)
		(end 122.241607 82.602802)
		(width 0.162)
		(layer "In2.Cu")
		(net 143)
	)
	(arc
		(start 125.723597 80.393608)
		(mid 125.924668 80.879037)
		(end 125.723597 81.364466)
		(width 0.162)
		(layer "In2.Cu")
		(net 143)
	)
	(segment
		(start 125.86 60.94)
		(end 126.26 60.54)
		(width 0.182)
		(layer "F.Cu")
		(net 144)
	)
	(segment
		(start 124.3 88.3)
		(end 123.91 88.69)
		(width 0.2)
		(layer "F.Cu")
		(net 144)
	)
	(segment
		(start 123.91 88.69)
		(end 123.9 88.69)
		(width 0.2)
		(layer "F.Cu")
		(net 144)
	)
	(via
		(at 126.26 60.54)
		(size 0.45)
		(drill 0.2)
		(layers "F.Cu" "B.Cu")
		(remove_unused_layers yes)
		(keep_end_layers yes)
		(zone_layer_connections)
		(net 144)
	)
	(via
		(at 123.9 88.69)
		(size 0.45)
		(drill 0.1)
		(layers "F.Cu" "B.Cu")
		(net 144)
	)
	(segment
		(start 125.77 60.05)
		(end 125.77 59.38)
		(width 0.15)
		(layer "B.Cu")
		(net 144)
	)
	(segment
		(start 124.62 58.23)
		(end 124.61 58.23)
		(width 0.15)
		(layer "B.Cu")
		(net 144)
	)
	(segment
		(start 124.61 58.23)
		(end 124.61 57.89)
		(width 0.15)
		(layer "B.Cu")
		(net 144)
	)
	(segment
		(start 126.26 60.54)
		(end 125.77 60.05)
		(width 0.15)
		(layer "B.Cu")
		(net 144)
	)
	(segment
		(start 125.77 59.38)
		(end 124.62 58.23)
		(width 0.15)
		(layer "B.Cu")
		(net 144)
	)
	(segment
		(start 126.65 61.505059)
		(end 126.65 60.93)
		(width 0.162)
		(layer "In4.Cu")
		(net 144)
	)
	(segment
		(start 131.39 62.28)
		(end 130.05 62.28)
		(width 0.162)
		(layer "In4.Cu")
		(net 144)
	)
	(segment
		(start 131.33162 71.919512)
		(end 132.909356 71.919512)
		(width 0.162)
		(layer "In4.Cu")
		(net 144)
	)
	(segment
		(start 131.920488 72.319512)
		(end 131.33162 72.319512)
		(width 0.162)
		(layer "In4.Cu")
		(net 144)
	)
	(segment
		(start 123.495 87.736385)
		(end 123.253615 87.495)
		(width 0.15)
		(layer "In4.Cu")
		(net 144)
	)
	(segment
		(start 131.8 74.97)
		(end 132.120488 74.649512)
		(width 0.162)
		(layer "In4.Cu")
		(net 144)
	)
	(segment
		(start 122.936385 87.495)
		(end 122.7 87.258615)
		(width 0.15)
		(layer "In4.Cu")
		(net 144)
	)
	(segment
		(start 131.33162 71.119512)
		(end 132.909356 71.119512)
		(width 0.162)
		(layer "In4.Cu")
		(net 144)
	)
	(segment
		(start 122.8 78.18)
		(end 126.01 74.97)
		(width 0.15)
		(layer "In4.Cu")
		(net 144)
	)
	(segment
		(start 132.062702 62.954247)
		(end 132.03 62.92)
		(width 0.162)
		(layer "In4.Cu")
		(net 144)
	)
	(segment
		(start 132.120488 74.649512)
		(end 132.120488 72.519512)
		(width 0.162)
		(layer "In4.Cu")
		(net 144)
	)
	(segment
		(start 132.120488 70.519512)
		(end 132.120488 63.132124)
		(width 0.162)
		(layer "In4.Cu")
		(net 144)
	)
	(segment
		(start 123.495 88.295499)
		(end 123.495 87.736385)
		(width 0.15)
		(layer "In4.Cu")
		(net 144)
	)
	(segment
		(start 122.7 85.82)
		(end 122.8 85.72)
		(width 0.15)
		(layer "In4.Cu")
		(net 144)
	)
	(segment
		(start 132.105683 63.038609)
		(end 132.062702 62.954247)
		(width 0.162)
		(layer "In4.Cu")
		(net 144)
	)
	(segment
		(start 128.4 61.2)
		(end 127.87 61.73)
		(width 0.162)
		(layer "In4.Cu")
		(net 144)
	)
	(segment
		(start 131.33162 71.519512)
		(end 132.909356 71.519512)
		(width 0.162)
		(layer "In4.Cu")
		(net 144)
	)
	(segment
		(start 127.87 61.73)
		(end 126.874941 61.73)
		(width 0.162)
		(layer "In4.Cu")
		(net 144)
	)
	(segment
		(start 123.9 88.69)
		(end 123.889501 88.69)
		(width 0.162)
		(layer "In4.Cu")
		(net 144)
	)
	(segment
		(start 123.889501 88.69)
		(end 123.495 88.295499)
		(width 0.162)
		(layer "In4.Cu")
		(net 144)
	)
	(segment
		(start 132.909356 70.719512)
		(end 132.320488 70.719512)
		(width 0.162)
		(layer "In4.Cu")
		(net 144)
	)
	(segment
		(start 128.97 61.2)
		(end 128.4 61.2)
		(width 0.162)
		(layer "In4.Cu")
		(net 144)
	)
	(segment
		(start 132.03 62.92)
		(end 131.39 62.28)
		(width 0.162)
		(layer "In4.Cu")
		(net 144)
	)
	(segment
		(start 122.7 87.258615)
		(end 122.7 85.82)
		(width 0.15)
		(layer "In4.Cu")
		(net 144)
	)
	(segment
		(start 123.253615 87.495)
		(end 122.936385 87.495)
		(width 0.15)
		(layer "In4.Cu")
		(net 144)
	)
	(segment
		(start 130.05 62.28)
		(end 128.97 61.2)
		(width 0.162)
		(layer "In4.Cu")
		(net 144)
	)
	(segment
		(start 132.120488 63.132124)
		(end 132.105683 63.038609)
		(width 0.162)
		(layer "In4.Cu")
		(net 144)
	)
	(segment
		(start 122.8 85.72)
		(end 122.8 78.18)
		(width 0.15)
		(layer "In4.Cu")
		(net 144)
	)
	(segment
		(start 126.65 60.93)
		(end 126.26 60.54)
		(width 0.162)
		(layer "In4.Cu")
		(net 144)
	)
	(segment
		(start 126.874941 61.73)
		(end 126.65 61.505059)
		(width 0.162)
		(layer "In4.Cu")
		(net 144)
	)
	(segment
		(start 126.01 74.97)
		(end 131.8 74.97)
		(width 0.162)
		(layer "In4.Cu")
		(net 144)
	)
	(arc
		(start 131.13162 71.319512)
		(mid 131.190199 71.178091)
		(end 131.33162 71.119512)
		(width 0.162)
		(layer "In4.Cu")
		(net 144)
	)
	(arc
		(start 132.120488 72.519512)
		(mid 132.061909 72.378091)
		(end 131.920488 72.319512)
		(width 0.162)
		(layer "In4.Cu")
		(net 144)
	)
	(arc
		(start 132.909356 71.919512)
		(mid 133.050777 71.860933)
		(end 133.109356 71.719512)
		(width 0.162)
		(layer "In4.Cu")
		(net 144)
	)
	(arc
		(start 131.13162 72.119512)
		(mid 131.190199 71.978091)
		(end 131.33162 71.919512)
		(width 0.162)
		(layer "In4.Cu")
		(net 144)
	)
	(arc
		(start 132.909356 71.119512)
		(mid 133.050777 71.060933)
		(end 133.109356 70.919512)
		(width 0.162)
		(layer "In4.Cu")
		(net 144)
	)
	(arc
		(start 132.320488 70.719512)
		(mid 132.179067 70.660933)
		(end 132.120488 70.519512)
		(width 0.162)
		(layer "In4.Cu")
		(net 144)
	)
	(arc
		(start 133.109356 71.719512)
		(mid 133.050777 71.578091)
		(end 132.909356 71.519512)
		(width 0.162)
		(layer "In4.Cu")
		(net 144)
	)
	(arc
		(start 131.33162 71.519512)
		(mid 131.190199 71.460933)
		(end 131.13162 71.319512)
		(width 0.162)
		(layer "In4.Cu")
		(net 144)
	)
	(arc
		(start 131.33162 72.319512)
		(mid 131.190199 72.260933)
		(end 131.13162 72.119512)
		(width 0.162)
		(layer "In4.Cu")
		(net 144)
	)
	(arc
		(start 133.109356 70.919512)
		(mid 133.050777 70.778091)
		(end 132.909356 70.719512)
		(width 0.162)
		(layer "In4.Cu")
		(net 144)
	)
	(segment
		(start 120.3 86.7)
		(end 119.9 86.3)
		(width 0.2)
		(layer "F.Cu")
		(net 145)
	)
	(segment
		(start 119.9 86.3)
		(end 119.86 86.3)
		(width 0.2)
		(layer "F.Cu")
		(net 145)
	)
	(segment
		(start 122.26 60.54)
		(end 122.66 60.94)
		(width 0.182)
		(layer "F.Cu")
		(net 145)
	)
	(via
		(at 119.86 86.3)
		(size 0.45)
		(drill 0.1)
		(layers "F.Cu" "B.Cu")
		(net 145)
	)
	(via
		(at 122.26 60.54)
		(size 0.45)
		(drill 0.2)
		(layers "F.Cu" "B.Cu")
		(remove_unused_layers yes)
		(keep_end_layers yes)
		(zone_layer_connections)
		(net 145)
	)
	(segment
		(start 123.09 59.53)
		(end 123.51 59.53)
		(width 0.15)
		(layer "B.Cu")
		(net 145)
	)
	(segment
		(start 122.26 60.54)
		(end 122.41 60.54)
		(width 0.15)
		(layer "B.Cu")
		(net 145)
	)
	(segment
		(start 122.41 60.54)
		(end 122.97 59.98)
		(width 0.15)
		(layer "B.Cu")
		(net 145)
	)
	(segment
		(start 122.97 59.65)
		(end 123.09 59.53)
		(width 0.15)
		(layer "B.Cu")
		(net 145)
	)
	(segment
		(start 122.97 59.98)
		(end 122.97 59.65)
		(width 0.15)
		(layer "B.Cu")
		(net 145)
	)
	(segment
		(start 114.513313 74.82)
		(end 115.053374 74.82)
		(width 0.162)
		(layer "In2.Cu")
		(net 145)
	)
	(segment
		(start 114.513313 74.42)
		(end 115.053374 74.42)
		(width 0.162)
		(layer "In2.Cu")
		(net 145)
	)
	(segment
		(start 114.316626 75.423313)
		(end 114.316626 75.416687)
		(width 0.162)
		(layer "In2.Cu")
		(net 145)
	)
	(segment
		(start 114.316626 77.023313)
		(end 114.316626 77.016687)
		(width 0.162)
		(layer "In2.Cu")
		(net 145)
	)
	(segment
		(start 114.513313 73.62)
		(end 115.053374 73.62)
		(width 0.162)
		(layer "In2.Cu")
		(net 145)
	)
	(segment
		(start 114.513313 75.22)
		(end 115.053374 75.22)
		(width 0.162)
		(layer "In2.Cu")
		(net 145)
	)
	(segment
		(start 114.71 80.023313)
		(end 114.71 80.02)
		(width 0.162)
		(layer "In2.Cu")
		(net 145)
	)
	(segment
		(start 120.88 61.3)
		(end 121.24 60.94)
		(width 0.15)
		(layer "In2.Cu")
		(net 145)
	)
	(segment
		(start 114.513313 74.02)
		(end 115.053374 74.02)
		(width 0.162)
		(layer "In2.Cu")
		(net 145)
	)
	(segment
		(start 114.513313 77.22)
		(end 115.053374 77.22)
		(width 0.162)
		(layer "In2.Cu")
		(net 145)
	)
	(segment
		(start 114.316626 79.423313)
		(end 114.316626 79.416687)
		(width 0.162)
		(layer "In2.Cu")
		(net 145)
	)
	(segment
		(start 114.513313 77.62)
		(end 115.053374 77.62)
		(width 0.162)
		(layer "In2.Cu")
		(net 145)
	)
	(segment
		(start 114.513313 76.82)
		(end 115.053374 76.82)
		(width 0.162)
		(layer "In2.Cu")
		(net 145)
	)
	(segment
		(start 114.71 73.02)
		(end 114.71 63.96)
		(width 0.162)
		(layer "In2.Cu")
		(net 145)
	)
	(segment
		(start 114.513313 75.62)
		(end 115.053374 75.62)
		(width 0.162)
		(layer "In2.Cu")
		(net 145)
	)
	(segment
		(start 114.316626 76.223313)
		(end 114.316626 76.216687)
		(width 0.162)
		(layer "In2.Cu")
		(net 145)
	)
	(segment
		(start 114.316626 74.623313)
		(end 114.316626 74.616687)
		(width 0.162)
		(layer "In2.Cu")
		(net 145)
	)
	(segment
		(start 114.513313 78.02)
		(end 115.053374 78.02)
		(width 0.162)
		(layer "In2.Cu")
		(net 145)
	)
	(segment
		(start 114.316626 73.823313)
		(end 114.316626 73.816687)
		(width 0.162)
		(layer "In2.Cu")
		(net 145)
	)
	(segment
		(start 114.513313 78.82)
		(end 115.053374 78.82)
		(width 0.162)
		(layer "In2.Cu")
		(net 145)
	)
	(segment
		(start 119.79 86.37)
		(end 119.32 86.37)
		(width 0.162)
		(layer "In2.Cu")
		(net 145)
	)
	(segment
		(start 117.37 61.3)
		(end 120.88 61.3)
		(width 0.162)
		(layer "In2.Cu")
		(net 145)
	)
	(segment
		(start 114.316626 77.823313)
		(end 114.316626 77.816687)
		(width 0.162)
		(layer "In2.Cu")
		(net 145)
	)
	(segment
		(start 114.513313 76.42)
		(end 115.053374 76.42)
		(width 0.162)
		(layer "In2.Cu")
		(net 145)
	)
	(segment
		(start 114.513313 79.62)
		(end 115.053374 79.62)
		(width 0.162)
		(layer "In2.Cu")
		(net 145)
	)
	(segment
		(start 114.71 63.96)
		(end 117.37 61.3)
		(width 0.162)
		(layer "In2.Cu")
		(net 145)
	)
	(segment
		(start 114.71 81.76)
		(end 114.71 80.62)
		(width 0.162)
		(layer "In2.Cu")
		(net 145)
	)
	(segment
		(start 114.513313 78.42)
		(end 115.053374 78.42)
		(width 0.162)
		(layer "In2.Cu")
		(net 145)
	)
	(segment
		(start 114.513313 76.02)
		(end 115.053374 76.02)
		(width 0.162)
		(layer "In2.Cu")
		(net 145)
	)
	(segment
		(start 121.86 60.94)
		(end 121.24 60.94)
		(width 0.15)
		(layer "In2.Cu")
		(net 145)
	)
	(segment
		(start 114.513313 79.22)
		(end 115.053374 79.22)
		(width 0.162)
		(layer "In2.Cu")
		(net 145)
	)
	(segment
		(start 119.86 86.3)
		(end 119.79 86.37)
		(width 0.162)
		(layer "In2.Cu")
		(net 145)
	)
	(segment
		(start 114.71 80.02)
		(end 115.053374 80.02)
		(width 0.162)
		(layer "In2.Cu")
		(net 145)
	)
	(segment
		(start 114.316626 80.226626)
		(end 114.316626 80.22)
		(width 0.162)
		(layer "In2.Cu")
		(net 145)
	)
	(segment
		(start 115.053374 73.22)
		(end 114.91 73.22)
		(width 0.162)
		(layer "In2.Cu")
		(net 145)
	)
	(segment
		(start 121.86 60.94)
		(end 122.26 60.54)
		(width 0.15)
		(layer "In2.Cu")
		(net 145)
	)
	(segment
		(start 119.32 86.37)
		(end 114.71 81.76)
		(width 0.162)
		(layer "In2.Cu")
		(net 145)
	)
	(segment
		(start 114.513313 80.023313)
		(end 114.71 80.023313)
		(width 0.162)
		(layer "In2.Cu")
		(net 145)
	)
	(segment
		(start 114.316626 78.623313)
		(end 114.316626 78.616687)
		(width 0.162)
		(layer "In2.Cu")
		(net 145)
	)
	(arc
		(start 114.513313 74.02)
		(mid 114.374234 73.962392)
		(end 114.316626 73.823313)
		(width 0.162)
		(layer "In2.Cu")
		(net 145)
	)
	(arc
		(start 114.316626 74.616687)
		(mid 114.374234 74.477608)
		(end 114.513313 74.42)
		(width 0.162)
		(layer "In2.Cu")
		(net 145)
	)
	(arc
		(start 115.253374 78.22)
		(mid 115.194795 78.078579)
		(end 115.053374 78.02)
		(width 0.162)
		(layer "In2.Cu")
		(net 145)
	)
	(arc
		(start 114.316626 77.816687)
		(mid 114.374234 77.677608)
		(end 114.513313 77.62)
		(width 0.162)
		(layer "In2.Cu")
		(net 145)
	)
	(arc
		(start 114.316626 80.22)
		(mid 114.374234 80.080921)
		(end 114.513313 80.023313)
		(width 0.162)
		(layer "In2.Cu")
		(net 145)
	)
	(arc
		(start 115.253374 75.02)
		(mid 115.194795 74.878579)
		(end 115.053374 74.82)
		(width 0.162)
		(layer "In2.Cu")
		(net 145)
	)
	(arc
		(start 115.053374 76.02)
		(mid 115.194795 75.961421)
		(end 115.253374 75.82)
		(width 0.162)
		(layer "In2.Cu")
		(net 145)
	)
	(arc
		(start 115.053374 77.62)
		(mid 115.194795 77.561421)
		(end 115.253374 77.42)
		(width 0.162)
		(layer "In2.Cu")
		(net 145)
	)
	(arc
		(start 114.513313 76.42)
		(mid 114.374234 76.362392)
		(end 114.316626 76.223313)
		(width 0.162)
		(layer "In2.Cu")
		(net 145)
	)
	(arc
		(start 114.316626 78.616687)
		(mid 114.374234 78.477608)
		(end 114.513313 78.42)
		(width 0.162)
		(layer "In2.Cu")
		(net 145)
	)
	(arc
		(start 115.053374 79.22)
		(mid 115.194795 79.161421)
		(end 115.253374 79.02)
		(width 0.162)
		(layer "In2.Cu")
		(net 145)
	)
	(arc
		(start 115.053374 74.42)
		(mid 115.194795 74.361421)
		(end 115.253374 74.22)
		(width 0.162)
		(layer "In2.Cu")
		(net 145)
	)
	(arc
		(start 115.253374 73.42)
		(mid 115.194795 73.278579)
		(end 115.053374 73.22)
		(width 0.162)
		(layer "In2.Cu")
		(net 145)
	)
	(arc
		(start 115.253374 77.42)
		(mid 115.194795 77.278579)
		(end 115.053374 77.22)
		(width 0.162)
		(layer "In2.Cu")
		(net 145)
	)
	(arc
		(start 114.316626 77.016687)
		(mid 114.374234 76.877608)
		(end 114.513313 76.82)
		(width 0.162)
		(layer "In2.Cu")
		(net 145)
	)
	(arc
		(start 114.513313 79.62)
		(mid 114.374234 79.562392)
		(end 114.316626 79.423313)
		(width 0.162)
		(layer "In2.Cu")
		(net 145)
	)
	(arc
		(start 114.513313 75.62)
		(mid 114.374234 75.562392)
		(end 114.316626 75.423313)
		(width 0.162)
		(layer "In2.Cu")
		(net 145)
	)
	(arc
		(start 114.513313 78.02)
		(mid 114.374234 77.962392)
		(end 114.316626 77.823313)
		(width 0.162)
		(layer "In2.Cu")
		(net 145)
	)
	(arc
		(start 115.253374 79.02)
		(mid 115.194795 78.878579)
		(end 115.053374 78.82)
		(width 0.162)
		(layer "In2.Cu")
		(net 145)
	)
	(arc
		(start 114.316626 79.416687)
		(mid 114.374234 79.277608)
		(end 114.513313 79.22)
		(width 0.162)
		(layer "In2.Cu")
		(net 145)
	)
	(arc
		(start 114.513313 77.22)
		(mid 114.374234 77.162392)
		(end 114.316626 77.023313)
		(width 0.162)
		(layer "In2.Cu")
		(net 145)
	)
	(arc
		(start 115.253374 74.22)
		(mid 115.194795 74.078579)
		(end 115.053374 74.02)
		(width 0.162)
		(layer "In2.Cu")
		(net 145)
	)
	(arc
		(start 115.053374 75.22)
		(mid 115.194795 75.161421)
		(end 115.253374 75.02)
		(width 0.162)
		(layer "In2.Cu")
		(net 145)
	)
	(arc
		(start 114.71 80.62)
		(mid 114.652392 80.480921)
		(end 114.513313 80.423313)
		(width 0.162)
		(layer "In2.Cu")
		(net 145)
	)
	(arc
		(start 114.316626 73.816687)
		(mid 114.374234 73.677608)
		(end 114.513313 73.62)
		(width 0.162)
		(layer "In2.Cu")
		(net 145)
	)
	(arc
		(start 115.253374 76.62)
		(mid 115.194795 76.478579)
		(end 115.053374 76.42)
		(width 0.162)
		(layer "In2.Cu")
		(net 145)
	)
	(arc
		(start 115.253374 79.82)
		(mid 115.194795 79.678579)
		(end 115.053374 79.62)
		(width 0.162)
		(layer "In2.Cu")
		(net 145)
	)
	(arc
		(start 114.316626 76.216687)
		(mid 114.374234 76.077608)
		(end 114.513313 76.02)
		(width 0.162)
		(layer "In2.Cu")
		(net 145)
	)
	(arc
		(start 114.91 73.22)
		(mid 114.768579 73.161421)
		(end 114.71 73.02)
		(width 0.162)
		(layer "In2.Cu")
		(net 145)
	)
	(arc
		(start 115.253374 75.82)
		(mid 115.194795 75.678579)
		(end 115.053374 75.62)
		(width 0.162)
		(layer "In2.Cu")
		(net 145)
	)
	(arc
		(start 114.513313 80.423313)
		(mid 114.374234 80.365705)
		(end 114.316626 80.226626)
		(width 0.162)
		(layer "In2.Cu")
		(net 145)
	)
	(arc
		(start 114.316626 75.416687)
		(mid 114.374234 75.277608)
		(end 114.513313 75.22)
		(width 0.162)
		(layer "In2.Cu")
		(net 145)
	)
	(arc
		(start 115.053374 78.42)
		(mid 115.194795 78.361421)
		(end 115.253374 78.22)
		(width 0.162)
		(layer "In2.Cu")
		(net 145)
	)
	(arc
		(start 115.053374 76.82)
		(mid 115.194795 76.761421)
		(end 115.253374 76.62)
		(width 0.162)
		(layer "In2.Cu")
		(net 145)
	)
	(arc
		(start 115.053374 80.02)
		(mid 115.194795 79.961421)
		(end 115.253374 79.82)
		(width 0.162)
		(layer "In2.Cu")
		(net 145)
	)
	(arc
		(start 114.513313 78.82)
		(mid 114.374234 78.762392)
		(end 114.316626 78.623313)
		(width 0.162)
		(layer "In2.Cu")
		(net 145)
	)
	(arc
		(start 114.513313 74.82)
		(mid 114.374234 74.762392)
		(end 114.316626 74.623313)
		(width 0.162)
		(layer "In2.Cu")
		(net 145)
	)
	(arc
		(start 115.053374 73.62)
		(mid 115.194795 73.561421)
		(end 115.253374 73.42)
		(width 0.162)
		(layer "In2.Cu")
		(net 145)
	)
	(segment
		(start 126.7 85.9)
		(end 127.1 85.5)
		(width 0.15)
		(layer "F.Cu")
		(net 146)
	)
	(segment
		(start 126.66 61.74)
		(end 127.06 61.34)
		(width 0.182)
		(layer "F.Cu")
		(net 146)
	)
	(via
		(at 127.06 61.34)
		(size 0.45)
		(drill 0.2)
		(layers "F.Cu" "B.Cu")
		(remove_unused_layers yes)
		(keep_end_layers yes)
		(zone_layer_connections)
		(net 146)
	)
	(via
		(at 127.1 85.5)
		(size 0.45)
		(drill 0.2)
		(layers "F.Cu" "B.Cu")
		(remove_unused_layers yes)
		(keep_end_layers yes)
		(zone_layer_connections)
		(net 146)
	)
	(segment
		(start 126.66 60.94)
		(end 127.06 61.34)
		(width 0.15)
		(layer "B.Cu")
		(net 146)
	)
	(segment
		(start 125.46 60.6)
		(end 125.8 60.94)
		(width 0.15)
		(layer "B.Cu")
		(net 146)
	)
	(segment
		(start 124.11 58.1)
		(end 125.46 59.45)
		(width 0.15)
		(layer "B.Cu")
		(net 146)
	)
	(segment
		(start 124.11 57.89)
		(end 124.11 58.1)
		(width 0.15)
		(layer "B.Cu")
		(net 146)
	)
	(segment
		(start 125.8 60.94)
		(end 126.66 60.94)
		(width 0.15)
		(layer "B.Cu")
		(net 146)
	)
	(segment
		(start 125.46 59.45)
		(end 125.46 60.6)
		(width 0.15)
		(layer "B.Cu")
		(net 146)
	)
	(segment
		(start 138.553568 72.26)
		(end 139.646432 72.26)
		(width 0.162)
		(layer "In2.Cu")
		(net 146)
	)
	(segment
		(start 138.553568 71.06)
		(end 139.646432 71.06)
		(width 0.162)
		(layer "In2.Cu")
		(net 146)
	)
	(segment
		(start 131.07 81.555)
		(end 139 73.625)
		(width 0.162)
		(layer "In2.Cu")
		(net 146)
	)
	(segment
		(start 138.553568 70.26)
		(end 139.646432 70.26)
		(width 0.162)
		(layer "In2.Cu")
		(net 146)
	)
	(segment
		(start 127.06 61.301184)
		(end 127.06 61.34)
		(width 0.162)
		(layer "In2.Cu")
		(net 146)
	)
	(segment
		(start 139 69.66)
		(end 139 64.46)
		(width 0.162)
		(layer "In2.Cu")
		(net 146)
	)
	(segment
		(start 138.553568 70.66)
		(end 139.646432 70.66)
		(width 0.162)
		(layer "In2.Cu")
		(net 146)
	)
	(segment
		(start 138.553568 71.46)
		(end 139.646432 71.46)
		(width 0.162)
		(layer "In2.Cu")
		(net 146)
	)
	(segment
		(start 139.646432 69.86)
		(end 139.2 69.86)
		(width 0.162)
		(layer "In2.Cu")
		(net 146)
	)
	(segment
		(start 139 64.46)
		(end 135.04 60.5)
		(width 0.162)
		(layer "In2.Cu")
		(net 146)
	)
	(segment
		(start 128.6 85.2)
		(end 131.07 82.73)
		(width 0.162)
		(layer "In2.Cu")
		(net 146)
	)
	(segment
		(start 139 73.625)
		(end 139 72.86)
		(width 0.162)
		(layer "In2.Cu")
		(net 146)
	)
	(segment
		(start 127.4 85.2)
		(end 128.6 85.2)
		(width 0.162)
		(layer "In2.Cu")
		(net 146)
	)
	(segment
		(start 127.861184 60.5)
		(end 127.06 61.301184)
		(width 0.162)
		(layer "In2.Cu")
		(net 146)
	)
	(segment
		(start 138.553568 71.86)
		(end 139.646432 71.86)
		(width 0.162)
		(layer "In2.Cu")
		(net 146)
	)
	(segment
		(start 131.07 82.73)
		(end 131.07 81.555)
		(width 0.162)
		(layer "In2.Cu")
		(net 146)
	)
	(segment
		(start 127.1 85.5)
		(end 127.4 85.2)
		(width 0.162)
		(layer "In2.Cu")
		(net 146)
	)
	(segment
		(start 135.04 60.5)
		(end 127.861184 60.5)
		(width 0.162)
		(layer "In2.Cu")
		(net 146)
	)
	(segment
		(start 139.2 72.66)
		(end 139.646432 72.66)
		(width 0.162)
		(layer "In2.Cu")
		(net 146)
	)
	(arc
		(start 139.646432 70.26)
		(mid 139.787853 70.201421)
		(end 139.846432 70.06)
		(width 0.162)
		(layer "In2.Cu")
		(net 146)
	)
	(arc
		(start 139 72.86)
		(mid 139.058579 72.718579)
		(end 139.2 72.66)
		(width 0.162)
		(layer "In2.Cu")
		(net 146)
	)
	(arc
		(start 139.846432 72.46)
		(mid 139.787853 72.318579)
		(end 139.646432 72.26)
		(width 0.162)
		(layer "In2.Cu")
		(net 146)
	)
	(arc
		(start 139.646432 72.66)
		(mid 139.787853 72.601421)
		(end 139.846432 72.46)
		(width 0.162)
		(layer "In2.Cu")
		(net 146)
	)
	(arc
		(start 138.353568 70.46)
		(mid 138.412147 70.318579)
		(end 138.553568 70.26)
		(width 0.162)
		(layer "In2.Cu")
		(net 146)
	)
	(arc
		(start 138.553568 70.66)
		(mid 138.412147 70.601421)
		(end 138.353568 70.46)
		(width 0.162)
		(layer "In2.Cu")
		(net 146)
	)
	(arc
		(start 138.553568 72.26)
		(mid 138.412147 72.201421)
		(end 138.353568 72.06)
		(width 0.162)
		(layer "In2.Cu")
		(net 146)
	)
	(arc
		(start 139.2 69.86)
		(mid 139.058579 69.801421)
		(end 139 69.66)
		(width 0.162)
		(layer "In2.Cu")
		(net 146)
	)
	(arc
		(start 139.846432 70.86)
		(mid 139.787853 70.718579)
		(end 139.646432 70.66)
		(width 0.162)
		(layer "In2.Cu")
		(net 146)
	)
	(arc
		(start 139.646432 71.06)
		(mid 139.787853 71.001421)
		(end 139.846432 70.86)
		(width 0.162)
		(layer "In2.Cu")
		(net 146)
	)
	(arc
		(start 138.353568 71.26)
		(mid 138.412147 71.118579)
		(end 138.553568 71.06)
		(width 0.162)
		(layer "In2.Cu")
		(net 146)
	)
	(arc
		(start 139.846432 71.66)
		(mid 139.787853 71.518579)
		(end 139.646432 71.46)
		(width 0.162)
		(layer "In2.Cu")
		(net 146)
	)
	(arc
		(start 138.553568 71.46)
		(mid 138.412147 71.401421)
		(end 138.353568 71.26)
		(width 0.162)
		(layer "In2.Cu")
		(net 146)
	)
	(arc
		(start 138.353568 72.06)
		(mid 138.412147 71.918579)
		(end 138.553568 71.86)
		(width 0.162)
		(layer "In2.Cu")
		(net 146)
	)
	(arc
		(start 139.846432 70.06)
		(mid 139.787853 69.918579)
		(end 139.646432 69.86)
		(width 0.162)
		(layer "In2.Cu")
		(net 146)
	)
	(arc
		(start 139.646432 71.86)
		(mid 139.787853 71.801421)
		(end 139.846432 71.66)
		(width 0.162)
		(layer "In2.Cu")
		(net 146)
	)
	(segment
		(start 125.86 61.74)
		(end 126.26 61.34)
		(width 0.182)
		(layer "F.Cu")
		(net 147)
	)
	(segment
		(start 127.5 85.9)
		(end 127.9 86.3)
		(width 0.15)
		(layer "F.Cu")
		(net 147)
	)
	(via
		(at 126.26 61.34)
		(size 0.45)
		(drill 0.2)
		(layers "F.Cu" "B.Cu")
		(remove_unused_layers yes)
		(keep_end_layers yes)
		(zone_layer_connections)
		(net 147)
	)
	(via
		(at 127.9 86.3)
		(size 0.45)
		(drill 0.2)
		(layers "F.Cu" "B.Cu")
		(remove_unused_layers yes)
		(keep_end_layers yes)
		(zone_layer_connections)
		(net 147)
	)
	(segment
		(start 126.26 61.34)
		(end 125.79 61.34)
		(width 0.15)
		(layer "B.Cu")
		(net 147)
	)
	(segment
		(start 125.04 60.59)
		(end 125.04 59.4)
		(width 0.15)
		(layer "B.Cu")
		(net 147)
	)
	(segment
		(start 125.04 59.4)
		(end 124.13 58.49)
		(width 0.15)
		(layer "B.Cu")
		(net 147)
	)
	(segment
		(start 123.56 58.21)
		(end 123.56 57.89)
		(width 0.15)
		(layer "B.Cu")
		(net 147)
	)
	(segment
		(start 124.13 58.49)
		(end 123.84 58.49)
		(width 0.15)
		(layer "B.Cu")
		(net 147)
	)
	(segment
		(start 125.79 61.34)
		(end 125.04 60.59)
		(width 0.15)
		(layer "B.Cu")
		(net 147)
	)
	(segment
		(start 123.84 58.49)
		(end 123.56 58.21)
		(width 0.15)
		(layer "B.Cu")
		(net 147)
	)
	(segment
		(start 127.2594 58.939)
		(end 126.8594 59.339)
		(width 0.162)
		(layer "In2.Cu")
		(net 147)
	)
	(segment
		(start 140.19 75.21958)
		(end 140.19 74.4)
		(width 0.162)
		(layer "In2.Cu")
		(net 147)
	)
	(segment
		(start 140.645295 73.4)
		(end 140.39 73.4)
		(width 0.162)
		(layer "In2.Cu")
		(net 147)
	)
	(segment
		(start 128.2261 58.939)
		(end 127.2594 58.939)
		(width 0.162)
		(layer "In2.Cu")
		(net 147)
	)
	(segment
		(start 139.734705 73.8)
		(end 140.645295 73.8)
		(width 0.162)
		(layer "In2.Cu")
		(net 147)
	)
	(segment
		(start 125.859 60.939)
		(end 126.26 61.34)
		(width 0.162)
		(layer "In2.Cu")
		(net 147)
	)
	(segment
		(start 140.19 64.08)
		(end 136.11 60)
		(width 0.162)
		(layer "In2.Cu")
		(net 147)
	)
	(segment
		(start 140.19 73.2)
		(end 140.19 64.08)
		(width 0.162)
		(layer "In2.Cu")
		(net 147)
	)
	(segment
		(start 137.357831 78.051749)
		(end 140.19 75.21958)
		(width 0.162)
		(layer "In2.Cu")
		(net 147)
	)
	(segment
		(start 125.859 59.5739)
		(end 125.859 60.939)
		(width 0.162)
		(layer "In2.Cu")
		(net 147)
	)
	(segment
		(start 136.11 60)
		(end 129.2871 60)
		(width 0.162)
		(layer "In2.Cu")
		(net 147)
	)
	(segment
		(start 129.2871 60)
		(end 128.2261 58.939)
		(width 0.162)
		(layer "In2.Cu")
		(net 147)
	)
	(segment
		(start 139.99 74.2)
		(end 139.734705 74.2)
		(width 0.162)
		(layer "In2.Cu")
		(net 147)
	)
	(segment
		(start 131.68 82.52)
		(end 131.68 82.07)
		(width 0.162)
		(layer "In2.Cu")
		(net 147)
	)
	(segment
		(start 126.8594 59.339)
		(end 126.0939 59.339)
		(width 0.162)
		(layer "In2.Cu")
		(net 147)
	)
	(segment
		(start 131.68 82.07)
		(end 135.698251 78.051749)
		(width 0.162)
		(layer "In2.Cu")
		(net 147)
	)
	(segment
		(start 126.0939 59.339)
		(end 125.859 59.5739)
		(width 0.162)
		(layer "In2.Cu")
		(net 147)
	)
	(segment
		(start 127.9 86.3)
		(end 131.68 82.52)
		(width 0.162)
		(layer "In2.Cu")
		(net 147)
	)
	(segment
		(start 135.698251 78.051749)
		(end 137.357831 78.051749)
		(width 0.162)
		(layer "In2.Cu")
		(net 147)
	)
	(arc
		(start 140.645295 73.8)
		(mid 140.786716 73.741421)
		(end 140.845295 73.6)
		(width 0.162)
		(layer "In2.Cu")
		(net 147)
	)
	(arc
		(start 140.39 73.4)
		(mid 140.248579 73.341421)
		(end 140.19 73.2)
		(width 0.162)
		(layer "In2.Cu")
		(net 147)
	)
	(arc
		(start 139.734705 74.2)
		(mid 139.593284 74.141421)
		(end 139.534705 74)
		(width 0.162)
		(layer "In2.Cu")
		(net 147)
	)
	(arc
		(start 140.845295 73.6)
		(mid 140.786716 73.458579)
		(end 140.645295 73.4)
		(width 0.162)
		(layer "In2.Cu")
		(net 147)
	)
	(arc
		(start 139.534705 74)
		(mid 139.593284 73.858579)
		(end 139.734705 73.8)
		(width 0.162)
		(layer "In2.Cu")
		(net 147)
	)
	(arc
		(start 140.19 74.4)
		(mid 140.131421 74.258579)
		(end 139.99 74.2)
		(width 0.162)
		(layer "In2.Cu")
		(net 147)
	)
	(segment
		(start 122.7 87.5)
		(end 122.3 87.1)
		(width 0.15)
		(layer "F.Cu")
		(net 148)
	)
	(segment
		(start 121.46 59.74)
		(end 121.86 60.14)
		(width 0.182)
		(layer "F.Cu")
		(net 148)
	)
	(via
		(at 122.3 87.1)
		(size 0.45)
		(drill 0.2)
		(layers "F.Cu" "B.Cu")
		(remove_unused_layers yes)
		(keep_end_layers yes)
		(zone_layer_connections)
		(net 148)
	)
	(via
		(at 121.46 59.74)
		(size 0.45)
		(drill 0.2)
		(layers "F.Cu" "B.Cu")
		(remove_unused_layers yes)
		(keep_end_layers yes)
		(zone_layer_connections)
		(net 148)
	)
	(segment
		(start 121.9 59.23)
		(end 121.9 58.72)
		(width 0.2)
		(layer "B.Cu")
		(net 148)
	)
	(segment
		(start 121.9 58.72)
		(end 121.62 58.44)
		(width 0.2)
		(layer "B.Cu")
		(net 148)
	)
	(segment
		(start 121.46 59.74)
		(end 121.46 59.67)
		(width 0.2)
		(layer "B.Cu")
		(net 148)
	)
	(segment
		(start 121.52 58.44)
		(end 121.31 58.23)
		(width 0.2)
		(layer "B.Cu")
		(net 148)
	)
	(segment
		(start 121.46 59.67)
		(end 121.9 59.23)
		(width 0.2)
		(layer "B.Cu")
		(net 148)
	)
	(segment
		(start 121.31 58.23)
		(end 121.31 57.89)
		(width 0.2)
		(layer "B.Cu")
		(net 148)
	)
	(segment
		(start 121.62 58.44)
		(end 121.52 58.44)
		(width 0.2)
		(layer "B.Cu")
		(net 148)
	)
	(segment
		(start 114.43645 85.770707)
		(end 114.563798 85.643358)
		(width 0.162)
		(layer "In2.Cu")
		(net 148)
	)
	(segment
		(start 114.436449 85.770707)
		(end 114.43645 85.770707)
		(width 0.162)
		(layer "In2.Cu")
		(net 148)
	)
	(segment
		(start 116.6839 88.301)
		(end 114.43645 86.05355)
		(width 0.162)
		(layer "In2.Cu")
		(net 148)
	)
	(segment
		(start 114.563798 85.360516)
		(end 114.563798 85.360515)
		(width 0.162)
		(layer "In2.Cu")
		(net 148)
	)
	(segment
		(start 114.280955 85.360514)
		(end 114.280955 85.360515)
		(width 0.162)
		(layer "In2.Cu")
		(net 148)
	)
	(segment
		(start 121.901 87.499)
		(end 122.3 87.1)
		(width 0.15)
		(layer "In2.Cu")
		(net 148)
	)
	(segment
		(start 113.99811 84.794827)
		(end 113.998109 84.794827)
		(width 0.162)
		(layer "In2.Cu")
		(net 148)
	)
	(segment
		(start 112.506 84.1231)
		(end 112.506 61.954)
		(width 0.162)
		(layer "In2.Cu")
		(net 148)
	)
	(segment
		(start 113.305074 84.922175)
		(end 112.506 84.1231)
		(width 0.162)
		(layer "In2.Cu")
		(net 148)
	)
	(segment
		(start 121.6661 88.301)
		(end 116.6839 88.301)
		(width 0.162)
		(layer "In2.Cu")
		(net 148)
	)
	(segment
		(start 113.305075 84.922175)
		(end 113.305074 84.922175)
		(width 0.162)
		(layer "In2.Cu")
		(net 148)
	)
	(segment
		(start 120.8 58.9)
		(end 121.46 59.56)
		(width 0.162)
		(layer "In2.Cu")
		(net 148)
	)
	(segment
		(start 115.56 58.9)
		(end 120.8 58.9)
		(width 0.162)
		(layer "In2.Cu")
		(net 148)
	)
	(segment
		(start 121.46 59.56)
		(end 121.46 59.74)
		(width 0.162)
		(layer "In2.Cu")
		(net 148)
	)
	(segment
		(start 113.662061 85.74599)
		(end 113.612632 85.696561)
		(width 0.162)
		(layer "In2.Cu")
		(net 148)
	)
	(segment
		(start 112.506 61.954)
		(end 115.56 58.9)
		(width 0.162)
		(layer "In2.Cu")
		(net 148)
	)
	(segment
		(start 113.612632 85.463147)
		(end 113.998109 85.07767)
		(width 0.162)
		(layer "In2.Cu")
		(net 148)
	)
	(segment
		(start 121.901 88.0661)
		(end 121.901 87.499)
		(width 0.15)
		(layer "In2.Cu")
		(net 148)
	)
	(segment
		(start 114.280955 85.360515)
		(end 113.895475 85.74599)
		(width 0.162)
		(layer "In2.Cu")
		(net 148)
	)
	(segment
		(start 113.715266 84.794827)
		(end 113.587917 84.922175)
		(width 0.162)
		(layer "In2.Cu")
		(net 148)
	)
	(segment
		(start 121.901 88.0661)
		(end 121.6661 88.301)
		(width 0.162)
		(layer "In2.Cu")
		(net 148)
	)
	(segment
		(start 113.715266 84.794826)
		(end 113.715266 84.794827)
		(width 0.162)
		(layer "In2.Cu")
		(net 148)
	)
	(segment
		(start 113.612633 85.463146)
		(end 113.612632 85.463147)
		(width 0.162)
		(layer "In2.Cu")
		(net 148)
	)
	(arc
		(start 114.43645 86.05355)
		(mid 114.377871 85.912129)
		(end 114.436449 85.770707)
		(width 0.162)
		(layer "In2.Cu")
		(net 148)
	)
	(arc
		(start 113.612632 85.696561)
		(mid 113.564292 85.579854)
		(end 113.612633 85.463146)
		(width 0.162)
		(layer "In2.Cu")
		(net 148)
	)
	(arc
		(start 114.563798 85.360515)
		(mid 114.422377 85.301936)
		(end 114.280955 85.360514)
		(width 0.162)
		(layer "In2.Cu")
		(net 148)
	)
	(arc
		(start 113.998109 85.07767)
		(mid 114.056688 84.936249)
		(end 113.99811 84.794827)
		(width 0.162)
		(layer "In2.Cu")
		(net 148)
	)
	(arc
		(start 113.998109 84.794827)
		(mid 113.856688 84.736248)
		(end 113.715266 84.794826)
		(width 0.162)
		(layer "In2.Cu")
		(net 148)
	)
	(arc
		(start 114.563798 85.643358)
		(mid 114.622376 85.501937)
		(end 114.563798 85.360516)
		(width 0.162)
		(layer "In2.Cu")
		(net 148)
	)
	(arc
		(start 113.895475 85.74599)
		(mid 113.778769 85.794333)
		(end 113.662061 85.74599)
		(width 0.162)
		(layer "In2.Cu")
		(net 148)
	)
	(arc
		(start 113.587917 84.922175)
		(mid 113.446496 84.980753)
		(end 113.305075 84.922175)
		(width 0.162)
		(layer "In2.Cu")
		(net 148)
	)
	(segment
		(start 125.499496 88.7055)
		(end 125.499496 88.700504)
		(width 0.15)
		(layer "F.Cu")
		(net 149)
	)
	(segment
		(start 125.499496 88.700504)
		(end 125.9 88.3)
		(width 0.15)
		(layer "F.Cu")
		(net 149)
	)
	(segment
		(start 126.66 60.94)
		(end 127.06 60.54)
		(width 0.182)
		(layer "F.Cu")
		(net 149)
	)
	(via
		(at 127.06 60.54)
		(size 0.45)
		(drill 0.2)
		(layers "F.Cu" "B.Cu")
		(remove_unused_layers yes)
		(keep_end_layers yes)
		(zone_layer_connections)
		(net 149)
	)
	(via
		(at 125.499496 88.7055)
		(size 0.45)
		(drill 0.2)
		(layers "F.Cu" "B.Cu")
		(remove_unused_layers yes)
		(keep_end_layers yes)
		(zone_layer_connections)
		(net 149)
	)
	(segment
		(start 127.86 57.89)
		(end 127.86 58.73)
		(width 0.15)
		(layer "B.Cu")
		(net 149)
	)
	(segment
		(start 127.45 59.14)
		(end 127.45 60.15)
		(width 0.15)
		(layer "B.Cu")
		(net 149)
	)
	(segment
		(start 127.86 58.73)
		(end 127.45 59.14)
		(width 0.15)
		(layer "B.Cu")
		(net 149)
	)
	(segment
		(start 127.45 60.15)
		(end 127.06 60.54)
		(width 0.15)
		(layer "B.Cu")
		(net 149)
	)
	(segment
		(start 125.499496 88.7055)
		(end 124.946885 88.7055)
		(width 0.15)
		(layer "In4.Cu")
		(net 149)
	)
	(segment
		(start 132.59012 64.405659)
		(end 132.590122 64.40566)
		(width 0.162)
		(layer "In4.Cu")
		(net 149)
	)
	(segment
		(start 124.145 87.495)
		(end 123.695 87.495)
		(width 0.15)
		(layer "In4.Cu")
		(net 149)
	)
	(segment
		(start 126.54 75.88)
		(end 131.97 75.88)
		(width 0.162)
		(layer "In4.Cu")
		(net 149)
	)
	(segment
		(start 133.77504 62.949337)
		(end 133.763599 62.937896)
		(width 0.162)
		(layer "In4.Cu")
		(net 149)
	)
	(segment
		(start 131.97 75.88)
		(end 134.52 73.33)
		(width 0.162)
		(layer "In4.Cu")
		(net 149)
	)
	(segment
		(start 134.52 73.33)
		(end 134.52 64.2371)
		(width 0.162)
		(layer "In4.Cu")
		(net 149)
	)
	(segment
		(start 124.295 87.645)
		(end 124.145 87.495)
		(width 0.15)
		(layer "In4.Cu")
		(net 149)
	)
	(segment
		(start 123.5 86.251)
		(end 123.499 86.25)
		(width 0.15)
		(layer "In4.Cu")
		(net 149)
	)
	(segment
		(start 133.492198 62.937895)
		(end 133.492197 62.937896)
		(width 0.162)
		(layer "In4.Cu")
		(net 149)
	)
	(segment
		(start 132.932231 62.649331)
		(end 131.2029 60.92)
		(width 0.162)
		(layer "In4.Cu")
		(net 149)
	)
	(segment
		(start 134.063608 63.509304)
		(end 134.063607 63.509305)
		(width 0.162)
		(layer "In4.Cu")
		(net 149)
	)
	(segment
		(start 132.554764 63.309642)
		(end 132.93223 62.932173)
		(width 0.162)
		(layer "In4.Cu")
		(net 149)
	)
	(segment
		(start 129.28 60.5)
		(end 127.1 60.5)
		(width 0.162)
		(layer "In4.Cu")
		(net 149)
	)
	(segment
		(start 132.554762 63.592483)
		(end 132.554763 63.592484)
		(width 0.162)
		(layer "In4.Cu")
		(net 149)
	)
	(segment
		(start 127.1 60.5)
		(end 127.06 60.54)
		(width 0.162)
		(layer "In4.Cu")
		(net 149)
	)
	(segment
		(start 134.34645 63.520746)
		(end 134.335009 63.509305)
		(width 0.162)
		(layer "In4.Cu")
		(net 149)
	)
	(segment
		(start 129.7 60.92)
		(end 129.28 60.5)
		(width 0.162)
		(layer "In4.Cu")
		(net 149)
	)
	(segment
		(start 132.59012 64.688501)
		(end 132.590121 64.688502)
		(width 0.162)
		(layer "In4.Cu")
		(net 149)
	)
	(segment
		(start 134.063607 63.509305)
		(end 133.927906 63.645005)
		(width 0.162)
		(layer "In4.Cu")
		(net 149)
	)
	(segment
		(start 123.695 87.495)
		(end 123.5 87.3)
		(width 0.15)
		(layer "In4.Cu")
		(net 149)
	)
	(segment
		(start 132.932231 62.64933)
		(end 132.932231 62.649331)
		(width 0.162)
		(layer "In4.Cu")
		(net 149)
	)
	(segment
		(start 133.922184 63.639284)
		(end 132.872963 64.688502)
		(width 0.162)
		(layer "In4.Cu")
		(net 149)
	)
	(segment
		(start 124.946885 88.7055)
		(end 124.295 88.053615)
		(width 0.15)
		(layer "In4.Cu")
		(net 149)
	)
	(segment
		(start 131.2029 60.92)
		(end 129.7 60.92)
		(width 0.162)
		(layer "In4.Cu")
		(net 149)
	)
	(segment
		(start 133.492197 62.937896)
		(end 132.837605 63.592484)
		(width 0.162)
		(layer "In4.Cu")
		(net 149)
	)
	(segment
		(start 123.499 78.921)
		(end 126.54 75.88)
		(width 0.162)
		(layer "In4.Cu")
		(net 149)
	)
	(segment
		(start 123.499 86.25)
		(end 123.499 78.921)
		(width 0.162)
		(layer "In4.Cu")
		(net 149)
	)
	(segment
		(start 132.590122 64.40566)
		(end 133.77504 63.220739)
		(width 0.162)
		(layer "In4.Cu")
		(net 149)
	)
	(segment
		(start 134.52 64.2371)
		(end 134.34645 64.06355)
		(width 0.162)
		(layer "In4.Cu")
		(net 149)
	)
	(segment
		(start 134.346449 63.792149)
		(end 134.34645 63.792148)
		(width 0.162)
		(layer "In4.Cu")
		(net 149)
	)
	(segment
		(start 123.5 87.3)
		(end 123.5 86.251)
		(width 0.15)
		(layer "In4.Cu")
		(net 149)
	)
	(segment
		(start 133.775041 62.949338)
		(end 133.77504 62.949337)
		(width 0.162)
		(layer "In4.Cu")
		(net 149)
	)
	(segment
		(start 133.927906 63.645005)
		(end 133.922184 63.639284)
		(width 0.162)
		(layer "In4.Cu")
		(net 149)
	)
	(segment
		(start 132.554762 63.309641)
		(end 132.554764 63.309642)
		(width 0.162)
		(layer "In4.Cu")
		(net 149)
	)
	(segment
		(start 124.295 88.053615)
		(end 124.295 87.645)
		(width 0.15)
		(layer "In4.Cu")
		(net 149)
	)
	(arc
		(start 132.554763 63.592484)
		(mid 132.496184 63.451063)
		(end 132.554762 63.309641)
		(width 0.162)
		(layer "In4.Cu")
		(net 149)
	)
	(arc
		(start 134.34645 64.06355)
		(mid 134.290241 63.92785)
		(end 134.346449 63.792149)
		(width 0.162)
		(layer "In4.Cu")
		(net 149)
	)
	(arc
		(start 132.872963 64.688502)
		(mid 132.731541 64.74708)
		(end 132.59012 64.688501)
		(width 0.162)
		(layer "In4.Cu")
		(net 149)
	)
	(arc
		(start 134.34645 63.792148)
		(mid 134.402659 63.656447)
		(end 134.34645 63.520746)
		(width 0.162)
		(layer "In4.Cu")
		(net 149)
	)
	(arc
		(start 132.590121 64.688502)
		(mid 132.531542 64.547081)
		(end 132.59012 64.405659)
		(width 0.162)
		(layer "In4.Cu")
		(net 149)
	)
	(arc
		(start 134.335009 63.509305)
		(mid 134.199309 63.453096)
		(end 134.063608 63.509304)
		(width 0.162)
		(layer "In4.Cu")
		(net 149)
	)
	(arc
		(start 132.837605 63.592484)
		(mid 132.696183 63.651062)
		(end 132.554762 63.592483)
		(width 0.162)
		(layer "In4.Cu")
		(net 149)
	)
	(arc
		(start 133.77504 63.220739)
		(mid 133.831249 63.085039)
		(end 133.775041 62.949338)
		(width 0.162)
		(layer "In4.Cu")
		(net 149)
	)
	(arc
		(start 133.763599 62.937896)
		(mid 133.627899 62.881687)
		(end 133.492198 62.937895)
		(width 0.162)
		(layer "In4.Cu")
		(net 149)
	)
	(arc
		(start 132.93223 62.932173)
		(mid 132.990809 62.790752)
		(end 132.932231 62.64933)
		(width 0.162)
		(layer "In4.Cu")
		(net 149)
	)
	(segment
		(start 126.66 60.14)
		(end 127.05 59.75)
		(width 0.182)
		(layer "F.Cu")
		(net 150)
	)
	(segment
		(start 125.1 88.3)
		(end 125.5 87.9)
		(width 0.15)
		(layer "F.Cu")
		(net 150)
	)
	(segment
		(start 127.07 59.75)
		(end 127.07 59.7355)
		(width 0.182)
		(layer "F.Cu")
		(net 150)
	)
	(segment
		(start 127.05 59.75)
		(end 127.07 59.75)
		(width 0.182)
		(layer "F.Cu")
		(net 150)
	)
	(segment
		(start 125.5 87.9)
		(end 125.5 87.876766)
		(width 0.15)
		(layer "F.Cu")
		(net 150)
	)
	(segment
		(start 127.07 59.7355)
		(end 127.05 59.7155)
		(width 0.182)
		(layer "F.Cu")
		(net 150)
	)
	(via
		(at 127.05 59.7155)
		(size 0.45)
		(drill 0.2)
		(layers "F.Cu" "B.Cu")
		(remove_unused_layers yes)
		(keep_end_layers yes)
		(zone_layer_connections)
		(net 150)
	)
	(via
		(at 125.5 87.876766)
		(size 0.45)
		(drill 0.2)
		(layers "F.Cu" "B.Cu")
		(remove_unused_layers yes)
		(keep_end_layers yes)
		(zone_layer_connections)
		(net 150)
	)
	(segment
		(start 127.05 59.7155)
		(end 127.05 59.06)
		(width 0.15)
		(layer "B.Cu")
		(net 150)
	)
	(segment
		(start 127.31 58.8)
		(end 127.31 57.89)
		(width 0.15)
		(layer "B.Cu")
		(net 150)
	)
	(segment
		(start 127.05 59.06)
		(end 127.31 58.8)
		(width 0.15)
		(layer "B.Cu")
		(net 150)
	)
	(segment
		(start 135.771902 68.05)
		(end 136.268098 68.05)
		(width 0.162)
		(layer "In4.Cu")
		(net 150)
	)
	(segment
		(start 136.268098 66.05)
		(end 136.22 66.05)
		(width 0.162)
		(layer "In4.Cu")
		(net 150)
	)
	(segment
		(start 130.34 58.86)
		(end 127.94 58.86)
		(width 0.162)
		(layer "In4.Cu")
		(net 150)
	)
	(segment
		(start 136.02 63.28)
		(end 133.94 61.2)
		(width 0.162)
		(layer "In4.Cu")
		(net 150)
	)
	(segment
		(start 133.94 61.2)
		(end 132.68 61.2)
		(width 0.162)
		(layer "In4.Cu")
		(net 150)
	)
	(segment
		(start 124.783812 80.136188)
		(end 127.42 77.5)
		(width 0.162)
		(layer "In4.Cu")
		(net 150)
	)
	(segment
		(start 125.099 85.45)
		(end 125.099 85.299)
		(width 0.162)
		(layer "In4.Cu")
		(net 150)
	)
	(segment
		(start 125.099 85.299)
		(end 124.783812 84.983812)
		(width 0.162)
		(layer "In4.Cu")
		(net 150)
	)
	(segment
		(start 135.771902 67.65)
		(end 136.268098 67.65)
		(width 0.162)
		(layer "In4.Cu")
		(net 150)
	)
	(segment
		(start 135.771902 66.85)
		(end 136.268098 66.85)
		(width 0.162)
		(layer "In4.Cu")
		(net 150)
	)
	(segment
		(start 136.22 68.45)
		(end 135.771902 68.45)
		(width 0.162)
		(layer "In4.Cu")
		(net 150)
	)
	(segment
		(start 135.771902 66.45)
		(end 136.268098 66.45)
		(width 0.162)
		(layer "In4.Cu")
		(net 150)
	)
	(segment
		(start 135.771902 67.25)
		(end 136.268098 67.25)
		(width 0.162)
		(layer "In4.Cu")
		(net 150)
	)
	(segment
		(start 136.268098 68.45)
		(end 136.22 68.45)
		(width 0.162)
		(layer "In4.Cu")
		(net 150)
	)
	(segment
		(start 125.095 85.454)
		(end 125.099 85.45)
		(width 0.15)
		(layer "In4.Cu")
		(net 150)
	)
	(segment
		(start 136.02 65.85)
		(end 136.02 63.28)
		(width 0.162)
		(layer "In4.Cu")
		(net 150)
	)
	(segment
		(start 127.42 77.5)
		(end 132.42 77.5)
		(width 0.162)
		(layer "In4.Cu")
		(net 150)
	)
	(segment
		(start 136.02 73.9)
		(end 136.02 69.05)
		(width 0.162)
		(layer "In4.Cu")
		(net 150)
	)
	(segment
		(start 124.783812 84.983812)
		(end 124.783812 80.136188)
		(width 0.162)
		(layer "In4.Cu")
		(net 150)
	)
	(segment
		(start 125.5 87.688383)
		(end 125.095 87.283383)
		(width 0.15)
		(layer "In4.Cu")
		(net 150)
	)
	(segment
		(start 125.095 87.283383)
		(end 125.095 85.454)
		(width 0.15)
		(layer "In4.Cu")
		(net 150)
	)
	(segment
		(start 136.22 68.85)
		(end 136.268098 68.85)
		(width 0.162)
		(layer "In4.Cu")
		(net 150)
	)
	(segment
		(start 127.94 58.86)
		(end 127.06 59.74)
		(width 0.162)
		(layer "In4.Cu")
		(net 150)
	)
	(segment
		(start 125.5 87.876766)
		(end 125.5 87.688383)
		(width 0.15)
		(layer "In4.Cu")
		(net 150)
	)
	(segment
		(start 132.68 61.2)
		(end 130.34 58.86)
		(width 0.162)
		(layer "In4.Cu")
		(net 150)
	)
	(segment
		(start 132.42 77.5)
		(end 136.02 73.9)
		(width 0.162)
		(layer "In4.Cu")
		(net 150)
	)
	(arc
		(start 136.468098 67.85)
		(mid 136.409519 67.708579)
		(end 136.268098 67.65)
		(width 0.162)
		(layer "In4.Cu")
		(net 150)
	)
	(arc
		(start 136.02 69.05)
		(mid 136.078579 68.908579)
		(end 136.22 68.85)
		(width 0.162)
		(layer "In4.Cu")
		(net 150)
	)
	(arc
		(start 136.268098 67.25)
		(mid 136.409519 67.191421)
		(end 136.468098 67.05)
		(width 0.162)
		(layer "In4.Cu")
		(net 150)
	)
	(arc
		(start 135.571902 68.25)
		(mid 135.630481 68.108579)
		(end 135.771902 68.05)
		(width 0.162)
		(layer "In4.Cu")
		(net 150)
	)
	(arc
		(start 136.468098 66.25)
		(mid 136.409519 66.108579)
		(end 136.268098 66.05)
		(width 0.162)
		(layer "In4.Cu")
		(net 150)
	)
	(arc
		(start 135.771902 67.65)
		(mid 135.630481 67.591421)
		(end 135.571902 67.45)
		(width 0.162)
		(layer "In4.Cu")
		(net 150)
	)
	(arc
		(start 135.571902 66.65)
		(mid 135.630481 66.508579)
		(end 135.771902 66.45)
		(width 0.162)
		(layer "In4.Cu")
		(net 150)
	)
	(arc
		(start 136.268098 68.05)
		(mid 136.409519 67.991421)
		(end 136.468098 67.85)
		(width 0.162)
		(layer "In4.Cu")
		(net 150)
	)
	(arc
		(start 136.22 66.05)
		(mid 136.078579 65.991421)
		(end 136.02 65.85)
		(width 0.162)
		(layer "In4.Cu")
		(net 150)
	)
	(arc
		(start 136.268098 68.85)
		(mid 136.409519 68.791421)
		(end 136.468098 68.65)
		(width 0.162)
		(layer "In4.Cu")
		(net 150)
	)
	(arc
		(start 135.771902 68.45)
		(mid 135.630481 68.391421)
		(end 135.571902 68.25)
		(width 0.162)
		(layer "In4.Cu")
		(net 150)
	)
	(arc
		(start 135.771902 66.85)
		(mid 135.630481 66.791421)
		(end 135.571902 66.65)
		(width 0.162)
		(layer "In4.Cu")
		(net 150)
	)
	(arc
		(start 135.571902 67.45)
		(mid 135.630481 67.308579)
		(end 135.771902 67.25)
		(width 0.162)
		(layer "In4.Cu")
		(net 150)
	)
	(arc
		(start 136.468098 68.65)
		(mid 136.409519 68.508579)
		(end 136.268098 68.45)
		(width 0.162)
		(layer "In4.Cu")
		(net 150)
	)
	(arc
		(start 136.268098 66.45)
		(mid 136.409519 66.391421)
		(end 136.468098 66.25)
		(width 0.162)
		(layer "In4.Cu")
		(net 150)
	)
	(arc
		(start 136.468098 67.05)
		(mid 136.409519 66.908579)
		(end 136.268098 66.85)
		(width 0.162)
		(layer "In4.Cu")
		(net 150)
	)
	(segment
		(start 121.46 60.54)
		(end 121.86 60.94)
		(width 0.182)
		(layer "F.Cu")
		(net 151)
	)
	(segment
		(start 120.3 87.5)
		(end 119.9 87.1)
		(width 0.2)
		(layer "F.Cu")
		(net 151)
	)
	(segment
		(start 119.9 87.1)
		(end 119.87 87.1)
		(width 0.2)
		(layer "F.Cu")
		(net 151)
	)
	(via
		(at 119.87 87.1)
		(size 0.45)
		(drill 0.1)
		(layers "F.Cu" "B.Cu")
		(net 151)
	)
	(via
		(at 121.46 60.54)
		(size 0.45)
		(drill 0.2)
		(layers "F.Cu" "B.Cu")
		(remove_unused_layers yes)
		(keep_end_layers yes)
		(zone_layer_connections)
		(net 151)
	)
	(segment
		(start 122.61 58.53)
		(end 122.36 58.28)
		(width 0.15)
		(layer "B.Cu")
		(net 151)
	)
	(segment
		(start 122.7 59.33)
		(end 122.61 59.24)
		(width 0.15)
		(layer "B.Cu")
		(net 151)
	)
	(segment
		(start 121.86 60.14)
		(end 122.45 60.14)
		(width 0.15)
		(layer "B.Cu")
		(net 151)
	)
	(segment
		(start 122.61 59.24)
		(end 122.61 58.53)
		(width 0.15)
		(layer "B.Cu")
		(net 151)
	)
	(segment
		(start 121.46 60.54)
		(end 121.86 60.14)
		(width 0.15)
		(layer "B.Cu")
		(net 151)
	)
	(segment
		(start 122.45 60.14)
		(end 122.7 59.89)
		(width 0.15)
		(layer "B.Cu")
		(net 151)
	)
	(segment
		(start 122.36 58.28)
		(end 122.36 57.89)
		(width 0.15)
		(layer "B.Cu")
		(net 151)
	)
	(segment
		(start 122.7 59.89)
		(end 122.7 59.33)
		(width 0.15)
		(layer "B.Cu")
		(net 151)
	)
	(segment
		(start 117.912157 86.624999)
		(end 117.912156 86.624999)
		(width 0.162)
		(layer "In2.Cu")
		(net 151)
	)
	(segment
		(start 116.656416 86.183677)
		(end 116.656418 86.183678)
		(width 0.162)
		(layer "In2.Cu")
		(net 151)
	)
	(segment
		(start 116.656418 86.183678)
		(end 117.541544 85.298549)
		(width 0.162)
		(layer "In2.Cu")
		(net 151)
	)
	(segment
		(start 115.649405 84.079406)
		(end 114.03 82.46)
		(width 0.162)
		(layer "In2.Cu")
		(net 151)
	)
	(segment
		(start 119.87 87.1)
		(end 118.67 87.1)
		(width 0.162)
		(layer "In2.Cu")
		(net 151)
	)
	(segment
		(start 118.107233 85.581394)
		(end 118.107232 85.581394)
		(width 0.162)
		(layer "In2.Cu")
		(net 151)
	)
	(segment
		(start 116.885 60.655)
		(end 120.15 60.655)
		(width 0.162)
		(layer "In2.Cu")
		(net 151)
	)
	(segment
		(start 114.03 82.46)
		(end 114.03 63.51)
		(width 0.162)
		(layer "In2.Cu")
		(net 151)
	)
	(segment
		(start 115.649406 84.079406)
		(end 115.649405 84.079406)
		(width 0.162)
		(layer "In2.Cu")
		(net 151)
	)
	(segment
		(start 121.14 60.54)
		(end 120.9 60.3)
		(width 0.15)
		(layer "In2.Cu")
		(net 151)
	)
	(segment
		(start 117.912156 86.624999)
		(end 117.504948 87.032208)
		(width 0.162)
		(layer "In2.Cu")
		(net 151)
	)
	(segment
		(start 117.222105 86.749365)
		(end 117.770734 86.200733)
		(width 0.162)
		(layer "In2.Cu")
		(net 151)
	)
	(segment
		(start 116.09073 85.61799)
		(end 116.975856 84.732861)
		(width 0.162)
		(layer "In2.Cu")
		(net 151)
	)
	(segment
		(start 117.222103 86.749364)
		(end 117.222105 86.749365)
		(width 0.162)
		(layer "In2.Cu")
		(net 151)
	)
	(segment
		(start 116.975857 84.450018)
		(end 116.975856 84.450018)
		(width 0.162)
		(layer "In2.Cu")
		(net 151)
	)
	(segment
		(start 117.824389 85.581394)
		(end 116.939259 86.46652)
		(width 0.162)
		(layer "In2.Cu")
		(net 151)
	)
	(segment
		(start 120.15 60.655)
		(end 120.3025 60.5025)
		(width 0.162)
		(layer "In2.Cu")
		(net 151)
	)
	(segment
		(start 117.258701 85.015706)
		(end 116.373571 85.900832)
		(width 0.162)
		(layer "In2.Cu")
		(net 151)
	)
	(segment
		(start 116.090728 85.617989)
		(end 116.09073 85.61799)
		(width 0.162)
		(layer "In2.Cu")
		(net 151)
	)
	(segment
		(start 116.127325 83.884329)
		(end 116.127325 83.88433)
		(width 0.162)
		(layer "In2.Cu")
		(net 151)
	)
	(segment
		(start 115.525042 85.052302)
		(end 116.410168 84.167173)
		(width 0.162)
		(layer "In2.Cu")
		(net 151)
	)
	(segment
		(start 116.693013 84.450018)
		(end 115.807883 85.335144)
		(width 0.162)
		(layer "In2.Cu")
		(net 151)
	)
	(segment
		(start 116.090728 85.900831)
		(end 116.090729 85.900832)
		(width 0.162)
		(layer "In2.Cu")
		(net 151)
	)
	(segment
		(start 116.410169 83.88433)
		(end 116.410168 83.88433)
		(width 0.162)
		(layer "In2.Cu")
		(net 151)
	)
	(segment
		(start 115.52504 85.335143)
		(end 115.525041 85.335144)
		(width 0.162)
		(layer "In2.Cu")
		(net 151)
	)
	(segment
		(start 117.222105 87.032209)
		(end 117.222104 87.032207)
		(width 0.162)
		(layer "In2.Cu")
		(net 151)
	)
	(segment
		(start 120.505 60.3)
		(end 120.3025 60.5025)
		(width 0.15)
		(layer "In2.Cu")
		(net 151)
	)
	(segment
		(start 117.770734 86.200733)
		(end 117.770735 86.200735)
		(width 0.162)
		(layer "In2.Cu")
		(net 151)
	)
	(segment
		(start 118.67 87.1)
		(end 118.195 86.625)
		(width 0.162)
		(layer "In2.Cu")
		(net 151)
	)
	(segment
		(start 116.693013 84.450017)
		(end 116.693013 84.450018)
		(width 0.162)
		(layer "In2.Cu")
		(net 151)
	)
	(segment
		(start 117.258701 85.015705)
		(end 117.258701 85.015706)
		(width 0.162)
		(layer "In2.Cu")
		(net 151)
	)
	(segment
		(start 115.52504 85.052301)
		(end 115.525042 85.052302)
		(width 0.162)
		(layer "In2.Cu")
		(net 151)
	)
	(segment
		(start 116.656416 86.466519)
		(end 116.656417 86.46652)
		(width 0.162)
		(layer "In2.Cu")
		(net 151)
	)
	(segment
		(start 114.03 63.51)
		(end 116.885 60.655)
		(width 0.162)
		(layer "In2.Cu")
		(net 151)
	)
	(segment
		(start 121.46 60.54)
		(end 121.14 60.54)
		(width 0.15)
		(layer "In2.Cu")
		(net 151)
	)
	(segment
		(start 117.770735 86.200735)
		(end 118.107232 85.864237)
		(width 0.162)
		(layer "In2.Cu")
		(net 151)
	)
	(segment
		(start 120.9 60.3)
		(end 120.505 60.3)
		(width 0.15)
		(layer "In2.Cu")
		(net 151)
	)
	(segment
		(start 116.127325 83.88433)
		(end 115.932248 84.079406)
		(width 0.162)
		(layer "In2.Cu")
		(net 151)
	)
	(segment
		(start 117.824389 85.581393)
		(end 117.824389 85.581394)
		(width 0.162)
		(layer "In2.Cu")
		(net 151)
	)
	(segment
		(start 117.541545 85.015706)
		(end 117.541544 85.015706)
		(width 0.162)
		(layer "In2.Cu")
		(net 151)
	)
	(arc
		(start 117.222104 87.032207)
		(mid 117.163525 86.890786)
		(end 117.222103 86.749364)
		(width 0.162)
		(layer "In2.Cu")
		(net 151)
	)
	(arc
		(start 115.525041 85.335144)
		(mid 115.466462 85.193723)
		(end 115.52504 85.052301)
		(width 0.162)
		(layer "In2.Cu")
		(net 151)
	)
	(arc
		(start 117.541544 85.298549)
		(mid 117.600123 85.157128)
		(end 117.541545 85.015706)
		(width 0.162)
		(layer "In2.Cu")
		(net 151)
	)
	(arc
		(start 116.410168 84.167173)
		(mid 116.468747 84.025752)
		(end 116.410169 83.88433)
		(width 0.162)
		(layer "In2.Cu")
		(net 151)
	)
	(arc
		(start 115.932248 84.079406)
		(mid 115.790827 84.137984)
		(end 115.649406 84.079406)
		(width 0.162)
		(layer "In2.Cu")
		(net 151)
	)
	(arc
		(start 116.939259 86.46652)
		(mid 116.797837 86.525098)
		(end 116.656416 86.466519)
		(width 0.162)
		(layer "In2.Cu")
		(net 151)
	)
	(arc
		(start 117.504948 87.032208)
		(mid 117.363527 87.090787)
		(end 117.222105 87.032209)
		(width 0.162)
		(layer "In2.Cu")
		(net 151)
	)
	(arc
		(start 116.975856 84.732861)
		(mid 117.034435 84.59144)
		(end 116.975857 84.450018)
		(width 0.162)
		(layer "In2.Cu")
		(net 151)
	)
	(arc
		(start 116.410168 83.88433)
		(mid 116.268747 83.825751)
		(end 116.127325 83.884329)
		(width 0.162)
		(layer "In2.Cu")
		(net 151)
	)
	(arc
		(start 117.541544 85.015706)
		(mid 117.400123 84.957127)
		(end 117.258701 85.015705)
		(width 0.162)
		(layer "In2.Cu")
		(net 151)
	)
	(arc
		(start 118.195 86.625)
		(mid 118.053579 86.566421)
		(end 117.912157 86.624999)
		(width 0.162)
		(layer "In2.Cu")
		(net 151)
	)
	(arc
		(start 116.373571 85.900832)
		(mid 116.232149 85.95941)
		(end 116.090728 85.900831)
		(width 0.162)
		(layer "In2.Cu")
		(net 151)
	)
	(arc
		(start 118.107232 85.581394)
		(mid 117.965811 85.522815)
		(end 117.824389 85.581393)
		(width 0.162)
		(layer "In2.Cu")
		(net 151)
	)
	(arc
		(start 116.975856 84.450018)
		(mid 116.834435 84.391439)
		(end 116.693013 84.450017)
		(width 0.162)
		(layer "In2.Cu")
		(net 151)
	)
	(arc
		(start 118.107232 85.864237)
		(mid 118.165811 85.722816)
		(end 118.107233 85.581394)
		(width 0.162)
		(layer "In2.Cu")
		(net 151)
	)
	(arc
		(start 115.807883 85.335144)
		(mid 115.666461 85.393722)
		(end 115.52504 85.335143)
		(width 0.162)
		(layer "In2.Cu")
		(net 151)
	)
	(arc
		(start 116.656417 86.46652)
		(mid 116.597838 86.325099)
		(end 116.656416 86.183677)
		(width 0.162)
		(layer "In2.Cu")
		(net 151)
	)
	(arc
		(start 116.090729 85.900832)
		(mid 116.03215 85.759411)
		(end 116.090728 85.617989)
		(width 0.162)
		(layer "In2.Cu")
		(net 151)
	)
	(segment
		(start 121.1 85.9)
		(end 120.72 85.52)
		(width 0.2)
		(layer "F.Cu")
		(net 152)
	)
	(segment
		(start 120.72 85.52)
		(end 120.72 85.51)
		(width 0.2)
		(layer "F.Cu")
		(net 152)
	)
	(segment
		(start 122.26 62.94)
		(end 122.66 63.34)
		(width 0.182)
		(layer "F.Cu")
		(net 152)
	)
	(via
		(at 122.26 62.94)
		(size 0.45)
		(drill 0.2)
		(layers "F.Cu" "B.Cu")
		(remove_unused_layers yes)
		(keep_end_layers yes)
		(zone_layer_connections)
		(net 152)
	)
	(via
		(at 120.72 85.51)
		(size 0.45)
		(drill 0.1)
		(layers "F.Cu" "B.Cu")
		(net 152)
	)
	(segment
		(start 122.26 62)
		(end 123.13 61.13)
		(width 0.15)
		(layer "B.Cu")
		(net 152)
	)
	(segment
		(start 123.13 61.13)
		(end 123.51 61.13)
		(width 0.15)
		(layer "B.Cu")
		(net 152)
	)
	(segment
		(start 122.26 62.94)
		(end 122.26 62)
		(width 0.15)
		(layer "B.Cu")
		(net 152)
	)
	(segment
		(start 116.79169 69.93)
		(end 117.56831 69.93)
		(width 0.162)
		(layer "In2.Cu")
		(net 152)
	)
	(segment
		(start 119.34 63.66)
		(end 119.556 63.444)
		(width 0.162)
		(layer "In2.Cu")
		(net 152)
	)
	(segment
		(start 116.79169 69.13)
		(end 117.56831 69.13)
		(width 0.162)
		(layer "In2.Cu")
		(net 152)
	)
	(segment
		(start 116.79169 71.13)
		(end 117.56831 71.13)
		(width 0.162)
		(layer "In2.Cu")
		(net 152)
	)
	(segment
		(start 116.79169 65.93)
		(end 117.56831 65.93)
		(width 0.162)
		(layer "In2.Cu")
		(net 152)
	)
	(segment
		(start 120.72 85.51)
		(end 120.72 83.5029)
		(width 0.162)
		(layer "In2.Cu")
		(net 152)
	)
	(segment
		(start 116.79169 69.53)
		(end 117.56831 69.53)
		(width 0.162)
		(layer "In2.Cu")
		(net 152)
	)
	(segment
		(start 121.756 63.444)
		(end 122.26 62.94)
		(width 0.162)
		(layer "In2.Cu")
		(net 152)
	)
	(segment
		(start 117.56831 65.53)
		(end 117.48 65.53)
		(width 0.162)
		(layer "In2.Cu")
		(net 152)
	)
	(segment
		(start 116.79169 67.13)
		(end 117.56831 67.13)
		(width 0.162)
		(layer "In2.Cu")
		(net 152)
	)
	(segment
		(start 116.79169 67.53)
		(end 117.56831 67.53)
		(width 0.162)
		(layer "In2.Cu")
		(net 152)
	)
	(segment
		(start 116.79169 68.73)
		(end 117.56831 68.73)
		(width 0.162)
		(layer "In2.Cu")
		(net 152)
	)
	(segment
		(start 116.79169 70.33)
		(end 117.56831 70.33)
		(width 0.162)
		(layer "In2.Cu")
		(net 152)
	)
	(segment
		(start 116.79169 66.73)
		(end 117.56831 66.73)
		(width 0.162)
		(layer "In2.Cu")
		(net 152)
	)
	(segment
		(start 117.28 65.33)
		(end 117.28 64.97)
		(width 0.162)
		(layer "In2.Cu")
		(net 152)
	)
	(segment
		(start 119.556 63.444)
		(end 121.756 63.444)
		(width 0.162)
		(layer "In2.Cu")
		(net 152)
	)
	(segment
		(start 116.79169 67.93)
		(end 117.56831 67.93)
		(width 0.162)
		(layer "In2.Cu")
		(net 152)
	)
	(segment
		(start 116.79169 68.33)
		(end 117.56831 68.33)
		(width 0.162)
		(layer "In2.Cu")
		(net 152)
	)
	(segment
		(start 118.59 63.66)
		(end 119.34 63.66)
		(width 0.162)
		(layer "In2.Cu")
		(net 152)
	)
	(segment
		(start 116.79169 72.33)
		(end 117.56831 72.33)
		(width 0.162)
		(layer "In2.Cu")
		(net 152)
	)
	(segment
		(start 116.79169 70.73)
		(end 117.56831 70.73)
		(width 0.162)
		(layer "In2.Cu")
		(net 152)
	)
	(segment
		(start 116.79169 66.33)
		(end 117.56831 66.33)
		(width 0.162)
		(layer "In2.Cu")
		(net 152)
	)
	(segment
		(start 117.28 64.97)
		(end 118.59 63.66)
		(width 0.162)
		(layer "In2.Cu")
		(net 152)
	)
	(segment
		(start 120.72 83.5029)
		(end 117.28 80.0629)
		(width 0.162)
		(layer "In2.Cu")
		(net 152)
	)
	(segment
		(start 116.79169 71.93)
		(end 117.56831 71.93)
		(width 0.162)
		(layer "In2.Cu")
		(net 152)
	)
	(segment
		(start 117.28 80.0629)
		(end 117.28 72.93)
		(width 0.162)
		(layer "In2.Cu")
		(net 152)
	)
	(segment
		(start 117.08 72.73)
		(end 116.79169 72.73)
		(width 0.162)
		(layer "In2.Cu")
		(net 152)
	)
	(segment
		(start 116.79169 71.53)
		(end 117.56831 71.53)
		(width 0.162)
		(layer "In2.Cu")
		(net 152)
	)
	(arc
		(start 117.76831 68.93)
		(mid 117.709731 68.788579)
		(end 117.56831 68.73)
		(width 0.162)
		(layer "In2.Cu")
		(net 152)
	)
	(arc
		(start 116.79169 70.33)
		(mid 116.650269 70.271421)
		(end 116.59169 70.13)
		(width 0.162)
		(layer "In2.Cu")
		(net 152)
	)
	(arc
		(start 117.76831 67.33)
		(mid 117.709731 67.188579)
		(end 117.56831 67.13)
		(width 0.162)
		(layer "In2.Cu")
		(net 152)
	)
	(arc
		(start 117.56831 71.53)
		(mid 117.709731 71.471421)
		(end 117.76831 71.33)
		(width 0.162)
		(layer "In2.Cu")
		(net 152)
	)
	(arc
		(start 117.28 72.93)
		(mid 117.221421 72.788579)
		(end 117.08 72.73)
		(width 0.162)
		(layer "In2.Cu")
		(net 152)
	)
	(arc
		(start 116.59169 66.93)
		(mid 116.650269 66.788579)
		(end 116.79169 66.73)
		(width 0.162)
		(layer "In2.Cu")
		(net 152)
	)
	(arc
		(start 117.56831 68.33)
		(mid 117.709731 68.271421)
		(end 117.76831 68.13)
		(width 0.162)
		(layer "In2.Cu")
		(net 152)
	)
	(arc
		(start 117.48 65.53)
		(mid 117.338579 65.471421)
		(end 117.28 65.33)
		(width 0.162)
		(layer "In2.Cu")
		(net 152)
	)
	(arc
		(start 117.76831 66.53)
		(mid 117.709731 66.388579)
		(end 117.56831 66.33)
		(width 0.162)
		(layer "In2.Cu")
		(net 152)
	)
	(arc
		(start 116.59169 66.13)
		(mid 116.650269 65.988579)
		(end 116.79169 65.93)
		(width 0.162)
		(layer "In2.Cu")
		(net 152)
	)
	(arc
		(start 116.79169 71.93)
		(mid 116.650269 71.871421)
		(end 116.59169 71.73)
		(width 0.162)
		(layer "In2.Cu")
		(net 152)
	)
	(arc
		(start 117.76831 68.13)
		(mid 117.709731 67.988579)
		(end 117.56831 67.93)
		(width 0.162)
		(layer "In2.Cu")
		(net 152)
	)
	(arc
		(start 116.79169 71.13)
		(mid 116.650269 71.071421)
		(end 116.59169 70.93)
		(width 0.162)
		(layer "In2.Cu")
		(net 152)
	)
	(arc
		(start 116.79169 72.73)
		(mid 116.650269 72.671421)
		(end 116.59169 72.53)
		(width 0.162)
		(layer "In2.Cu")
		(net 152)
	)
	(arc
		(start 116.79169 69.53)
		(mid 116.650269 69.471421)
		(end 116.59169 69.33)
		(width 0.162)
		(layer "In2.Cu")
		(net 152)
	)
	(arc
		(start 116.59169 71.73)
		(mid 116.650269 71.588579)
		(end 116.79169 71.53)
		(width 0.162)
		(layer "In2.Cu")
		(net 152)
	)
	(arc
		(start 117.56831 69.13)
		(mid 117.709731 69.071421)
		(end 117.76831 68.93)
		(width 0.162)
		(layer "In2.Cu")
		(net 152)
	)
	(arc
		(start 117.56831 66.73)
		(mid 117.709731 66.671421)
		(end 117.76831 66.53)
		(width 0.162)
		(layer "In2.Cu")
		(net 152)
	)
	(arc
		(start 117.56831 69.93)
		(mid 117.709731 69.871421)
		(end 117.76831 69.73)
		(width 0.162)
		(layer "In2.Cu")
		(net 152)
	)
	(arc
		(start 117.56831 65.93)
		(mid 117.709731 65.871421)
		(end 117.76831 65.73)
		(width 0.162)
		(layer "In2.Cu")
		(net 152)
	)
	(arc
		(start 116.59169 69.33)
		(mid 116.650269 69.188579)
		(end 116.79169 69.13)
		(width 0.162)
		(layer "In2.Cu")
		(net 152)
	)
	(arc
		(start 117.76831 69.73)
		(mid 117.709731 69.588579)
		(end 117.56831 69.53)
		(width 0.162)
		(layer "In2.Cu")
		(net 152)
	)
	(arc
		(start 116.59169 68.53)
		(mid 116.650269 68.388579)
		(end 116.79169 68.33)
		(width 0.162)
		(layer "In2.Cu")
		(net 152)
	)
	(arc
		(start 116.79169 68.73)
		(mid 116.650269 68.671421)
		(end 116.59169 68.53)
		(width 0.162)
		(layer "In2.Cu")
		(net 152)
	)
	(arc
		(start 117.56831 70.73)
		(mid 117.709731 70.671421)
		(end 117.76831 70.53)
		(width 0.162)
		(layer "In2.Cu")
		(net 152)
	)
	(arc
		(start 116.79169 67.13)
		(mid 116.650269 67.071421)
		(end 116.59169 66.93)
		(width 0.162)
		(layer "In2.Cu")
		(net 152)
	)
	(arc
		(start 117.56831 67.53)
		(mid 117.709731 67.471421)
		(end 117.76831 67.33)
		(width 0.162)
		(layer "In2.Cu")
		(net 152)
	)
	(arc
		(start 116.79169 67.93)
		(mid 116.650269 67.871421)
		(end 116.59169 67.73)
		(width 0.162)
		(layer "In2.Cu")
		(net 152)
	)
	(arc
		(start 116.79169 66.33)
		(mid 116.650269 66.271421)
		(end 116.59169 66.13)
		(width 0.162)
		(layer "In2.Cu")
		(net 152)
	)
	(arc
		(start 117.76831 71.33)
		(mid 117.709731 71.188579)
		(end 117.56831 71.13)
		(width 0.162)
		(layer "In2.Cu")
		(net 152)
	)
	(arc
		(start 116.59169 70.93)
		(mid 116.650269 70.788579)
		(end 116.79169 70.73)
		(width 0.162)
		(layer "In2.Cu")
		(net 152)
	)
	(arc
		(start 116.59169 70.13)
		(mid 116.650269 69.988579)
		(end 116.79169 69.93)
		(width 0.162)
		(layer "In2.Cu")
		(net 152)
	)
	(arc
		(start 116.59169 67.73)
		(mid 116.650269 67.588579)
		(end 116.79169 67.53)
		(width 0.162)
		(layer "In2.Cu")
		(net 152)
	)
	(arc
		(start 117.76831 72.13)
		(mid 117.709731 71.988579)
		(end 117.56831 71.93)
		(width 0.162)
		(layer "In2.Cu")
		(net 152)
	)
	(arc
		(start 117.76831 65.73)
		(mid 117.709731 65.588579)
		(end 117.56831 65.53)
		(width 0.162)
		(layer "In2.Cu")
		(net 152)
	)
	(arc
		(start 116.59169 72.53)
		(mid 116.650269 72.388579)
		(end 116.79169 72.33)
		(width 0.162)
		(layer "In2.Cu")
		(net 152)
	)
	(arc
		(start 117.76831 70.53)
		(mid 117.709731 70.388579)
		(end 117.56831 70.33)
		(width 0.162)
		(layer "In2.Cu")
		(net 152)
	)
	(arc
		(start 117.56831 72.33)
		(mid 117.709731 72.271421)
		(end 117.76831 72.13)
		(width 0.162)
		(layer "In2.Cu")
		(net 152)
	)
	(segment
		(start 126.7 88.3)
		(end 126.3 88.7)
		(width 0.15)
		(layer "F.Cu")
		(net 153)
	)
	(segment
		(start 125.86 60.14)
		(end 126.26 59.74)
		(width 0.182)
		(layer "F.Cu")
		(net 153)
	)
	(via
		(at 126.3 88.7)
		(size 0.45)
		(drill 0.2)
		(layers "F.Cu" "B.Cu")
		(remove_unused_layers yes)
		(keep_end_layers yes)
		(zone_layer_connections)
		(net 153)
	)
	(via
		(at 126.26 59.74)
		(size 0.45)
		(drill 0.2)
		(layers "F.Cu" "B.Cu")
		(remove_unused_layers yes)
		(keep_end_layers yes)
		(zone_layer_connections)
		(net 153)
	)
	(segment
		(start 126.26 59.74)
		(end 126.26 57.89)
		(width 0.15)
		(layer "B.Cu")
		(net 153)
	)
	(segment
		(start 125.35 88.3)
		(end 125.095 88.045)
		(width 0.15)
		(layer "In4.Cu")
		(net 153)
	)
	(segment
		(start 126.66 60.14)
		(end 126.26 59.74)
		(width 0.162)
		(layer "In4.Cu")
		(net 153)
	)
	(segment
		(start 126.92 76.73)
		(end 132.13 76.73)
		(width 0.162)
		(layer "In4.Cu")
		(net 153)
	)
	(segment
		(start 124.299 79.351)
		(end 126.92 76.73)
		(width 0.162)
		(layer "In4.Cu")
		(net 153)
	)
	(segment
		(start 129 59.5)
		(end 128.44 59.5)
		(width 0.162)
		(layer "In4.Cu")
		(net 153)
	)
	(segment
		(start 125.9 88.3)
		(end 125.35 88.3)
		(width 0.15)
		(layer "In4.Cu")
		(net 153)
	)
	(segment
		(start 125.095 88.045)
		(end 125.095 87.736385)
		(width 0.15)
		(layer "In4.Cu")
		(net 153)
	)
	(segment
		(start 135.042266 71.98)
		(end 135.07 71.98)
		(width 0.162)
		(layer "In4.Cu")
		(net 153)
	)
	(segment
		(start 135.042266 71.58)
		(end 135.497734 71.58)
		(width 0.162)
		(layer "In4.Cu")
		(net 153)
	)
	(segment
		(start 128.44 59.5)
		(end 127.8 60.14)
		(width 0.162)
		(layer "In4.Cu")
		(net 153)
	)
	(segment
		(start 135.042266 70.78)
		(end 135.497734 70.78)
		(width 0.162)
		(layer "In4.Cu")
		(net 153)
	)
	(segment
		(start 124.541385 87.5)
		(end 124.3 87.258615)
		(width 0.15)
		(layer "In4.Cu")
		(net 153)
	)
	(segment
		(start 135.497734 69.98)
		(end 135.47 69.98)
		(width 0.162)
		(layer "In4.Cu")
		(net 153)
	)
	(segment
		(start 127.8 60.14)
		(end 127.66 60.14)
		(width 0.162)
		(layer "In4.Cu")
		(net 153)
	)
	(segment
		(start 135.27 73.59)
		(end 135.27 72.58)
		(width 0.162)
		(layer "In4.Cu")
		(net 153)
	)
	(segment
		(start 125.095 87.736385)
		(end 124.858615 87.5)
		(width 0.15)
		(layer "In4.Cu")
		(net 153)
	)
	(segment
		(start 132.54 61.68)
		(end 131.19 60.33)
		(width 0.162)
		(layer "In4.Cu")
		(net 153)
	)
	(segment
		(start 124.3 87.258615)
		(end 124.3 86.251)
		(width 0.15)
		(layer "In4.Cu")
		(net 153)
	)
	(segment
		(start 126.66 60.14)
		(end 127.66 60.14)
		(width 0.15)
		(layer "In4.Cu")
		(net 153)
	)
	(segment
		(start 124.299 86.25)
		(end 124.299 79.351)
		(width 0.162)
		(layer "In4.Cu")
		(net 153)
	)
	(segment
		(start 124.858615 87.5)
		(end 124.541385 87.5)
		(width 0.15)
		(layer "In4.Cu")
		(net 153)
	)
	(segment
		(start 135.27 63.84)
		(end 135.26 63.84)
		(width 0.162)
		(layer "In4.Cu")
		(net 153)
	)
	(segment
		(start 129.83 60.33)
		(end 129 59.5)
		(width 0.162)
		(layer "In4.Cu")
		(net 153)
	)
	(segment
		(start 135.07 71.98)
		(end 135.497734 71.98)
		(width 0.162)
		(layer "In4.Cu")
		(net 153)
	)
	(segment
		(start 124.3 86.251)
		(end 124.299 86.25)
		(width 0.15)
		(layer "In4.Cu")
		(net 153)
	)
	(segment
		(start 131.19 60.33)
		(end 129.83 60.33)
		(width 0.162)
		(layer "In4.Cu")
		(net 153)
	)
	(segment
		(start 133.1 61.68)
		(end 132.54 61.68)
		(width 0.162)
		(layer "In4.Cu")
		(net 153)
	)
	(segment
		(start 132.13 76.73)
		(end 135.27 73.59)
		(width 0.162)
		(layer "In4.Cu")
		(net 153)
	)
	(segment
		(start 135.042266 70.38)
		(end 135.497734 70.38)
		(width 0.162)
		(layer "In4.Cu")
		(net 153)
	)
	(segment
		(start 135.27 69.78)
		(end 135.27 63.84)
		(width 0.162)
		(layer "In4.Cu")
		(net 153)
	)
	(segment
		(start 126.3 88.7)
		(end 125.9 88.3)
		(width 0.15)
		(layer "In4.Cu")
		(net 153)
	)
	(segment
		(start 135.26 63.84)
		(end 133.1 61.68)
		(width 0.162)
		(layer "In4.Cu")
		(net 153)
	)
	(segment
		(start 135.042266 71.18)
		(end 135.497734 71.18)
		(width 0.162)
		(layer "In4.Cu")
		(net 153)
	)
	(segment
		(start 135.07 72.38)
		(end 135.042266 72.38)
		(width 0.162)
		(layer "In4.Cu")
		(net 153)
	)
	(arc
		(start 135.697734 70.18)
		(mid 135.639155 70.038579)
		(end 135.497734 69.98)
		(width 0.162)
		(layer "In4.Cu")
		(net 153)
	)
	(arc
		(start 135.497734 71.98)
		(mid 135.639155 71.921421)
		(end 135.697734 71.78)
		(width 0.162)
		(layer "In4.Cu")
		(net 153)
	)
	(arc
		(start 134.842266 71.38)
		(mid 134.900845 71.238579)
		(end 135.042266 71.18)
		(width 0.162)
		(layer "In4.Cu")
		(net 153)
	)
	(arc
		(start 135.497734 70.38)
		(mid 135.639155 70.321421)
		(end 135.697734 70.18)
		(width 0.162)
		(layer "In4.Cu")
		(net 153)
	)
	(arc
		(start 134.842266 72.18)
		(mid 134.900845 72.038579)
		(end 135.042266 71.98)
		(width 0.162)
		(layer "In4.Cu")
		(net 153)
	)
	(arc
		(start 135.042266 71.58)
		(mid 134.900845 71.521421)
		(end 134.842266 71.38)
		(width 0.162)
		(layer "In4.Cu")
		(net 153)
	)
	(arc
		(start 135.27 72.58)
		(mid 135.211421 72.438579)
		(end 135.07 72.38)
		(width 0.162)
		(layer "In4.Cu")
		(net 153)
	)
	(arc
		(start 134.842266 70.58)
		(mid 134.900845 70.438579)
		(end 135.042266 70.38)
		(width 0.162)
		(layer "In4.Cu")
		(net 153)
	)
	(arc
		(start 135.042266 72.38)
		(mid 134.900845 72.321421)
		(end 134.842266 72.18)
		(width 0.162)
		(layer "In4.Cu")
		(net 153)
	)
	(arc
		(start 135.497734 71.18)
		(mid 135.639155 71.121421)
		(end 135.697734 70.98)
		(width 0.162)
		(layer "In4.Cu")
		(net 153)
	)
	(arc
		(start 135.697734 70.98)
		(mid 135.639155 70.838579)
		(end 135.497734 70.78)
		(width 0.162)
		(layer "In4.Cu")
		(net 153)
	)
	(arc
		(start 135.697734 71.78)
		(mid 135.639155 71.638579)
		(end 135.497734 71.58)
		(width 0.162)
		(layer "In4.Cu")
		(net 153)
	)
	(arc
		(start 135.042266 70.78)
		(mid 134.900845 70.721421)
		(end 134.842266 70.58)
		(width 0.162)
		(layer "In4.Cu")
		(net 153)
	)
	(arc
		(start 135.47 69.98)
		(mid 135.328579 69.921421)
		(end 135.27 69.78)
		(width 0.162)
		(layer "In4.Cu")
		(net 153)
	)
	(segment
		(start 122.26 59.74)
		(end 122.66 60.14)
		(width 0.182)
		(layer "F.Cu")
		(net 154)
	)
	(segment
		(start 121.9 87.5)
		(end 121.51 87.11)
		(width 0.2)
		(layer "F.Cu")
		(net 154)
	)
	(segment
		(start 121.51 87.11)
		(end 121.51 87.1)
		(width 0.2)
		(layer "F.Cu")
		(net 154)
	)
	(via
		(at 121.51 87.1)
		(size 0.45)
		(drill 0.1)
		(layers "F.Cu" "B.Cu")
		(net 154)
	)
	(via
		(at 122.26 59.74)
		(size 0.45)
		(drill 0.2)
		(layers "F.Cu" "B.Cu")
		(remove_unused_layers yes)
		(keep_end_layers yes)
		(zone_layer_connections)
		(net 154)
	)
	(segment
		(start 122.26 59.74)
		(end 122.26 58.63)
		(width 0.2)
		(layer "B.Cu")
		(net 154)
	)
	(segment
		(start 121.81 58.18)
		(end 121.81 57.89)
		(width 0.2)
		(layer "B.Cu")
		(net 154)
	)
	(segment
		(start 122.26 58.63)
		(end 121.81 58.18)
		(width 0.2)
		(layer "B.Cu")
		(net 154)
	)
	(segment
		(start 114.54863 60.991373)
		(end 114.54863 60.991372)
		(width 0.162)
		(layer "In2.Cu")
		(net 154)
	)
	(segment
		(start 114.81378 60.125152)
		(end 114.813779 60.125152)
		(width 0.162)
		(layer "In2.Cu")
		(net 154)
	)
	(segment
		(start 115.679999 60.142844)
		(end 116.051244 60.514089)
		(width 0.162)
		(layer "In2.Cu")
		(net 154)
	)
	(segment
		(start 120.2 59.6)
		(end 115.94 59.6)
		(width 0.162)
		(layer "In2.Cu")
		(net 154)
	)
	(segment
		(start 115.096622 60.125152)
		(end 115.768403 60.796931)
		(width 0.162)
		(layer "In2.Cu")
		(net 154)
	)
	(segment
		(start 114.813779 60.407994)
		(end 115.485559 61.079773)
		(width 0.162)
		(layer "In2.Cu")
		(net 154)
	)
	(segment
		(start 121.86 60.14)
		(end 121.24 60.14)
		(width 0.15)
		(layer "In2.Cu")
		(net 154)
	)
	(segment
		(start 116.051244 60.796931)
		(end 116.051245 60.796931)
		(width 0.162)
		(layer "In2.Cu")
		(net 154)
	)
	(segment
		(start 120.9 59.8)
		(end 120.4 59.8)
		(width 0.162)
		(layer "In2.Cu")
		(net 154)
	)
	(segment
		(start 114.54863 60.991372)
		(end 113.268 62.272)
		(width 0.162)
		(layer "In2.Cu")
		(net 154)
	)
	(segment
		(start 113.268 83.568)
		(end 117.2 87.5)
		(width 0.162)
		(layer "In2.Cu")
		(net 154)
	)
	(segment
		(start 121.87 60.13)
		(end 121.86 60.14)
		(width 0.15)
		(layer "In2.Cu")
		(net 154)
	)
	(segment
		(start 115.94 59.6)
		(end 115.68 59.86)
		(width 0.162)
		(layer "In2.Cu")
		(net 154)
	)
	(segment
		(start 121.076766 87.5)
		(end 119.72 87.5)
		(width 0.15)
		(layer "In2.Cu")
		(net 154)
	)
	(segment
		(start 121.24 60.14)
		(end 120.9 59.8)
		(width 0.162)
		(layer "In2.Cu")
		(net 154)
	)
	(segment
		(start 115.48556 61.362616)
		(end 115.485558 61.362617)
		(width 0.162)
		(layer "In2.Cu")
		(net 154)
	)
	(segment
		(start 121.51 87.1)
		(end 121.476766 87.1)
		(width 0.162)
		(layer "In2.Cu")
		(net 154)
	)
	(segment
		(start 113.268 62.272)
		(end 113.268 83.568)
		(width 0.162)
		(layer "In2.Cu")
		(net 154)
	)
	(segment
		(start 115.202716 61.362617)
		(end 114.831472 60.991373)
		(width 0.162)
		(layer "In2.Cu")
		(net 154)
	)
	(segment
		(start 121.87 60.13)
		(end 122.26 59.74)
		(width 0.162)
		(layer "In2.Cu")
		(net 154)
	)
	(segment
		(start 120.4 59.8)
		(end 120.2 59.6)
		(width 0.162)
		(layer "In2.Cu")
		(net 154)
	)
	(segment
		(start 115.68 60.142844)
		(end 115.679999 60.142844)
		(width 0.162)
		(layer "In2.Cu")
		(net 154)
	)
	(segment
		(start 117.2 87.5)
		(end 119.72 87.5)
		(width 0.162)
		(layer "In2.Cu")
		(net 154)
	)
	(segment
		(start 121.476766 87.1)
		(end 121.076766 87.5)
		(width 0.162)
		(layer "In2.Cu")
		(net 154)
	)
	(arc
		(start 115.68 59.86)
		(mid 115.62142 60.001423)
		(end 115.68 60.142844)
		(width 0.162)
		(layer "In2.Cu")
		(net 154)
	)
	(arc
		(start 115.096622 60.125152)
		(mid 114.955201 60.066574)
		(end 114.81378 60.125152)
		(width 0.162)
		(layer "In2.Cu")
		(net 154)
	)
	(arc
		(start 114.813779 60.125152)
		(mid 114.755201 60.266573)
		(end 114.813779 60.407994)
		(width 0.162)
		(layer "In2.Cu")
		(net 154)
	)
	(arc
		(start 116.051245 60.796931)
		(mid 115.909823 60.85551)
		(end 115.768403 60.796931)
		(width 0.162)
		(layer "In2.Cu")
		(net 154)
	)
	(arc
		(start 115.485558 61.362617)
		(mid 115.344138 61.421194)
		(end 115.202716 61.362617)
		(width 0.162)
		(layer "In2.Cu")
		(net 154)
	)
	(arc
		(start 115.485559 61.079773)
		(mid 115.544138 61.221194)
		(end 115.48556 61.362616)
		(width 0.162)
		(layer "In2.Cu")
		(net 154)
	)
	(arc
		(start 116.051244 60.514089)
		(mid 116.109823 60.655509)
		(end 116.051244 60.796931)
		(width 0.162)
		(layer "In2.Cu")
		(net 154)
	)
	(arc
		(start 114.831472 60.991373)
		(mid 114.690052 60.932794)
		(end 114.54863 60.991373)
		(width 0.162)
		(layer "In2.Cu")
		(net 154)
	)
	(segment
		(start 121.46 58.94)
		(end 121.86 59.34)
		(width 0.182)
		(layer "F.Cu")
		(net 155)
	)
	(segment
		(start 123.11 88.69)
		(end 123.1 88.69)
		(width 0.2)
		(layer "F.Cu")
		(net 155)
	)
	(segment
		(start 123.5 88.3)
		(end 123.11 88.69)
		(width 0.2)
		(layer "F.Cu")
		(net 155)
	)
	(via
		(at 123.1 88.69)
		(size 0.45)
		(drill 0.1)
		(layers "F.Cu" "B.Cu")
		(net 155)
	)
	(via
		(at 121.46 58.94)
		(size 0.45)
		(drill 0.2)
		(layers "F.Cu" "B.Cu")
		(remove_unused_layers yes)
		(keep_end_layers yes)
		(zone_layer_connections)
		(net 155)
	)
	(segment
		(start 121.46 58.94)
		(end 120.76 58.24)
		(width 0.2)
		(layer "B.Cu")
		(net 155)
	)
	(segment
		(start 120.76 58.24)
		(end 120.76 57.89)
		(width 0.2)
		(layer "B.Cu")
		(net 155)
	)
	(segment
		(start 123.1 88.69)
		(end 116.09 88.69)
		(width 0.162)
		(layer "In2.Cu")
		(net 155)
	)
	(segment
		(start 111.744 61.606)
		(end 114.491 58.859)
		(width 0.162)
		(layer "In2.Cu")
		(net 155)
	)
	(segment
		(start 116.09 88.69)
		(end 111.744 84.344)
		(width 0.162)
		(layer "In2.Cu")
		(net 155)
	)
	(segment
		(start 120.92 58.4)
		(end 114.95 58.4)
		(width 0.15)
		(layer "In2.Cu")
		(net 155)
	)
	(segment
		(start 121.46 58.94)
		(end 120.92 58.4)
		(width 0.15)
		(layer "In2.Cu")
		(net 155)
	)
	(segment
		(start 114.95 58.4)
		(end 114.491 58.859)
		(width 0.15)
		(layer "In2.Cu")
		(net 155)
	)
	(segment
		(start 111.744 84.344)
		(end 111.744 61.606)
		(width 0.162)
		(layer "In2.Cu")
		(net 155)
	)
	(segment
		(start 91.6 73.9)
		(end 91.6 74.03)
		(width 0.5)
		(layer "F.Cu")
		(net 156)
	)
	(segment
		(start 92.1 73.4)
		(end 91.6 73.9)
		(width 0.5)
		(layer "F.Cu")
		(net 156)
	)
	(via
		(at 91.6 74.03)
		(size 0.45)
		(drill 0.2)
		(layers "F.Cu" "B.Cu")
		(remove_unused_layers yes)
		(keep_end_layers yes)
		(zone_layer_connections)
		(net 156)
	)
	(segment
		(start 91.6 74.03)
		(end 91.6 73.465)
		(width 0.5)
		(layer "B.Cu")
		(net 156)
	)
	(segment
		(start 126.66 62.54)
		(end 127.06 62.14)
		(width 0.182)
		(layer "F.Cu")
		(net 157)
	)
	(segment
		(start 125.9 85.9)
		(end 126.3 85.5)
		(width 0.15)
		(layer "F.Cu")
		(net 157)
	)
	(via
		(at 127.06 62.14)
		(size 0.45)
		(drill 0.2)
		(layers "F.Cu" "B.Cu")
		(remove_unused_layers yes)
		(keep_end_layers yes)
		(zone_layer_connections)
		(net 157)
	)
	(via
		(at 126.3 85.5)
		(size 0.45)
		(drill 0.2)
		(layers "F.Cu" "B.Cu")
		(remove_unused_layers yes)
		(keep_end_layers yes)
		(zone_layer_connections)
		(net 157)
	)
	(segment
		(start 125.7 61.94)
		(end 125.9 61.74)
		(width 0.15)
		(layer "B.Cu")
		(net 157)
	)
	(segment
		(start 125.9 61.74)
		(end 126.66 61.74)
		(width 0.15)
		(layer "B.Cu")
		(net 157)
	)
	(segment
		(start 125.01 61.94)
		(end 125.7 61.94)
		(width 0.15)
		(layer "B.Cu")
		(net 157)
	)
	(segment
		(start 126.66 61.74)
		(end 127.06 62.14)
		(width 0.15)
		(layer "B.Cu")
		(net 157)
	)
	(segment
		(start 132.508453 79.41581)
		(end 132.01348 78.920836)
		(width 0.162)
		(layer "In2.Cu")
		(net 157)
	)
	(segment
		(start 126.5 85.5)
		(end 127.1 84.9)
		(width 0.162)
		(layer "In2.Cu")
		(net 157)
	)
	(segment
		(start 131.942767 79.981495)
		(end 131.942767 79.981496)
		(width 0.162)
		(layer "In2.Cu")
		(net 157)
	)
	(segment
		(start 133.074139 78.850123)
		(end 133.074139 78.850124)
		(width 0.162)
		(layer "In2.Cu")
		(net 157)
	)
	(segment
		(start 131.942767 79.981496)
		(end 131.447794 79.486522)
		(width 0.162)
		(layer "In2.Cu")
		(net 157)
	)
	(segment
		(start 136.672814 74.262914)
		(end 136.813529 74.403629)
		(width 0.162)
		(layer "In2.Cu")
		(net 157)
	)
	(segment
		(start 131.164951 79.769365)
		(end 131.659925 80.264339)
		(width 0.162)
		(layer "In2.Cu")
		(net 157)
	)
	(segment
		(start 130.004 83.406)
		(end 130.004 81.496)
		(width 0.162)
		(layer "In2.Cu")
		(net 157)
	)
	(segment
		(start 131.377081 80.547181)
		(end 131.377081 80.547182)
		(width 0.162)
		(layer "In2.Cu")
		(net 157)
	)
	(segment
		(start 132.296325 78.637992)
		(end 132.296323 78.637993)
		(width 0.162)
		(layer "In2.Cu")
		(net 157)
	)
	(segment
		(start 131.377081 80.547182)
		(end 130.882108 80.052208)
		(width 0.162)
		(layer "In2.Cu")
		(net 157)
	)
	(segment
		(start 133.074139 78.850124)
		(end 133.003428 78.779413)
		(width 0.162)
		(layer "In2.Cu")
		(net 157)
	)
	(segment
		(start 131.942768 80.264338)
		(end 131.942767 80.264339)
		(width 0.162)
		(layer "In2.Cu")
		(net 157)
	)
	(segment
		(start 130.004 81.496)
		(end 130.175 81.325)
		(width 0.162)
		(layer "In2.Cu")
		(net 157)
	)
	(segment
		(start 130.811395 81.112866)
		(end 130.811395 81.112867)
		(width 0.162)
		(layer "In2.Cu")
		(net 157)
	)
	(segment
		(start 128.51 84.9)
		(end 130.004 83.406)
		(width 0.162)
		(layer "In2.Cu")
		(net 157)
	)
	(segment
		(start 136.883531 75.322161)
		(end 136.883532 75.322161)
		(width 0.162)
		(layer "In2.Cu")
		(net 157)
	)
	(segment
		(start 130.599265 80.335051)
		(end 131.094239 80.830025)
		(width 0.162)
		(layer "In2.Cu")
		(net 157)
	)
	(segment
		(start 133.07414 79.132966)
		(end 133.074139 79.132967)
		(width 0.162)
		(layer "In2.Cu")
		(net 157)
	)
	(segment
		(start 137.096373 74.403628)
		(end 138 73.5)
		(width 0.162)
		(layer "In2.Cu")
		(net 157)
	)
	(segment
		(start 136.883532 75.039317)
		(end 136.883532 75.039318)
		(width 0.162)
		(layer "In2.Cu")
		(net 157)
	)
	(segment
		(start 130.811395 81.112867)
		(end 130.316422 80.617894)
		(width 0.162)
		(layer "In2.Cu")
		(net 157)
	)
	(segment
		(start 133.003428 78.49657)
		(end 135.965 75.535)
		(width 0.162)
		(layer "In2.Cu")
		(net 157)
	)
	(segment
		(start 130.316421 80.335051)
		(end 130.316423 80.33505)
		(width 0.162)
		(layer "In2.Cu")
		(net 157)
	)
	(segment
		(start 131.377082 80.830024)
		(end 131.377081 80.830025)
		(width 0.162)
		(layer "In2.Cu")
		(net 157)
	)
	(segment
		(start 130.811395 81.395711)
		(end 130.811395 81.39571)
		(width 0.162)
		(layer "In2.Cu")
		(net 157)
	)
	(segment
		(start 132.296323 78.637993)
		(end 132.791297 79.132967)
		(width 0.162)
		(layer "In2.Cu")
		(net 157)
	)
	(segment
		(start 136.107131 74.8286)
		(end 136.107129 74.828601)
		(width 0.162)
		(layer "In2.Cu")
		(net 157)
	)
	(segment
		(start 131.730639 79.203678)
		(end 131.730637 79.203679)
		(width 0.162)
		(layer "In2.Cu")
		(net 157)
	)
	(segment
		(start 132.508453 79.415809)
		(end 132.508453 79.41581)
		(width 0.162)
		(layer "In2.Cu")
		(net 157)
	)
	(segment
		(start 126.3 85.5)
		(end 126.5 85.5)
		(width 0.162)
		(layer "In2.Cu")
		(net 157)
	)
	(segment
		(start 137.096372 74.40363)
		(end 137.096373 74.403628)
		(width 0.162)
		(layer "In2.Cu")
		(net 157)
	)
	(segment
		(start 130.599267 80.33505)
		(end 130.599265 80.335051)
		(width 0.162)
		(layer "In2.Cu")
		(net 157)
	)
	(segment
		(start 133.003427 78.49657)
		(end 133.003428 78.49657)
		(width 0.162)
		(layer "In2.Cu")
		(net 157)
	)
	(segment
		(start 135.965 75.252158)
		(end 135.824286 75.111444)
		(width 0.162)
		(layer "In2.Cu")
		(net 157)
	)
	(segment
		(start 131.730637 79.203679)
		(end 132.225611 79.698653)
		(width 0.162)
		(layer "In2.Cu")
		(net 157)
	)
	(segment
		(start 128.5 61.1)
		(end 128.1 61.5)
		(width 0.162)
		(layer "In2.Cu")
		(net 157)
	)
	(segment
		(start 136.883532 75.039318)
		(end 136.389971 74.545757)
		(width 0.162)
		(layer "In2.Cu")
		(net 157)
	)
	(segment
		(start 138 64.98)
		(end 134.12 61.1)
		(width 0.162)
		(layer "In2.Cu")
		(net 157)
	)
	(segment
		(start 128.1 61.5)
		(end 127.68 61.5)
		(width 0.162)
		(layer "In2.Cu")
		(net 157)
	)
	(segment
		(start 136.389972 74.262914)
		(end 136.389972 74.262913)
		(width 0.162)
		(layer "In2.Cu")
		(net 157)
	)
	(segment
		(start 136.672816 74.262913)
		(end 136.672814 74.262914)
		(width 0.162)
		(layer "In2.Cu")
		(net 157)
	)
	(segment
		(start 135.824285 74.828601)
		(end 135.824287 74.8286)
		(width 0.162)
		(layer "In2.Cu")
		(net 157)
	)
	(segment
		(start 138 73.5)
		(end 138 64.98)
		(width 0.162)
		(layer "In2.Cu")
		(net 157)
	)
	(segment
		(start 127.06 62.12)
		(end 127.06 62.14)
		(width 0.162)
		(layer "In2.Cu")
		(net 157)
	)
	(segment
		(start 132.508454 79.698652)
		(end 132.508453 79.698653)
		(width 0.162)
		(layer "In2.Cu")
		(net 157)
	)
	(segment
		(start 136.107129 74.828601)
		(end 136.600689 75.322161)
		(width 0.162)
		(layer "In2.Cu")
		(net 157)
	)
	(segment
		(start 127.68 61.5)
		(end 127.06 62.12)
		(width 0.162)
		(layer "In2.Cu")
		(net 157)
	)
	(segment
		(start 132.013479 78.637993)
		(end 132.013481 78.637992)
		(width 0.162)
		(layer "In2.Cu")
		(net 157)
	)
	(segment
		(start 131.164953 79.769364)
		(end 131.164951 79.769365)
		(width 0.162)
		(layer "In2.Cu")
		(net 157)
	)
	(segment
		(start 131.447793 79.203679)
		(end 131.447795 79.203678)
		(width 0.162)
		(layer "In2.Cu")
		(net 157)
	)
	(segment
		(start 130.457842 81.325)
		(end 130.528552 81.39571)
		(width 0.162)
		(layer "In2.Cu")
		(net 157)
	)
	(segment
		(start 134.12 61.1)
		(end 128.5 61.1)
		(width 0.162)
		(layer "In2.Cu")
		(net 157)
	)
	(segment
		(start 127.1 84.9)
		(end 128.51 84.9)
		(width 0.162)
		(layer "In2.Cu")
		(net 157)
	)
	(segment
		(start 130.882107 79.769365)
		(end 130.882109 79.769364)
		(width 0.162)
		(layer "In2.Cu")
		(net 157)
	)
	(arc
		(start 132.013481 78.637992)
		(mid 132.154902 78.579414)
		(end 132.296325 78.637992)
		(width 0.162)
		(layer "In2.Cu")
		(net 157)
	)
	(arc
		(start 136.813529 74.403629)
		(mid 136.95495 74.462208)
		(end 137.096372 74.40363)
		(width 0.162)
		(layer "In2.Cu")
		(net 157)
	)
	(arc
		(start 132.01348 78.920836)
		(mid 131.954901 78.779415)
		(end 132.013479 78.637993)
		(width 0.162)
		(layer "In2.Cu")
		(net 157)
	)
	(arc
		(start 130.175 81.325)
		(mid 130.316421 81.266422)
		(end 130.457842 81.325)
		(width 0.162)
		(layer "In2.Cu")
		(net 157)
	)
	(arc
		(start 130.811395 81.39571)
		(mid 130.869974 81.254288)
		(end 130.811395 81.112866)
		(width 0.162)
		(layer "In2.Cu")
		(net 157)
	)
	(arc
		(start 130.882109 79.769364)
		(mid 131.02353 79.710786)
		(end 131.164953 79.769364)
		(width 0.162)
		(layer "In2.Cu")
		(net 157)
	)
	(arc
		(start 130.316423 80.33505)
		(mid 130.457844 80.276472)
		(end 130.599267 80.33505)
		(width 0.162)
		(layer "In2.Cu")
		(net 157)
	)
	(arc
		(start 131.942767 80.264339)
		(mid 132.001346 80.122917)
		(end 131.942767 79.981495)
		(width 0.162)
		(layer "In2.Cu")
		(net 157)
	)
	(arc
		(start 136.389971 74.545757)
		(mid 136.331393 74.404335)
		(end 136.389972 74.262914)
		(width 0.162)
		(layer "In2.Cu")
		(net 157)
	)
	(arc
		(start 130.882108 80.052208)
		(mid 130.823529 79.910787)
		(end 130.882107 79.769365)
		(width 0.162)
		(layer "In2.Cu")
		(net 157)
	)
	(arc
		(start 130.316422 80.617894)
		(mid 130.257843 80.476473)
		(end 130.316421 80.335051)
		(width 0.162)
		(layer "In2.Cu")
		(net 157)
	)
	(arc
		(start 136.389972 74.262913)
		(mid 136.531393 74.204335)
		(end 136.672816 74.262913)
		(width 0.162)
		(layer "In2.Cu")
		(net 157)
	)
	(arc
		(start 135.824286 75.111444)
		(mid 135.765707 74.970023)
		(end 135.824285 74.828601)
		(width 0.162)
		(layer "In2.Cu")
		(net 157)
	)
	(arc
		(start 135.965 75.535)
		(mid 136.023579 75.393578)
		(end 135.965 75.252158)
		(width 0.162)
		(layer "In2.Cu")
		(net 157)
	)
	(arc
		(start 132.791297 79.132967)
		(mid 132.932719 79.191545)
		(end 133.07414 79.132966)
		(width 0.162)
		(layer "In2.Cu")
		(net 157)
	)
	(arc
		(start 136.883532 75.322161)
		(mid 136.942111 75.180739)
		(end 136.883532 75.039317)
		(width 0.162)
		(layer "In2.Cu")
		(net 157)
	)
	(arc
		(start 131.447795 79.203678)
		(mid 131.589216 79.1451)
		(end 131.730639 79.203678)
		(width 0.162)
		(layer "In2.Cu")
		(net 157)
	)
	(arc
		(start 131.447794 79.486522)
		(mid 131.389215 79.345101)
		(end 131.447793 79.203679)
		(width 0.162)
		(layer "In2.Cu")
		(net 157)
	)
	(arc
		(start 131.659925 80.264339)
		(mid 131.801347 80.322917)
		(end 131.942768 80.264338)
		(width 0.162)
		(layer "In2.Cu")
		(net 157)
	)
	(arc
		(start 131.094239 80.830025)
		(mid 131.235661 80.888603)
		(end 131.377082 80.830024)
		(width 0.162)
		(layer "In2.Cu")
		(net 157)
	)
	(arc
		(start 130.528552 81.39571)
		(mid 130.669973 81.454289)
		(end 130.811395 81.395711)
		(width 0.162)
		(layer "In2.Cu")
		(net 157)
	)
	(arc
		(start 132.225611 79.698653)
		(mid 132.367033 79.757231)
		(end 132.508454 79.698652)
		(width 0.162)
		(layer "In2.Cu")
		(net 157)
	)
	(arc
		(start 136.600689 75.322161)
		(mid 136.74211 75.380739)
		(end 136.883531 75.322161)
		(width 0.162)
		(layer "In2.Cu")
		(net 157)
	)
	(arc
		(start 133.074139 79.132967)
		(mid 133.132718 78.991545)
		(end 133.074139 78.850123)
		(width 0.162)
		(layer "In2.Cu")
		(net 157)
	)
	(arc
		(start 131.377081 80.830025)
		(mid 131.43566 80.688603)
		(end 131.377081 80.547181)
		(width 0.162)
		(layer "In2.Cu")
		(net 157)
	)
	(arc
		(start 132.508453 79.698653)
		(mid 132.567032 79.557231)
		(end 132.508453 79.415809)
		(width 0.162)
		(layer "In2.Cu")
		(net 157)
	)
	(arc
		(start 133.003428 78.779413)
		(mid 132.944849 78.637992)
		(end 133.003427 78.49657)
		(width 0.162)
		(layer "In2.Cu")
		(net 157)
	)
	(arc
		(start 135.824287 74.8286)
		(mid 135.965708 74.770022)
		(end 136.107131 74.8286)
		(width 0.162)
		(layer "In2.Cu")
		(net 157)
	)
	(segment
		(start 126.7 86.7)
		(end 127.1 86.3)
		(width 0.15)
		(layer "F.Cu")
		(net 158)
	)
	(segment
		(start 125.86 59.34)
		(end 125.86 58.87)
		(width 0.182)
		(layer "F.Cu")
		(net 158)
	)
	(via
		(at 127.1 86.3)
		(size 0.45)
		(drill 0.2)
		(layers "F.Cu" "B.Cu")
		(remove_unused_layers yes)
		(keep_end_layers yes)
		(zone_layer_connections)
		(net 158)
	)
	(via
		(at 125.86 58.87)
		(size 0.45)
		(drill 0.2)
		(layers "F.Cu" "B.Cu")
		(remove_unused_layers yes)
		(keep_end_layers yes)
		(zone_layer_connections)
		(net 158)
	)
	(segment
		(start 125.16 58.35)
		(end 125.16 57.89)
		(width 0.15)
		(layer "B.Cu")
		(net 158)
	)
	(segment
		(start 125.68 58.87)
		(end 125.16 58.35)
		(width 0.15)
		(layer "B.Cu")
		(net 158)
	)
	(segment
		(start 125.86 58.87)
		(end 125.68 58.87)
		(width 0.15)
		(layer "B.Cu")
		(net 158)
	)
	(segment
		(start 137.57 74.53)
		(end 137.57 66.51)
		(width 0.162)
		(layer "In4.Cu")
		(net 158)
	)
	(segment
		(start 137.57 62.91)
		(end 136.76 62.1)
		(width 0.162)
		(layer "In4.Cu")
		(net 158)
	)
	(segment
		(start 126.705 85.454)
		(end 126.701 85.45)
		(width 0.15)
		(layer "In4.Cu")
		(net 158)
	)
	(segment
		(start 126.701 85.199)
		(end 127.15 84.75)
		(width 0.162)
		(layer "In4.Cu")
		(net 158)
	)
	(segment
		(start 125.86 58.69)
		(end 125.86 58.87)
		(width 0.162)
		(layer "In4.Cu")
		(net 158)
	)
	(segment
		(start 137.57 65.71)
		(end 137.57 62.91)
		(width 0.162)
		(layer "In4.Cu")
		(net 158)
	)
	(segment
		(start 126.709 80.671)
		(end 128.23 79.15)
		(width 0.162)
		(layer "In4.Cu")
		(net 158)
	)
	(segment
		(start 126.705 85.905)
		(end 126.705 85.454)
		(width 0.15)
		(layer "In4.Cu")
		(net 158)
	)
	(segment
		(start 127.15 84.75)
		(end 127.15 83.5)
		(width 0.162)
		(layer "In4.Cu")
		(net 158)
	)
	(segment
		(start 137.57 65.823066)
		(end 137.57 65.71)
		(width 0.162)
		(layer "In4.Cu")
		(net 158)
	)
	(segment
		(start 127.1 86.3)
		(end 126.705 85.905)
		(width 0.15)
		(layer "In4.Cu")
		(net 158)
	)
	(segment
		(start 136.48 62.1)
		(end 134.11 59.73)
		(width 0.162)
		(layer "In4.Cu")
		(net 158)
	)
	(segment
		(start 132.95 79.15)
		(end 137.57 74.53)
		(width 0.162)
		(layer "In4.Cu")
		(net 158)
	)
	(segment
		(start 127.15 83.5)
		(end 126.709 83.059)
		(width 0.162)
		(layer "In4.Cu")
		(net 158)
	)
	(segment
		(start 136.76 62.1)
		(end 136.48 62.1)
		(width 0.162)
		(layer "In4.Cu")
		(net 158)
	)
	(segment
		(start 133.42 57.55)
		(end 127 57.55)
		(width 0.162)
		(layer "In4.Cu")
		(net 158)
	)
	(segment
		(start 128.23 79.15)
		(end 132.95 79.15)
		(width 0.162)
		(layer "In4.Cu")
		(net 158)
	)
	(segment
		(start 134.11 59.73)
		(end 134.11 58.24)
		(width 0.162)
		(layer "In4.Cu")
		(net 158)
	)
	(segment
		(start 127 57.55)
		(end 125.86 58.69)
		(width 0.162)
		(layer "In4.Cu")
		(net 158)
	)
	(segment
		(start 126.701 85.45)
		(end 126.701 85.199)
		(width 0.162)
		(layer "In4.Cu")
		(net 158)
	)
	(segment
		(start 134.11 58.24)
		(end 133.42 57.55)
		(width 0.162)
		(layer "In4.Cu")
		(net 158)
	)
	(segment
		(start 137.283066 66.223066)
		(end 137.283066 66.11)
		(width 0.162)
		(layer "In4.Cu")
		(net 158)
	)
	(segment
		(start 126.709 83.059)
		(end 126.709 80.671)
		(width 0.162)
		(layer "In4.Cu")
		(net 158)
	)
	(arc
		(start 137.426533 65.966533)
		(mid 137.527979 65.924512)
		(end 137.57 65.823066)
		(width 0.162)
		(layer "In4.Cu")
		(net 158)
	)
	(arc
		(start 137.283066 66.11)
		(mid 137.325087 66.008554)
		(end 137.426533 65.966533)
		(width 0.162)
		(layer "In4.Cu")
		(net 158)
	)
	(arc
		(start 137.426533 66.366533)
		(mid 137.325087 66.324512)
		(end 137.283066 66.223066)
		(width 0.162)
		(layer "In4.Cu")
		(net 158)
	)
	(arc
		(start 137.57 66.51)
		(mid 137.527979 66.408554)
		(end 137.426533 66.366533)
		(width 0.162)
		(layer "In4.Cu")
		(net 158)
	)
	(segment
		(start 121.46 61.34)
		(end 121.86 61.74)
		(width 0.182)
		(layer "F.Cu")
		(net 159)
	)
	(segment
		(start 120.3 85.9)
		(end 119.95 85.55)
		(width 0.2)
		(layer "F.Cu")
		(net 159)
	)
	(segment
		(start 119.95 85.55)
		(end 119.89 85.55)
		(width 0.2)
		(layer "F.Cu")
		(net 159)
	)
	(via
		(at 119.89 85.55)
		(size 0.45)
		(drill 0.1)
		(layers "F.Cu" "B.Cu")
		(net 159)
	)
	(via
		(at 121.46 61.34)
		(size 0.45)
		(drill 0.2)
		(layers "F.Cu" "B.Cu")
		(remove_unused_layers yes)
		(keep_end_layers yes)
		(zone_layer_connections)
		(net 159)
	)
	(segment
		(start 123.23 60.08)
		(end 122.65 60.66)
		(width 0.15)
		(layer "B.Cu")
		(net 159)
	)
	(segment
		(start 123.51 60.08)
		(end 123.23 60.08)
		(width 0.15)
		(layer "B.Cu")
		(net 159)
	)
	(segment
		(start 122.65 60.66)
		(end 122.65 60.81)
		(width 0.15)
		(layer "B.Cu")
		(net 159)
	)
	(segment
		(start 122.52 60.94)
		(end 121.86 60.94)
		(width 0.15)
		(layer "B.Cu")
		(net 159)
	)
	(segment
		(start 121.86 60.94)
		(end 121.46 61.34)
		(width 0.15)
		(layer "B.Cu")
		(net 159)
	)
	(segment
		(start 122.65 60.81)
		(end 122.52 60.94)
		(width 0.15)
		(layer "B.Cu")
		(net 159)
	)
	(segment
		(start 115.210294 70.054)
		(end 115.847706 70.054)
		(width 0.162)
		(layer "In2.Cu")
		(net 159)
	)
	(segment
		(start 115.210294 65.654)
		(end 115.847706 65.654)
		(width 0.162)
		(layer "In2.Cu")
		(net 159)
	)
	(segment
		(start 121.04 61.76)
		(end 121.46 61.34)
		(width 0.162)
		(layer "In2.Cu")
		(net 159)
	)
	(segment
		(start 115.210294 70.854)
		(end 115.847706 70.854)
		(width 0.162)
		(layer "In2.Cu")
		(net 159)
	)
	(segment
		(start 115.210294 71.254)
		(end 115.847706 71.254)
		(width 0.162)
		(layer "In2.Cu")
		(net 159)
	)
	(segment
		(start 115.554 64.146)
		(end 116.899 62.801)
		(width 0.162)
		(layer "In2.Cu")
		(net 159)
	)
	(segment
		(start 115.754 72.054)
		(end 115.847706 72.054)
		(width 0.162)
		(layer "In2.Cu")
		(net 159)
	)
	(segment
		(start 115.554 64.654)
		(end 115.554 64.146)
		(width 0.162)
		(layer "In2.Cu")
		(net 159)
	)
	(segment
		(start 115.210294 66.454)
		(end 115.847706 66.454)
		(width 0.162)
		(layer "In2.Cu")
		(net 159)
	)
	(segment
		(start 115.210294 69.254)
		(end 115.847706 69.254)
		(width 0.162)
		(layer "In2.Cu")
		(net 159)
	)
	(segment
		(start 115.210294 68.054)
		(end 115.847706 68.054)
		(width 0.162)
		(layer "In2.Cu")
		(net 159)
	)
	(segment
		(start 115.210294 65.254)
		(end 115.847706 65.254)
		(width 0.162)
		(layer "In2.Cu")
		(net 159)
	)
	(segment
		(start 115.210294 66.054)
		(end 115.847706 66.054)
		(width 0.162)
		(layer "In2.Cu")
		(net 159)
	)
	(segment
		(start 115.554 81.454)
		(end 115.554 72.254)
		(width 0.162)
		(layer "In2.Cu")
		(net 159)
	)
	(segment
		(start 119.89 85.55)
		(end 119.88 85.54)
		(width 0.162)
		(layer "In2.Cu")
		(net 159)
	)
	(segment
		(start 115.210294 64.854)
		(end 115.354 64.854)
		(width 0.162)
		(layer "In2.Cu")
		(net 159)
	)
	(segment
		(start 115.210294 66.854)
		(end 115.847706 66.854)
		(width 0.162)
		(layer "In2.Cu")
		(net 159)
	)
	(segment
		(start 115.210294 67.654)
		(end 115.847706 67.654)
		(width 0.162)
		(layer "In2.Cu")
		(net 159)
	)
	(segment
		(start 115.210294 68.454)
		(end 115.847706 68.454)
		(width 0.162)
		(layer "In2.Cu")
		(net 159)
	)
	(segment
		(start 119.25 62.45)
		(end 119.96 62.45)
		(width 0.162)
		(layer "In2.Cu")
		(net 159)
	)
	(segment
		(start 119.88 85.54)
		(end 119.64 85.54)
		(width 0.162)
		(layer "In2.Cu")
		(net 159)
	)
	(segment
		(start 115.847706 71.654)
		(end 115.754 71.654)
		(width 0.162)
		(layer "In2.Cu")
		(net 159)
	)
	(segment
		(start 118.899 62.801)
		(end 119.25 62.45)
		(width 0.162)
		(layer "In2.Cu")
		(net 159)
	)
	(segment
		(start 115.210294 67.254)
		(end 115.847706 67.254)
		(width 0.162)
		(layer "In2.Cu")
		(net 159)
	)
	(segment
		(start 119.64 85.54)
		(end 115.554 81.454)
		(width 0.162)
		(layer "In2.Cu")
		(net 159)
	)
	(segment
		(start 115.210294 69.654)
		(end 115.847706 69.654)
		(width 0.162)
		(layer "In2.Cu")
		(net 159)
	)
	(segment
		(start 115.210294 70.454)
		(end 115.847706 70.454)
		(width 0.162)
		(layer "In2.Cu")
		(net 159)
	)
	(segment
		(start 115.754 71.654)
		(end 115.210294 71.654)
		(width 0.162)
		(layer "In2.Cu")
		(net 159)
	)
	(segment
		(start 116.899 62.801)
		(end 118.899 62.801)
		(width 0.162)
		(layer "In2.Cu")
		(net 159)
	)
	(segment
		(start 115.210294 68.854)
		(end 115.847706 68.854)
		(width 0.162)
		(layer "In2.Cu")
		(net 159)
	)
	(segment
		(start 119.96 62.45)
		(end 120.65 61.76)
		(width 0.162)
		(layer "In2.Cu")
		(net 159)
	)
	(segment
		(start 120.65 61.76)
		(end 121.04 61.76)
		(width 0.162)
		(layer "In2.Cu")
		(net 159)
	)
	(arc
		(start 115.354 64.854)
		(mid 115.495421 64.795421)
		(end 115.554 64.654)
		(width 0.162)
		(layer "In2.Cu")
		(net 159)
	)
	(arc
		(start 115.010294 65.054)
		(mid 115.068873 64.912579)
		(end 115.210294 64.854)
		(width 0.162)
		(layer "In2.Cu")
		(net 159)
	)
	(arc
		(start 115.847706 65.654)
		(mid 115.989127 65.595421)
		(end 116.047706 65.454)
		(width 0.162)
		(layer "In2.Cu")
		(net 159)
	)
	(arc
		(start 116.047706 69.454)
		(mid 115.989127 69.312579)
		(end 115.847706 69.254)
		(width 0.162)
		(layer "In2.Cu")
		(net 159)
	)
	(arc
		(start 116.047706 68.654)
		(mid 115.989127 68.512579)
		(end 115.847706 68.454)
		(width 0.162)
		(layer "In2.Cu")
		(net 159)
	)
	(arc
		(start 115.210294 66.854)
		(mid 115.068873 66.795421)
		(end 115.010294 66.654)
		(width 0.162)
		(layer "In2.Cu")
		(net 159)
	)
	(arc
		(start 115.847706 69.654)
		(mid 115.989127 69.595421)
		(end 116.047706 69.454)
		(width 0.162)
		(layer "In2.Cu")
		(net 159)
	)
	(arc
		(start 116.047706 71.854)
		(mid 115.989127 71.712579)
		(end 115.847706 71.654)
		(width 0.162)
		(layer "In2.Cu")
		(net 159)
	)
	(arc
		(start 116.047706 66.254)
		(mid 115.989127 66.112579)
		(end 115.847706 66.054)
		(width 0.162)
		(layer "In2.Cu")
		(net 159)
	)
	(arc
		(start 115.210294 66.054)
		(mid 115.068873 65.995421)
		(end 115.010294 65.854)
		(width 0.162)
		(layer "In2.Cu")
		(net 159)
	)
	(arc
		(start 115.847706 68.854)
		(mid 115.989127 68.795421)
		(end 116.047706 68.654)
		(width 0.162)
		(layer "In2.Cu")
		(net 159)
	)
	(arc
		(start 115.847706 72.054)
		(mid 115.989127 71.995421)
		(end 116.047706 71.854)
		(width 0.162)
		(layer "In2.Cu")
		(net 159)
	)
	(arc
		(start 116.047706 67.854)
		(mid 115.989127 67.712579)
		(end 115.847706 67.654)
		(width 0.162)
		(layer "In2.Cu")
		(net 159)
	)
	(arc
		(start 115.010294 71.454)
		(mid 115.068873 71.312579)
		(end 115.210294 71.254)
		(width 0.162)
		(layer "In2.Cu")
		(net 159)
	)
	(arc
		(start 115.847706 70.454)
		(mid 115.989127 70.395421)
		(end 116.047706 70.254)
		(width 0.162)
		(layer "In2.Cu")
		(net 159)
	)
	(arc
		(start 115.210294 70.054)
		(mid 115.068873 69.995421)
		(end 115.010294 69.854)
		(width 0.162)
		(layer "In2.Cu")
		(net 159)
	)
	(arc
		(start 115.847706 68.054)
		(mid 115.989127 67.995421)
		(end 116.047706 67.854)
		(width 0.162)
		(layer "In2.Cu")
		(net 159)
	)
	(arc
		(start 115.847706 67.254)
		(mid 115.989127 67.195421)
		(end 116.047706 67.054)
		(width 0.162)
		(layer "In2.Cu")
		(net 159)
	)
	(arc
		(start 116.047706 65.454)
		(mid 115.989127 65.312579)
		(end 115.847706 65.254)
		(width 0.162)
		(layer "In2.Cu")
		(net 159)
	)
	(arc
		(start 115.010294 68.254)
		(mid 115.068873 68.112579)
		(end 115.210294 68.054)
		(width 0.162)
		(layer "In2.Cu")
		(net 159)
	)
	(arc
		(start 116.047706 71.054)
		(mid 115.989127 70.912579)
		(end 115.847706 70.854)
		(width 0.162)
		(layer "In2.Cu")
		(net 159)
	)
	(arc
		(start 115.210294 68.454)
		(mid 115.068873 68.395421)
		(end 115.010294 68.254)
		(width 0.162)
		(layer "In2.Cu")
		(net 159)
	)
	(arc
		(start 115.010294 69.054)
		(mid 115.068873 68.912579)
		(end 115.210294 68.854)
		(width 0.162)
		(layer "In2.Cu")
		(net 159)
	)
	(arc
		(start 115.010294 65.854)
		(mid 115.068873 65.712579)
		(end 115.210294 65.654)
		(width 0.162)
		(layer "In2.Cu")
		(net 159)
	)
	(arc
		(start 115.010294 67.454)
		(mid 115.068873 67.312579)
		(end 115.210294 67.254)
		(width 0.162)
		(layer "In2.Cu")
		(net 159)
	)
	(arc
		(start 115.847706 66.454)
		(mid 115.989127 66.395421)
		(end 116.047706 66.254)
		(width 0.162)
		(layer "In2.Cu")
		(net 159)
	)
	(arc
		(start 116.047706 70.254)
		(mid 115.989127 70.112579)
		(end 115.847706 70.054)
		(width 0.162)
		(layer "In2.Cu")
		(net 159)
	)
	(arc
		(start 115.210294 65.254)
		(mid 115.068873 65.195421)
		(end 115.010294 65.054)
		(width 0.162)
		(layer "In2.Cu")
		(net 159)
	)
	(arc
		(start 115.210294 67.654)
		(mid 115.068873 67.595421)
		(end 115.010294 67.454)
		(width 0.162)
		(layer "In2.Cu")
		(net 159)
	)
	(arc
		(start 116.047706 67.054)
		(mid 115.989127 66.912579)
		(end 115.847706 66.854)
		(width 0.162)
		(layer "In2.Cu")
		(net 159)
	)
	(arc
		(start 115.847706 71.254)
		(mid 115.989127 71.195421)
		(end 116.047706 71.054)
		(width 0.162)
		(layer "In2.Cu")
		(net 159)
	)
	(arc
		(start 115.554 72.254)
		(mid 115.612579 72.112579)
		(end 115.754 72.054)
		(width 0.162)
		(layer "In2.Cu")
		(net 159)
	)
	(arc
		(start 115.210294 71.654)
		(mid 115.068873 71.595421)
		(end 115.010294 71.454)
		(width 0.162)
		(layer "In2.Cu")
		(net 159)
	)
	(arc
		(start 115.010294 70.654)
		(mid 115.068873 70.512579)
		(end 115.210294 70.454)
		(width 0.162)
		(layer "In2.Cu")
		(net 159)
	)
	(arc
		(start 115.010294 69.854)
		(mid 115.068873 69.712579)
		(end 115.210294 69.654)
		(width 0.162)
		(layer "In2.Cu")
		(net 159)
	)
	(arc
		(start 115.210294 69.254)
		(mid 115.068873 69.195421)
		(end 115.010294 69.054)
		(width 0.162)
		(layer "In2.Cu")
		(net 159)
	)
	(arc
		(start 115.010294 66.654)
		(mid 115.068873 66.512579)
		(end 115.210294 66.454)
		(width 0.162)
		(layer "In2.Cu")
		(net 159)
	)
	(arc
		(start 115.210294 70.854)
		(mid 115.068873 70.795421)
		(end 115.010294 70.654)
		(width 0.162)
		(layer "In2.Cu")
		(net 159)
	)
	(segment
		(start 122.26 61.34)
		(end 122.66 61.74)
		(width 0.182)
		(layer "F.Cu")
		(net 160)
	)
	(segment
		(start 121.1 86.7)
		(end 120.73 86.33)
		(width 0.15)
		(layer "F.Cu")
		(net 160)
	)
	(via
		(at 120.73 86.33)
		(size 0.45)
		(drill 0.2)
		(layers "F.Cu" "B.Cu")
		(remove_unused_layers yes)
		(keep_end_layers yes)
		(zone_layer_connections)
		(net 160)
	)
	(via
		(at 122.26 61.34)
		(size 0.45)
		(drill 0.2)
		(layers "F.Cu" "B.Cu")
		(remove_unused_layers yes)
		(keep_end_layers yes)
		(zone_layer_connections)
		(net 160)
	)
	(segment
		(start 122.26 61.34)
		(end 122.48 61.34)
		(width 0.15)
		(layer "B.Cu")
		(net 160)
	)
	(segment
		(start 123.17 60.58)
		(end 123.51 60.58)
		(width 0.15)
		(layer "B.Cu")
		(net 160)
	)
	(segment
		(start 123 60.75)
		(end 123.17 60.58)
		(width 0.15)
		(layer "B.Cu")
		(net 160)
	)
	(segment
		(start 123 60.82)
		(end 123 60.75)
		(width 0.15)
		(layer "B.Cu")
		(net 160)
	)
	(segment
		(start 122.48 61.34)
		(end 123 60.82)
		(width 0.15)
		(layer "B.Cu")
		(net 160)
	)
	(segment
		(start 116.037279 78.926)
		(end 116.794721 78.926)
		(width 0.162)
		(layer "In2.Cu")
		(net 160)
	)
	(segment
		(start 116.116 79.726)
		(end 116.794721 79.726)
		(width 0.162)
		(layer "In2.Cu")
		(net 160)
	)
	(segment
		(start 116.316 64.454)
		(end 117.55 63.22)
		(width 0.162)
		(layer "In2.Cu")
		(net 160)
	)
	(segment
		(start 116.037279 78.526)
		(end 116.794721 78.526)
		(width 0.162)
		(layer "In2.Cu")
		(net 160)
	)
	(segment
		(start 116.037279 77.326)
		(end 116.794721 77.326)
		(width 0.162)
		(layer "In2.Cu")
		(net 160)
	)
	(segment
		(start 120.3 85.2)
		(end 116.316 81.216)
		(width 0.162)
		(layer "In2.Cu")
		(net 160)
	)
	(segment
		(start 116.037279 76.926)
		(end 116.794721 76.926)
		(width 0.162)
		(layer "In2.Cu")
		(net 160)
	)
	(segment
		(start 120.85 62.98)
		(end 121.271 62.559)
		(width 0.162)
		(layer "In2.Cu")
		(net 160)
	)
	(segment
		(start 116.316 73.126)
		(end 116.316 64.454)
		(width 0.162)
		(layer "In2.Cu")
		(net 160)
	)
	(segment
		(start 119.07 63.22)
		(end 119.31 62.98)
		(width 0.162)
		(layer "In2.Cu")
		(net 160)
	)
	(segment
		(start 116.037279 75.726)
		(end 116.794721 75.726)
		(width 0.162)
		(layer "In2.Cu")
		(net 160)
	)
	(segment
		(start 116.037279 74.126)
		(end 116.794721 74.126)
		(width 0.162)
		(layer "In2.Cu")
		(net 160)
	)
	(segment
		(start 116.037279 74.526)
		(end 116.794721 74.526)
		(width 0.162)
		(layer "In2.Cu")
		(net 160)
	)
	(segment
		(start 116.037279 79.726)
		(end 116.116 79.726)
		(width 0.162)
		(layer "In2.Cu")
		(net 160)
	)
	(segment
		(start 116.037279 78.126)
		(end 116.794721 78.126)
		(width 0.162)
		(layer "In2.Cu")
		(net 160)
	)
	(segment
		(start 116.037279 73.726)
		(end 116.794721 73.726)
		(width 0.162)
		(layer "In2.Cu")
		(net 160)
	)
	(segment
		(start 122.26 62.07)
		(end 122.26 61.34)
		(width 0.162)
		(layer "In2.Cu")
		(net 160)
	)
	(segment
		(start 121.771 62.559)
		(end 122.26 62.07)
		(width 0.162)
		(layer "In2.Cu")
		(net 160)
	)
	(segment
		(start 116.116 80.126)
		(end 116.037279 80.126)
		(width 0.162)
		(layer "In2.Cu")
		(net 160)
	)
	(segment
		(start 116.037279 76.526)
		(end 116.794721 76.526)
		(width 0.162)
		(layer "In2.Cu")
		(net 160)
	)
	(segment
		(start 117.55 63.22)
		(end 119.07 63.22)
		(width 0.162)
		(layer "In2.Cu")
		(net 160)
	)
	(segment
		(start 116.037279 74.926)
		(end 116.794721 74.926)
		(width 0.162)
		(layer "In2.Cu")
		(net 160)
	)
	(segment
		(start 116.037279 73.326)
		(end 116.116 73.326)
		(width 0.162)
		(layer "In2.Cu")
		(net 160)
	)
	(segment
		(start 120.73 86.33)
		(end 120.3 85.9)
		(width 0.162)
		(layer "In2.Cu")
		(net 160)
	)
	(segment
		(start 116.037279 76.126)
		(end 116.794721 76.126)
		(width 0.162)
		(layer "In2.Cu")
		(net 160)
	)
	(segment
		(start 116.316 81.216)
		(end 116.316 80.326)
		(width 0.162)
		(layer "In2.Cu")
		(net 160)
	)
	(segment
		(start 116.037279 79.326)
		(end 116.794721 79.326)
		(width 0.162)
		(layer "In2.Cu")
		(net 160)
	)
	(segment
		(start 116.037279 77.726)
		(end 116.794721 77.726)
		(width 0.162)
		(layer "In2.Cu")
		(net 160)
	)
	(segment
		(start 116.037279 75.326)
		(end 116.794721 75.326)
		(width 0.162)
		(layer "In2.Cu")
		(net 160)
	)
	(segment
		(start 119.31 62.98)
		(end 120.85 62.98)
		(width 0.162)
		(layer "In2.Cu")
		(net 160)
	)
	(segment
		(start 120.3 85.9)
		(end 120.3 85.2)
		(width 0.162)
		(layer "In2.Cu")
		(net 160)
	)
	(segment
		(start 121.271 62.559)
		(end 121.771 62.559)
		(width 0.162)
		(layer "In2.Cu")
		(net 160)
	)
	(arc
		(start 115.837279 78.326)
		(mid 115.895858 78.184579)
		(end 116.037279 78.126)
		(width 0.162)
		(layer "In2.Cu")
		(net 160)
	)
	(arc
		(start 116.037279 80.126)
		(mid 115.895858 80.067421)
		(end 115.837279 79.926)
		(width 0.162)
		(layer "In2.Cu")
		(net 160)
	)
	(arc
		(start 115.837279 75.126)
		(mid 115.895858 74.984579)
		(end 116.037279 74.926)
		(width 0.162)
		(layer "In2.Cu")
		(net 160)
	)
	(arc
		(start 116.994721 73.926)
		(mid 116.936142 73.784579)
		(end 116.794721 73.726)
		(width 0.162)
		(layer "In2.Cu")
		(net 160)
	)
	(arc
		(start 116.994721 78.726)
		(mid 116.936142 78.584579)
		(end 116.794721 78.526)
		(width 0.162)
		(layer "In2.Cu")
		(net 160)
	)
	(arc
		(start 116.994721 77.126)
		(mid 116.936142 76.984579)
		(end 116.794721 76.926)
		(width 0.162)
		(layer "In2.Cu")
		(net 160)
	)
	(arc
		(start 115.837279 74.326)
		(mid 115.895858 74.184579)
		(end 116.037279 74.126)
		(width 0.162)
		(layer "In2.Cu")
		(net 160)
	)
	(arc
		(start 116.794721 76.526)
		(mid 116.936142 76.467421)
		(end 116.994721 76.326)
		(width 0.162)
		(layer "In2.Cu")
		(net 160)
	)
	(arc
		(start 115.837279 76.726)
		(mid 115.895858 76.584579)
		(end 116.037279 76.526)
		(width 0.162)
		(layer "In2.Cu")
		(net 160)
	)
	(arc
		(start 116.794721 74.126)
		(mid 116.936142 74.067421)
		(end 116.994721 73.926)
		(width 0.162)
		(layer "In2.Cu")
		(net 160)
	)
	(arc
		(start 116.794721 75.726)
		(mid 116.936142 75.667421)
		(end 116.994721 75.526)
		(width 0.162)
		(layer "In2.Cu")
		(net 160)
	)
	(arc
		(start 116.037279 79.326)
		(mid 115.895858 79.267421)
		(end 115.837279 79.126)
		(width 0.162)
		(layer "In2.Cu")
		(net 160)
	)
	(arc
		(start 116.037279 75.326)
		(mid 115.895858 75.267421)
		(end 115.837279 75.126)
		(width 0.162)
		(layer "In2.Cu")
		(net 160)
	)
	(arc
		(start 116.037279 77.726)
		(mid 115.895858 77.667421)
		(end 115.837279 77.526)
		(width 0.162)
		(layer "In2.Cu")
		(net 160)
	)
	(arc
		(start 116.037279 74.526)
		(mid 115.895858 74.467421)
		(end 115.837279 74.326)
		(width 0.162)
		(layer "In2.Cu")
		(net 160)
	)
	(arc
		(start 116.794721 78.926)
		(mid 116.936142 78.867421)
		(end 116.994721 78.726)
		(width 0.162)
		(layer "In2.Cu")
		(net 160)
	)
	(arc
		(start 116.037279 76.926)
		(mid 115.895858 76.867421)
		(end 115.837279 76.726)
		(width 0.162)
		(layer "In2.Cu")
		(net 160)
	)
	(arc
		(start 115.837279 75.926)
		(mid 115.895858 75.784579)
		(end 116.037279 75.726)
		(width 0.162)
		(layer "In2.Cu")
		(net 160)
	)
	(arc
		(start 115.837279 73.526)
		(mid 115.895858 73.384579)
		(end 116.037279 73.326)
		(width 0.162)
		(layer "In2.Cu")
		(net 160)
	)
	(arc
		(start 116.794721 77.326)
		(mid 116.936142 77.267421)
		(end 116.994721 77.126)
		(width 0.162)
		(layer "In2.Cu")
		(net 160)
	)
	(arc
		(start 115.837279 79.926)
		(mid 115.895858 79.784579)
		(end 116.037279 79.726)
		(width 0.162)
		(layer "In2.Cu")
		(net 160)
	)
	(arc
		(start 116.794721 74.926)
		(mid 116.936142 74.867421)
		(end 116.994721 74.726)
		(width 0.162)
		(layer "In2.Cu")
		(net 160)
	)
	(arc
		(start 116.037279 78.526)
		(mid 115.895858 78.467421)
		(end 115.837279 78.326)
		(width 0.162)
		(layer "In2.Cu")
		(net 160)
	)
	(arc
		(start 116.794721 79.726)
		(mid 116.936142 79.667421)
		(end 116.994721 79.526)
		(width 0.162)
		(layer "In2.Cu")
		(net 160)
	)
	(arc
		(start 116.994721 75.526)
		(mid 116.936142 75.384579)
		(end 116.794721 75.326)
		(width 0.162)
		(layer "In2.Cu")
		(net 160)
	)
	(arc
		(start 116.794721 78.126)
		(mid 116.936142 78.067421)
		(end 116.994721 77.926)
		(width 0.162)
		(layer "In2.Cu")
		(net 160)
	)
	(arc
		(start 116.037279 76.126)
		(mid 115.895858 76.067421)
		(end 115.837279 75.926)
		(width 0.162)
		(layer "In2.Cu")
		(net 160)
	)
	(arc
		(start 116.037279 73.726)
		(mid 115.895858 73.667421)
		(end 115.837279 73.526)
		(width 0.162)
		(layer "In2.Cu")
		(net 160)
	)
	(arc
		(start 116.994721 77.926)
		(mid 116.936142 77.784579)
		(end 116.794721 77.726)
		(width 0.162)
		(layer "In2.Cu")
		(net 160)
	)
	(arc
		(start 116.116 73.326)
		(mid 116.257421 73.267421)
		(end 116.316 73.126)
		(width 0.162)
		(layer "In2.Cu")
		(net 160)
	)
	(arc
		(start 116.994721 76.326)
		(mid 116.936142 76.184579)
		(end 116.794721 76.126)
		(width 0.162)
		(layer "In2.Cu")
		(net 160)
	)
	(arc
		(start 116.316 80.326)
		(mid 116.257421 80.184579)
		(end 116.116 80.126)
		(width 0.162)
		(layer "In2.Cu")
		(net 160)
	)
	(arc
		(start 116.994721 74.726)
		(mid 116.936142 74.584579)
		(end 116.794721 74.526)
		(width 0.162)
		(layer "In2.Cu")
		(net 160)
	)
	(arc
		(start 116.994721 79.526)
		(mid 116.936142 79.384579)
		(end 116.794721 79.326)
		(width 0.162)
		(layer "In2.Cu")
		(net 160)
	)
	(arc
		(start 115.837279 77.526)
		(mid 115.895858 77.384579)
		(end 116.037279 77.326)
		(width 0.162)
		(layer "In2.Cu")
		(net 160)
	)
	(arc
		(start 115.837279 79.126)
		(mid 115.895858 78.984579)
		(end 116.037279 78.926)
		(width 0.162)
		(layer "In2.Cu")
		(net 160)
	)
	(segment
		(start 126.7 83.72)
		(end 126.71 83.71)
		(width 0.15)
		(layer "F.Cu")
		(net 161)
	)
	(segment
		(start 126.26 63.79)
		(end 126.21 63.79)
		(width 0.182)
		(layer "F.Cu")
		(net 161)
	)
	(segment
		(start 126.21 63.79)
		(end 125.86 64.14)
		(width 0.182)
		(layer "F.Cu")
		(net 161)
	)
	(segment
		(start 126.7 84.3)
		(end 126.7 83.72)
		(width 0.15)
		(layer "F.Cu")
		(net 161)
	)
	(via
		(at 126.26 63.79)
		(size 0.45)
		(drill 0.2)
		(layers "F.Cu" "B.Cu")
		(remove_unused_layers yes)
		(keep_end_layers yes)
		(zone_layer_connections)
		(net 161)
	)
	(via
		(at 126.71 83.71)
		(size 0.45)
		(drill 0.2)
		(layers "F.Cu" "B.Cu")
		(remove_unused_layers yes)
		(keep_end_layers yes)
		(zone_layer_connections)
		(net 161)
	)
	(segment
		(start 125.79 64.26)
		(end 125.79 64.66)
		(width 0.15)
		(layer "B.Cu")
		(net 161)
	)
	(segment
		(start 125.46 64.99)
		(end 125.01 64.99)
		(width 0.15)
		(layer "B.Cu")
		(net 161)
	)
	(segment
		(start 126.26 63.79)
		(end 125.79 64.26)
		(width 0.15)
		(layer "B.Cu")
		(net 161)
	)
	(segment
		(start 125.79 64.66)
		(end 125.46 64.99)
		(width 0.15)
		(layer "B.Cu")
		(net 161)
	)
	(segment
		(start 132.009289 64.482181)
		(end 132.009289 64.482182)
		(width 0.162)
		(layer "In2.Cu")
		(net 161)
	)
	(segment
		(start 126.77 79.41)
		(end 127.29688 79.41)
		(width 0.162)
		(layer "In2.Cu")
		(net 161)
	)
	(segment
		(start 132.009289 64.482182)
		(end 131.337535 65.153932)
		(width 0.162)
		(layer "In2.Cu")
		(net 161)
	)
	(segment
		(start 128.151514 76.931474)
		(end 128.167862 76.915125)
		(width 0.162)
		(layer "In2.Cu")
		(net 161)
	)
	(segment
		(start 126.77 78.01)
		(end 126.77 77.96)
		(width 0.162)
		(layer "In2.Cu")
		(net 161)
	)
	(segment
		(start 127.29688 78.21)
		(end 126.97 78.21)
		(width 0.162)
		(layer "In2.Cu")
		(net 161)
	)
	(segment
		(start 128.7172 76.365788)
		(end 128.733548 76.349439)
		(width 0.162)
		(layer "In2.Cu")
		(net 161)
	)
	(segment
		(start 126.97 78.61)
		(end 127.29688 78.61)
		(width 0.162)
		(layer "In2.Cu")
		(net 161)
	)
	(segment
		(start 131.905 70.435)
		(end 132.88 70.435)
		(width 0.162)
		(layer "In2.Cu")
		(net 161)
	)
	(segment
		(start 131.905 67.635)
		(end 132.88 67.635)
		(width 0.162)
		(layer "In2.Cu")
		(net 161)
	)
	(segment
		(start 132.08 72.47)
		(end 132.08 71.41)
		(width 0.162)
		(layer "In2.Cu")
		(net 161)
	)
	(segment
		(start 131.905 70.835)
		(end 132.88 70.835)
		(width 0.162)
		(layer "In2.Cu")
		(net 161)
	)
	(segment
		(start 128.733548 75.81645)
		(end 132.08 72.47)
		(width 0.162)
		(layer "In2.Cu")
		(net 161)
	)
	(segment
		(start 126.77 77.78)
		(end 127.05284 77.49716)
		(width 0.162)
		(layer "In2.Cu")
		(net 161)
	)
	(segment
		(start 131.905 68.035)
		(end 132.88 68.035)
		(width 0.162)
		(layer "In2.Cu")
		(net 161)
	)
	(segment
		(start 131.905 66.835)
		(end 132.88 66.835)
		(width 0.162)
		(layer "In2.Cu")
		(net 161)
	)
	(segment
		(start 126.65656 79.81)
		(end 127.29688 79.81)
		(width 0.162)
		(layer "In2.Cu")
		(net 161)
	)
	(segment
		(start 131.905 70.035)
		(end 132.88 70.035)
		(width 0.162)
		(layer "In2.Cu")
		(net 161)
	)
	(segment
		(start 131.905 67.235)
		(end 132.88 67.235)
		(width 0.162)
		(layer "In2.Cu")
		(net 161)
	)
	(segment
		(start 131.905 69.635)
		(end 132.88 69.635)
		(width 0.162)
		(layer "In2.Cu")
		(net 161)
	)
	(segment
		(start 131.905 66.435)
		(end 132.88 66.435)
		(width 0.162)
		(layer "In2.Cu")
		(net 161)
	)
	(segment
		(start 131.23147 64.41147)
		(end 130.97 64.15)
		(width 0.162)
		(layer "In2.Cu")
		(net 161)
	)
	(segment
		(start 128.167862 76.382136)
		(end 128.184212 76.365788)
		(width 0.162)
		(layer "In2.Cu")
		(net 161)
	)
	(segment
		(start 126.71 83.71)
		(end 126.77 83.65)
		(width 0.162)
		(layer "In2.Cu")
		(net 161)
	)
	(segment
		(start 128.167861 76.382136)
		(end 128.167862 76.382136)
		(width 0.162)
		(layer "In2.Cu")
		(net 161)
	)
	(segment
		(start 128.717201 76.365787)
		(end 128.7172 76.365788)
		(width 0.162)
		(layer "In2.Cu")
		(net 161)
	)
	(segment
		(start 127.585829 77.497159)
		(end 127.585828 77.49716)
		(width 0.162)
		(layer "In2.Cu")
		(net 161)
	)
	(segment
		(start 131.905 68.435)
		(end 132.88 68.435)
		(width 0.162)
		(layer "In2.Cu")
		(net 161)
	)
	(segment
		(start 132.08 65.86)
		(end 132.08 65.26)
		(width 0.162)
		(layer "In2.Cu")
		(net 161)
	)
	(segment
		(start 131.054692 65.153931)
		(end 131.054693 65.153932)
		(width 0.162)
		(layer "In2.Cu")
		(net 161)
	)
	(segment
		(start 131.905 69.235)
		(end 132.88 69.235)
		(width 0.162)
		(layer "In2.Cu")
		(net 161)
	)
	(segment
		(start 131.73 67.06)
		(end 131.73 67.01)
		(width 0.162)
		(layer "In2.Cu")
		(net 161)
	)
	(segment
		(start 126.54312 79.69656)
		(end 126.54312 79.52344)
		(width 0.162)
		(layer "In2.Cu")
		(net 161)
	)
	(segment
		(start 131.73 69.46)
		(end 131.73 69.41)
		(width 0.162)
		(layer "In2.Cu")
		(net 161)
	)
	(segment
		(start 127.602175 76.947822)
		(end 127.602176 76.947822)
		(width 0.162)
		(layer "In2.Cu")
		(net 161)
	)
	(segment
		(start 131.23147 64.411469)
		(end 131.23147 64.41147)
		(width 0.162)
		(layer "In2.Cu")
		(net 161)
	)
	(segment
		(start 126.97 80.21)
		(end 127.29688 80.21)
		(width 0.162)
		(layer "In2.Cu")
		(net 161)
	)
	(segment
		(start 131.054694 64.87109)
		(end 131.231469 64.694312)
		(width 0.162)
		(layer "In2.Cu")
		(net 161)
	)
	(segment
		(start 131.905 68.835)
		(end 132.88 68.835)
		(width 0.162)
		(layer "In2.Cu")
		(net 161)
	)
	(segment
		(start 132.292131 64.482181)
		(end 132.292132 64.482182)
		(width 0.162)
		(layer "In2.Cu")
		(net 161)
	)
	(segment
		(start 127.585828 77.49716)
		(end 127.602176 77.480811)
		(width 0.162)
		(layer "In2.Cu")
		(net 161)
	)
	(segment
		(start 131.73 67.86)
		(end 131.73 67.81)
		(width 0.162)
		(layer "In2.Cu")
		(net 161)
	)
	(segment
		(start 127.29688 79.01)
		(end 126.97 79.01)
		(width 0.162)
		(layer "In2.Cu")
		(net 161)
	)
	(segment
		(start 126.77 83.65)
		(end 126.77 80.41)
		(width 0.162)
		(layer "In2.Cu")
		(net 161)
	)
	(segment
		(start 132.08 64.977157)
		(end 132.292132 64.765024)
		(width 0.162)
		(layer "In2.Cu")
		(net 161)
	)
	(segment
		(start 131.73 70.26)
		(end 131.73 70.21)
		(width 0.162)
		(layer "In2.Cu")
		(net 161)
	)
	(segment
		(start 126.65656 79.41)
		(end 126.77 79.41)
		(width 0.162)
		(layer "In2.Cu")
		(net 161)
	)
	(segment
		(start 131.73 66.26)
		(end 131.73 66.21)
		(width 0.162)
		(layer "In2.Cu")
		(net 161)
	)
	(segment
		(start 128.733547 75.81645)
		(end 128.733548 75.81645)
		(width 0.162)
		(layer "In2.Cu")
		(net 161)
	)
	(segment
		(start 130.97 64.15)
		(end 126.62 64.15)
		(width 0.162)
		(layer "In2.Cu")
		(net 161)
	)
	(segment
		(start 131.73 68.66)
		(end 131.73 68.61)
		(width 0.162)
		(layer "In2.Cu")
		(net 161)
	)
	(segment
		(start 131.054692 64.871089)
		(end 131.054694 64.87109)
		(width 0.162)
		(layer "In2.Cu")
		(net 161)
	)
	(segment
		(start 126.77 77.96)
		(end 126.77 77.78)
		(width 0.162)
		(layer "In2.Cu")
		(net 161)
	)
	(segment
		(start 128.151515 76.931473)
		(end 128.151514 76.931474)
		(width 0.162)
		(layer "In2.Cu")
		(net 161)
	)
	(segment
		(start 126.62 64.15)
		(end 126.26 63.79)
		(width 0.162)
		(layer "In2.Cu")
		(net 161)
	)
	(segment
		(start 127.602176 76.947822)
		(end 127.618526 76.931474)
		(width 0.162)
		(layer "In2.Cu")
		(net 161)
	)
	(segment
		(start 131.73 71.06)
		(end 131.73 71.01)
		(width 0.162)
		(layer "In2.Cu")
		(net 161)
	)
	(segment
		(start 132.079999 64.977157)
		(end 132.08 64.977157)
		(width 0.162)
		(layer "In2.Cu")
		(net 161)
	)
	(arc
		(start 132.292132 64.482182)
		(mid 132.150711 64.423603)
		(end 132.009289 64.482181)
		(width 0.162)
		(layer "In2.Cu")
		(net 161)
	)
	(arc
		(start 126.97 79.01)
		(mid 126.828579 78.951421)
		(end 126.77 78.81)
		(width 0.162)
		(layer "In2.Cu")
		(net 161)
	)
	(arc
		(start 128.733548 76.349439)
		(mid 128.788741 76.216192)
		(end 128.733548 76.082945)
		(width 0.162)
		(layer "In2.Cu")
		(net 161)
	)
	(arc
		(start 131.905 70.435)
		(mid 131.781256 70.383744)
		(end 131.73 70.26)
		(width 0.162)
		(layer "In2.Cu")
		(net 161)
	)
	(arc
		(start 132.88 67.635)
		(mid 133.021421 67.576421)
		(end 133.08 67.435)
		(width 0.162)
		(layer "In2.Cu")
		(net 161)
	)
	(arc
		(start 132.88 70.835)
		(mid 133.021421 70.776421)
		(end 133.08 70.635)
		(width 0.162)
		(layer "In2.Cu")
		(net 161)
	)
	(arc
		(start 132.88 68.435)
		(mid 133.021421 68.376421)
		(end 133.08 68.235)
		(width 0.162)
		(layer "In2.Cu")
		(net 161)
	)
	(arc
		(start 132.292132 64.765024)
		(mid 132.35071 64.623602)
		(end 132.292131 64.482181)
		(width 0.162)
		(layer "In2.Cu")
		(net 161)
	)
	(arc
		(start 131.054693 65.153932)
		(mid 130.996114 65.012511)
		(end 131.054692 64.871089)
		(width 0.162)
		(layer "In2.Cu")
		(net 161)
	)
	(arc
		(start 131.905 69.635)
		(mid 131.781256 69.583744)
		(end 131.73 69.46)
		(width 0.162)
		(layer "In2.Cu")
		(net 161)
	)
	(arc
		(start 128.450706 76.365788)
		(mid 128.583954 76.42098)
		(end 128.717201 76.365787)
		(width 0.162)
		(layer "In2.Cu")
		(net 161)
	)
	(arc
		(start 126.97 78.21)
		(mid 126.828579 78.151421)
		(end 126.77 78.01)
		(width 0.162)
		(layer "In2.Cu")
		(net 161)
	)
	(arc
		(start 127.49688 79.21)
		(mid 127.438301 79.068579)
		(end 127.29688 79.01)
		(width 0.162)
		(layer "In2.Cu")
		(net 161)
	)
	(arc
		(start 131.337535 65.153932)
		(mid 131.196113 65.21251)
		(end 131.054692 65.153931)
		(width 0.162)
		(layer "In2.Cu")
		(net 161)
	)
	(arc
		(start 128.167862 76.915125)
		(mid 128.223055 76.781878)
		(end 128.167862 76.648631)
		(width 0.162)
		(layer "In2.Cu")
		(net 161)
	)
	(arc
		(start 127.602176 77.214317)
		(mid 127.546983 77.08107)
		(end 127.602175 76.947822)
		(width 0.162)
		(layer "In2.Cu")
		(net 161)
	)
	(arc
		(start 131.905 67.235)
		(mid 131.781256 67.183744)
		(end 131.73 67.06)
		(width 0.162)
		(layer "In2.Cu")
		(net 161)
	)
	(arc
		(start 131.73 67.01)
		(mid 131.781256 66.886256)
		(end 131.905 66.835)
		(width 0.162)
		(layer "In2.Cu")
		(net 161)
	)
	(arc
		(start 128.733548 76.082945)
		(mid 128.678355 75.949698)
		(end 128.733547 75.81645)
		(width 0.162)
		(layer "In2.Cu")
		(net 161)
	)
	(arc
		(start 131.905 66.035)
		(mid 132.028744 65.983744)
		(end 132.08 65.86)
		(width 0.162)
		(layer "In2.Cu")
		(net 161)
	)
	(arc
		(start 126.77 78.81)
		(mid 126.828579 78.668579)
		(end 126.97 78.61)
		(width 0.162)
		(layer "In2.Cu")
		(net 161)
	)
	(arc
		(start 131.905 71.235)
		(mid 131.781256 71.183744)
		(end 131.73 71.06)
		(width 0.162)
		(layer "In2.Cu")
		(net 161)
	)
	(arc
		(start 127.29688 80.21)
		(mid 127.438301 80.151421)
		(end 127.49688 80.01)
		(width 0.162)
		(layer "In2.Cu")
		(net 161)
	)
	(arc
		(start 126.77 80.41)
		(mid 126.828579 80.268579)
		(end 126.97 80.21)
		(width 0.162)
		(layer "In2.Cu")
		(net 161)
	)
	(arc
		(start 127.618526 76.931474)
		(mid 127.751773 76.876281)
		(end 127.88502 76.931474)
		(width 0.162)
		(layer "In2.Cu")
		(net 161)
	)
	(arc
		(start 133.08 66.635)
		(mid 133.021421 66.493579)
		(end 132.88 66.435)
		(width 0.162)
		(layer "In2.Cu")
		(net 161)
	)
	(arc
		(start 126.65656 79.81)
		(mid 126.576346 79.776774)
		(end 126.54312 79.69656)
		(width 0.162)
		(layer "In2.Cu")
		(net 161)
	)
	(arc
		(start 131.905 68.035)
		(mid 131.781256 67.983744)
		(end 131.73 67.86)
		(width 0.162)
		(layer "In2.Cu")
		(net 161)
	)
	(arc
		(start 131.73 70.21)
		(mid 131.781256 70.086256)
		(end 131.905 70.035)
		(width 0.162)
		(layer "In2.Cu")
		(net 161)
	)
	(arc
		(start 133.08 67.435)
		(mid 133.021421 67.293579)
		(end 132.88 67.235)
		(width 0.162)
		(layer "In2.Cu")
		(net 161)
	)
	(arc
		(start 131.73 71.01)
		(mid 131.781256 70.886256)
		(end 131.905 70.835)
		(width 0.162)
		(layer "In2.Cu")
		(net 161)
	)
	(arc
		(start 127.602176 77.480811)
		(mid 127.657369 77.347564)
		(end 127.602176 77.214317)
		(width 0.162)
		(layer "In2.Cu")
		(net 161)
	)
	(arc
		(start 133.08 69.035)
		(mid 133.021421 68.893579)
		(end 132.88 68.835)
		(width 0.162)
		(layer "In2.Cu")
		(net 161)
	)
	(arc
		(start 132.88 66.835)
		(mid 133.021421 66.776421)
		(end 133.08 66.635)
		(width 0.162)
		(layer "In2.Cu")
		(net 161)
	)
	(arc
		(start 133.08 69.835)
		(mid 133.021421 69.693579)
		(end 132.88 69.635)
		(width 0.162)
		(layer "In2.Cu")
		(net 161)
	)
	(arc
		(start 127.05284 77.49716)
		(mid 127.186087 77.441967)
		(end 127.319334 77.49716)
		(width 0.162)
		(layer "In2.Cu")
		(net 161)
	)
	(arc
		(start 131.905 66.435)
		(mid 131.781256 66.383744)
		(end 131.73 66.26)
		(width 0.162)
		(layer "In2.Cu")
		(net 161)
	)
	(arc
		(start 127.49688 78.41)
		(mid 127.438301 78.268579)
		(end 127.29688 78.21)
		(width 0.162)
		(layer "In2.Cu")
		(net 161)
	)
	(arc
		(start 127.88502 76.931474)
		(mid 128.018268 76.986666)
		(end 128.151515 76.931473)
		(width 0.162)
		(layer "In2.Cu")
		(net 161)
	)
	(arc
		(start 127.49688 80.01)
		(mid 127.438301 79.868579)
		(end 127.29688 79.81)
		(width 0.162)
		(layer "In2.Cu")
		(net 161)
	)
	(arc
		(start 131.905 68.835)
		(mid 131.781256 68.783744)
		(end 131.73 68.66)
		(width 0.162)
		(layer "In2.Cu")
		(net 161)
	)
	(arc
		(start 132.08 65.26)
		(mid 132.021421 65.118579)
		(end 132.079999 64.977157)
		(width 0.162)
		(layer "In2.Cu")
		(net 161)
	)
	(arc
		(start 133.08 68.235)
		(mid 133.021421 68.093579)
		(end 132.88 68.035)
		(width 0.162)
		(layer "In2.Cu")
		(net 161)
	)
	(arc
		(start 132.88 70.035)
		(mid 133.021421 69.976421)
		(end 133.08 69.835)
		(width 0.162)
		(layer "In2.Cu")
		(net 161)
	)
	(arc
		(start 127.29688 78.61)
		(mid 127.438301 78.551421)
		(end 127.49688 78.41)
		(width 0.162)
		(layer "In2.Cu")
		(net 161)
	)
	(arc
		(start 126.54312 79.52344)
		(mid 126.576346 79.443226)
		(end 126.65656 79.41)
		(width 0.162)
		(layer "In2.Cu")
		(net 161)
	)
	(arc
		(start 131.73 68.61)
		(mid 131.781256 68.486256)
		(end 131.905 68.435)
		(width 0.162)
		(layer "In2.Cu")
		(net 161)
	)
	(arc
		(start 127.29688 79.41)
		(mid 127.438301 79.351421)
		(end 127.49688 79.21)
		(width 0.162)
		(layer "In2.Cu")
		(net 161)
	)
	(arc
		(start 131.231469 64.694312)
		(mid 131.290048 64.552891)
		(end 131.23147 64.411469)
		(width 0.162)
		(layer "In2.Cu")
		(net 161)
	)
	(arc
		(start 132.08 71.41)
		(mid 132.028744 71.286256)
		(end 131.905 71.235)
		(width 0.162)
		(layer "In2.Cu")
		(net 161)
	)
	(arc
		(start 131.73 67.81)
		(mid 131.781256 67.686256)
		(end 131.905 67.635)
		(width 0.162)
		(layer "In2.Cu")
		(net 161)
	)
	(arc
		(start 131.73 66.21)
		(mid 131.781256 66.086256)
		(end 131.905 66.035)
		(width 0.162)
		(layer "In2.Cu")
		(net 161)
	)
	(arc
		(start 132.88 69.235)
		(mid 133.021421 69.176421)
		(end 133.08 69.035)
		(width 0.162)
		(layer "In2.Cu")
		(net 161)
	)
	(arc
		(start 127.319334 77.49716)
		(mid 127.452582 77.552352)
		(end 127.585829 77.497159)
		(width 0.162)
		(layer "In2.Cu")
		(net 161)
	)
	(arc
		(start 128.167862 76.648631)
		(mid 128.112669 76.515384)
		(end 128.167861 76.382136)
		(width 0.162)
		(layer "In2.Cu")
		(net 161)
	)
	(arc
		(start 133.08 70.635)
		(mid 133.021421 70.493579)
		(end 132.88 70.435)
		(width 0.162)
		(layer "In2.Cu")
		(net 161)
	)
	(arc
		(start 128.184212 76.365788)
		(mid 128.317459 76.310595)
		(end 128.450706 76.365788)
		(width 0.162)
		(layer "In2.Cu")
		(net 161)
	)
	(arc
		(start 131.73 69.41)
		(mid 131.781256 69.286256)
		(end 131.905 69.235)
		(width 0.162)
		(layer "In2.Cu")
		(net 161)
	)
	(segment
		(start 123.5 87.5)
		(end 123.9 87.9)
		(width 0.15)
		(layer "F.Cu")
		(net 162)
	)
	(segment
		(start 125.86 64.94)
		(end 126.26 65.34)
		(width 0.182)
		(layer "F.Cu")
		(net 162)
	)
	(via
		(at 123.9 87.9)
		(size 0.45)
		(drill 0.2)
		(layers "F.Cu" "B.Cu")
		(remove_unused_layers yes)
		(keep_end_layers yes)
		(zone_layer_connections)
		(net 162)
	)
	(via
		(at 126.26 65.34)
		(size 0.45)
		(drill 0.2)
		(layers "F.Cu" "B.Cu")
		(remove_unused_layers yes)
		(keep_end_layers yes)
		(zone_layer_connections)
		(net 162)
	)
	(segment
		(start 125.74 65.49)
		(end 125.01 65.49)
		(width 0.15)
		(layer "B.Cu")
		(net 162)
	)
	(segment
		(start 125.89 65.34)
		(end 125.74 65.49)
		(width 0.15)
		(layer "B.Cu")
		(net 162)
	)
	(segment
		(start 126.26 65.34)
		(end 125.89 65.34)
		(width 0.15)
		(layer "B.Cu")
		(net 162)
	)
	(segment
		(start 130.6751 72.551985)
		(end 130.675098 72.551986)
		(width 0.162)
		(layer "In2.Cu")
		(net 162)
	)
	(segment
		(start 127.174911 75.840041)
		(end 127.608343 76.273471)
		(width 0.162)
		(layer "In2.Cu")
		(net 162)
	)
	(segment
		(start 130.838023 71.235)
		(end 131.23 71.235)
		(width 0.162)
		(layer "In2.Cu")
		(net 162)
	)
	(segment
		(start 131.771977 71.868024)
		(end 131.771977 71.81)
		(width 0.162)
		(layer "In2.Cu")
		(net 162)
	)
	(segment
		(start 131.02298 72.617023)
		(end 131.43 72.21)
		(width 0.162)
		(layer "In2.Cu")
		(net 162)
	)
	(segment
		(start 127.740598 75.274354)
		(end 128.17403 75.707784)
		(width 0.162)
		(layer "In2.Cu")
		(net 162)
	)
	(segment
		(start 123.5 84.8)
		(end 124.2 84.1)
		(width 0.162)
		(layer "In2.Cu")
		(net 162)
	)
	(segment
		(start 130.230319 73.238578)
		(end 130.436777 73.445037)
		(width 0.162)
		(layer "In2.Cu")
		(net 162)
	)
	(segment
		(start 123.5 87.5)
		(end 123.9 87.9)
		(width 0.15)
		(layer "In2.Cu")
		(net 162)
	)
	(segment
		(start 126.32 65.34)
		(end 126.26 65.34)
		(width 0.162)
		(layer "In2.Cu")
		(net 162)
	)
	(segment
		(start 128.412351 74.814733)
		(end 128.739717 75.142097)
		(width 0.162)
		(layer "In2.Cu")
		(net 162)
	)
	(segment
		(start 128.765906 74.036914)
		(end 129.305404 74.57641)
		(width 0.162)
		(layer "In2.Cu")
		(net 162)
	)
	(segment
		(start 129.437661 73.577292)
		(end 129.437659 73.577293)
		(width 0.162)
		(layer "In2.Cu")
		(net 162)
	)
	(segment
		(start 131.600989 71.639012)
		(end 131.600988 71.639012)
		(width 0.162)
		(layer "In2.Cu")
		(net 162)
	)
	(segment
		(start 129.947476 73.350318)
		(end 129.947476 73.350317)
		(width 0.162)
		(layer "In2.Cu")
		(net 162)
	)
	(segment
		(start 131.43 65.9)
		(end 130.06 64.53)
		(width 0.162)
		(layer "In2.Cu")
		(net 162)
	)
	(segment
		(start 126.491977 78.898024)
		(end 126.491977 78.74)
		(width 0.162)
		(layer "In2.Cu")
		(net 162)
	)
	(segment
		(start 130.230318 73.238578)
		(end 130.230319 73.238578)
		(width 0.162)
		(layer "In2.Cu")
		(net 162)
	)
	(segment
		(start 129.437659 73.577293)
		(end 129.871091 74.010723)
		(width 0.162)
		(layer "In2.Cu")
		(net 162)
	)
	(segment
		(start 126.25 78.215)
		(end 126.370989 78.215)
		(width 0.162)
		(layer "In2.Cu")
		(net 162)
	)
	(segment
		(start 123.5 86.1)
		(end 123.5 84.8)
		(width 0.162)
		(layer "In2.Cu")
		(net 162)
	)
	(segment
		(start 128.456873 75.424941)
		(end 128.129508 75.097576)
		(width 0.162)
		(layer "In2.Cu")
		(net 162)
	)
	(segment
		(start 126.491977 78.094012)
		(end 126.491977 77.935988)
		(width 0.162)
		(layer "In2.Cu")
		(net 162)
	)
	(segment
		(start 131.43 71.035)
		(end 131.43 65.9)
		(width 0.162)
		(layer "In2.Cu")
		(net 162)
	)
	(segment
		(start 129.947476 73.350317)
		(end 130.059215 73.238579)
		(width 0.162)
		(layer "In2.Cu")
		(net 162)
	)
	(segment
		(start 131.43 71.635)
		(end 130.838023 71.635)
		(width 0.162)
		(layer "In2.Cu")
		(net 162)
	)
	(segment
		(start 125.458023 78.215)
		(end 126.25 78.215)
		(width 0.162)
		(layer "In2.Cu")
		(net 162)
	)
	(segment
		(start 127.457754 75.274354)
		(end 127.457756 75.274353)
		(width 0.162)
		(layer "In2.Cu")
		(net 162)
	)
	(segment
		(start 130.675098 72.551986)
		(end 130.740136 72.617024)
		(width 0.162)
		(layer "In2.Cu")
		(net 162)
	)
	(segment
		(start 131.600988 72.039012)
		(end 131.600989 72.039012)
		(width 0.162)
		(layer "In2.Cu")
		(net 162)
	)
	(segment
		(start 126.370989 78.619012)
		(end 126.370988 78.619012)
		(width 0.162)
		(layer "In2.Cu")
		(net 162)
	)
	(segment
		(start 128.456872 75.424941)
		(end 128.456873 75.424941)
		(width 0.162)
		(layer "In2.Cu")
		(net 162)
	)
	(segment
		(start 125.63533 84.1)
		(end 126.25 83.48533)
		(width 0.162)
		(layer "In2.Cu")
		(net 162)
	)
	(segment
		(start 127.850157 76.273471)
		(end 127.891186 76.232441)
		(width 0.162)
		(layer "In2.Cu")
		(net 162)
	)
	(segment
		(start 126.370988 79.019012)
		(end 126.370989 79.019012)
		(width 0.162)
		(layer "In2.Cu")
		(net 162)
	)
	(segment
		(start 129.022559 74.859254)
		(end 129.02256 74.859254)
		(width 0.162)
		(layer "In2.Cu")
		(net 162)
	)
	(segment
		(start 131.022978 72.617024)
		(end 131.02298 72.617023)
		(width 0.162)
		(layer "In2.Cu")
		(net 162)
	)
	(segment
		(start 126.25 77.39)
		(end 126.497485 77.142515)
		(width 0.162)
		(layer "In2.Cu")
		(net 162)
	)
	(segment
		(start 126.25 78.615)
		(end 125.458023 78.615)
		(width 0.162)
		(layer "In2.Cu")
		(net 162)
	)
	(segment
		(start 129.02256 74.859254)
		(end 128.483063 74.319757)
		(width 0.162)
		(layer "In2.Cu")
		(net 162)
	)
	(segment
		(start 128.412353 74.814732)
		(end 128.412351 74.814733)
		(width 0.162)
		(layer "In2.Cu")
		(net 162)
	)
	(segment
		(start 126.25 78.619012)
		(end 126.25 78.615)
		(width 0.162)
		(layer "In2.Cu")
		(net 162)
	)
	(segment
		(start 127.325498 76.556315)
		(end 127.325499 76.556315)
		(width 0.162)
		(layer "In2.Cu")
		(net 162)
	)
	(segment
		(start 128.129507 74.814733)
		(end 128.129509 74.814732)
		(width 0.162)
		(layer "In2.Cu")
		(net 162)
	)
	(segment
		(start 130.678591 73.445037)
		(end 130.71962 73.404007)
		(width 0.162)
		(layer "In2.Cu")
		(net 162)
	)
	(segment
		(start 127.78 64.53)
		(end 127.38 64.93)
		(width 0.162)
		(layer "In2.Cu")
		(net 162)
	)
	(segment
		(start 130.112905 74.010723)
		(end 130.153934 73.969693)
		(width 0.162)
		(layer "In2.Cu")
		(net 162)
	)
	(segment
		(start 126.609227 76.405726)
		(end 126.609225 76.405727)
		(width 0.162)
		(layer "In2.Cu")
		(net 162)
	)
	(segment
		(start 127.891186 75.990628)
		(end 127.457755 75.557197)
		(width 0.162)
		(layer "In2.Cu")
		(net 162)
	)
	(segment
		(start 128.981531 75.142097)
		(end 129.02256 75.101067)
		(width 0.162)
		(layer "In2.Cu")
		(net 162)
	)
	(segment
		(start 123.5 86.1)
		(end 123.5 87.5)
		(width 0.15)
		(layer "In2.Cu")
		(net 162)
	)
	(segment
		(start 127.7406 75.274353)
		(end 127.740598 75.274354)
		(width 0.162)
		(layer "In2.Cu")
		(net 162)
	)
	(segment
		(start 131.43 71.639012)
		(end 131.43 71.635)
		(width 0.162)
		(layer "In2.Cu")
		(net 162)
	)
	(segment
		(start 126.326382 76.405728)
		(end 126.326383 76.405726)
		(width 0.162)
		(layer "In2.Cu")
		(net 162)
	)
	(segment
		(start 127.891185 75.990628)
		(end 127.891186 75.990628)
		(width 0.162)
		(layer "In2.Cu")
		(net 162)
	)
	(segment
		(start 124.2 84.1)
		(end 125.63533 84.1)
		(width 0.162)
		(layer "In2.Cu")
		(net 162)
	)
	(segment
		(start 129.588247 74.293567)
		(end 129.154816 73.860136)
		(width 0.162)
		(layer "In2.Cu")
		(net 162)
	)
	(segment
		(start 127.174913 75.84004)
		(end 127.174911 75.840041)
		(width 0.162)
		(layer "In2.Cu")
		(net 162)
	)
	(segment
		(start 126.25 83.48533)
		(end 126.25 79.14)
		(width 0.162)
		(layer "In2.Cu")
		(net 162)
	)
	(segment
		(start 130.71962 73.162194)
		(end 130.392255 72.834829)
		(width 0.162)
		(layer "In2.Cu")
		(net 162)
	)
	(segment
		(start 129.154815 73.577293)
		(end 129.154817 73.577292)
		(width 0.162)
		(layer "In2.Cu")
		(net 162)
	)
	(segment
		(start 130.153934 73.72788)
		(end 129.947475 73.521421)
		(width 0.162)
		(layer "In2.Cu")
		(net 162)
	)
	(segment
		(start 126.609225 76.405727)
		(end 127.042656 76.839158)
		(width 0.162)
		(layer "In2.Cu")
		(net 162)
	)
	(segment
		(start 129.547218 74.57641)
		(end 129.588247 74.53538)
		(width 0.162)
		(layer "In2.Cu")
		(net 162)
	)
	(segment
		(start 126.73 64.93)
		(end 126.32 65.34)
		(width 0.162)
		(layer "In2.Cu")
		(net 162)
	)
	(segment
		(start 126.497485 76.859673)
		(end 126.326382 76.68857)
		(width 0.162)
		(layer "In2.Cu")
		(net 162)
	)
	(segment
		(start 126.25 77.694012)
		(end 126.25 77.39)
		(width 0.162)
		(layer "In2.Cu")
		(net 162)
	)
	(segment
		(start 130.719619 73.162194)
		(end 130.71962 73.162194)
		(width 0.162)
		(layer "In2.Cu")
		(net 162)
	)
	(segment
		(start 126.370988 78.619012)
		(end 126.25 78.619012)
		(width 0.162)
		(layer "In2.Cu")
		(net 162)
	)
	(segment
		(start 131.600988 71.639012)
		(end 131.43 71.639012)
		(width 0.162)
		(layer "In2.Cu")
		(net 162)
	)
	(segment
		(start 130.06 64.53)
		(end 127.78 64.53)
		(width 0.162)
		(layer "In2.Cu")
		(net 162)
	)
	(segment
		(start 127.38 64.93)
		(end 126.73 64.93)
		(width 0.162)
		(layer "In2.Cu")
		(net 162)
	)
	(segment
		(start 127.325499 76.556315)
		(end 126.892068 76.122884)
		(width 0.162)
		(layer "In2.Cu")
		(net 162)
	)
	(segment
		(start 128.483062 74.036914)
		(end 128.483064 74.036913)
		(width 0.162)
		(layer "In2.Cu")
		(net 162)
	)
	(segment
		(start 126.370989 77.815)
		(end 126.370988 77.815)
		(width 0.162)
		(layer "In2.Cu")
		(net 162)
	)
	(segment
		(start 128.415844 75.707784)
		(end 128.456873 75.666754)
		(width 0.162)
		(layer "In2.Cu")
		(net 162)
	)
	(segment
		(start 130.153933 73.72788)
		(end 130.153934 73.72788)
		(width 0.162)
		(layer "In2.Cu")
		(net 162)
	)
	(segment
		(start 128.765908 74.036913)
		(end 128.765906 74.036914)
		(width 0.162)
		(layer "In2.Cu")
		(net 162)
	)
	(segment
		(start 130.392254 72.551986)
		(end 130.392256 72.551985)
		(width 0.162)
		(layer "In2.Cu")
		(net 162)
	)
	(segment
		(start 126.892067 75.840041)
		(end 126.892069 75.84004)
		(width 0.162)
		(layer "In2.Cu")
		(net 162)
	)
	(segment
		(start 129.588246 74.293567)
		(end 129.588247 74.293567)
		(width 0.162)
		(layer "In2.Cu")
		(net 162)
	)
	(segment
		(start 127.28447 76.839158)
		(end 127.325499 76.798128)
		(width 0.162)
		(layer "In2.Cu")
		(net 162)
	)
	(arc
		(start 131.600989 72.039012)
		(mid 131.721896 71.988931)
		(end 131.771977 71.868024)
		(width 0.162)
		(layer "In2.Cu")
		(net 162)
	)
	(arc
		(start 131.43 72.21)
		(mid 131.480081 72.089093)
		(end 131.600988 72.039012)
		(width 0.162)
		(layer "In2.Cu")
		(net 162)
	)
	(arc
		(start 130.638023 71.435)
		(mid 130.696602 71.293579)
		(end 130.838023 71.235)
		(width 0.162)
		(layer "In2.Cu")
		(net 162)
	)
	(arc
		(start 125.458023 78.615)
		(mid 125.316602 78.556421)
		(end 125.258023 78.415)
		(width 0.162)
		(layer "In2.Cu")
		(net 162)
	)
	(arc
		(start 127.457755 75.557197)
		(mid 127.399176 75.415776)
		(end 127.457754 75.274354)
		(width 0.162)
		(layer "In2.Cu")
		(net 162)
	)
	(arc
		(start 127.042656 76.839158)
		(mid 127.163563 76.889239)
		(end 127.28447 76.839158)
		(width 0.162)
		(layer "In2.Cu")
		(net 162)
	)
	(arc
		(start 130.838023 71.635)
		(mid 130.696602 71.576421)
		(end 130.638023 71.435)
		(width 0.162)
		(layer "In2.Cu")
		(net 162)
	)
	(arc
		(start 126.491977 77.935988)
		(mid 126.45654 77.850437)
		(end 126.370989 77.815)
		(width 0.162)
		(layer "In2.Cu")
		(net 162)
	)
	(arc
		(start 128.17403 75.707784)
		(mid 128.294937 75.757865)
		(end 128.415844 75.707784)
		(width 0.162)
		(layer "In2.Cu")
		(net 162)
	)
	(arc
		(start 131.23 71.235)
		(mid 131.371421 71.176421)
		(end 131.43 71.035)
		(width 0.162)
		(layer "In2.Cu")
		(net 162)
	)
	(arc
		(start 126.370989 79.019012)
		(mid 126.45654 78.983575)
		(end 126.491977 78.898024)
		(width 0.162)
		(layer "In2.Cu")
		(net 162)
	)
	(arc
		(start 131.771977 71.81)
		(mid 131.721896 71.689093)
		(end 131.600989 71.639012)
		(width 0.162)
		(layer "In2.Cu")
		(net 162)
	)
	(arc
		(start 128.456873 75.666754)
		(mid 128.506954 75.545847)
		(end 128.456872 75.424941)
		(width 0.162)
		(layer "In2.Cu")
		(net 162)
	)
	(arc
		(start 127.325499 76.798128)
		(mid 127.37558 76.677221)
		(end 127.325498 76.556315)
		(width 0.162)
		(layer "In2.Cu")
		(net 162)
	)
	(arc
		(start 126.892069 75.84004)
		(mid 127.03349 75.781462)
		(end 127.174913 75.84004)
		(width 0.162)
		(layer "In2.Cu")
		(net 162)
	)
	(arc
		(start 128.739717 75.142097)
		(mid 128.860624 75.192178)
		(end 128.981531 75.142097)
		(width 0.162)
		(layer "In2.Cu")
		(net 162)
	)
	(arc
		(start 126.370989 78.215)
		(mid 126.45654 78.179563)
		(end 126.491977 78.094012)
		(width 0.162)
		(layer "In2.Cu")
		(net 162)
	)
	(arc
		(start 129.947475 73.521421)
		(mid 129.912039 73.435869)
		(end 129.947476 73.350318)
		(width 0.162)
		(layer "In2.Cu")
		(net 162)
	)
	(arc
		(start 126.25 79.14)
		(mid 126.285437 79.054449)
		(end 126.370988 79.019012)
		(width 0.162)
		(layer "In2.Cu")
		(net 162)
	)
	(arc
		(start 130.392255 72.834829)
		(mid 130.333676 72.693408)
		(end 130.392254 72.551986)
		(width 0.162)
		(layer "In2.Cu")
		(net 162)
	)
	(arc
		(start 129.305404 74.57641)
		(mid 129.426311 74.626491)
		(end 129.547218 74.57641)
		(width 0.162)
		(layer "In2.Cu")
		(net 162)
	)
	(arc
		(start 126.491977 78.74)
		(mid 126.45654 78.654449)
		(end 126.370989 78.619012)
		(width 0.162)
		(layer "In2.Cu")
		(net 162)
	)
	(arc
		(start 127.891186 76.232441)
		(mid 127.941267 76.111534)
		(end 127.891185 75.990628)
		(width 0.162)
		(layer "In2.Cu")
		(net 162)
	)
	(arc
		(start 130.436777 73.445037)
		(mid 130.557684 73.495118)
		(end 130.678591 73.445037)
		(width 0.162)
		(layer "In2.Cu")
		(net 162)
	)
	(arc
		(start 129.588247 74.53538)
		(mid 129.638328 74.414473)
		(end 129.588246 74.293567)
		(width 0.162)
		(layer "In2.Cu")
		(net 162)
	)
	(arc
		(start 128.129509 74.814732)
		(mid 128.27093 74.756154)
		(end 128.412353 74.814732)
		(width 0.162)
		(layer "In2.Cu")
		(net 162)
	)
	(arc
		(start 128.483063 74.319757)
		(mid 128.424484 74.178336)
		(end 128.483062 74.036914)
		(width 0.162)
		(layer "In2.Cu")
		(net 162)
	)
	(arc
		(start 130.740136 72.617024)
		(mid 130.881558 72.675601)
		(end 131.022978 72.617024)
		(width 0.162)
		(layer "In2.Cu")
		(net 162)
	)
	(arc
		(start 130.153934 73.969693)
		(mid 130.204015 73.848786)
		(end 130.153933 73.72788)
		(width 0.162)
		(layer "In2.Cu")
		(net 162)
	)
	(arc
		(start 126.892068 76.122884)
		(mid 126.833489 75.981463)
		(end 126.892067 75.840041)
		(width 0.162)
		(layer "In2.Cu")
		(net 162)
	)
	(arc
		(start 126.326382 76.68857)
		(mid 126.267805 76.547148)
		(end 126.326382 76.405728)
		(width 0.162)
		(layer "In2.Cu")
		(net 162)
	)
	(arc
		(start 130.71962 73.404007)
		(mid 130.769701 73.2831)
		(end 130.719619 73.162194)
		(width 0.162)
		(layer "In2.Cu")
		(net 162)
	)
	(arc
		(start 128.129508 75.097576)
		(mid 128.070929 74.956155)
		(end 128.129507 74.814733)
		(width 0.162)
		(layer "In2.Cu")
		(net 162)
	)
	(arc
		(start 130.059215 73.238579)
		(mid 130.144766 73.203142)
		(end 130.230318 73.238578)
		(width 0.162)
		(layer "In2.Cu")
		(net 162)
	)
	(arc
		(start 127.457756 75.274353)
		(mid 127.599177 75.215775)
		(end 127.7406 75.274353)
		(width 0.162)
		(layer "In2.Cu")
		(net 162)
	)
	(arc
		(start 126.326383 76.405726)
		(mid 126.467804 76.347148)
		(end 126.609227 76.405726)
		(width 0.162)
		(layer "In2.Cu")
		(net 162)
	)
	(arc
		(start 129.871091 74.010723)
		(mid 129.991998 74.060804)
		(end 130.112905 74.010723)
		(width 0.162)
		(layer "In2.Cu")
		(net 162)
	)
	(arc
		(start 129.154817 73.577292)
		(mid 129.296238 73.518714)
		(end 129.437661 73.577292)
		(width 0.162)
		(layer "In2.Cu")
		(net 162)
	)
	(arc
		(start 126.370988 77.815)
		(mid 126.285437 77.779563)
		(end 126.25 77.694012)
		(width 0.162)
		(layer "In2.Cu")
		(net 162)
	)
	(arc
		(start 128.483064 74.036913)
		(mid 128.624485 73.978335)
		(end 128.765908 74.036913)
		(width 0.162)
		(layer "In2.Cu")
		(net 162)
	)
	(arc
		(start 126.497485 77.142515)
		(mid 126.556064 77.001093)
		(end 126.497485 76.859673)
		(width 0.162)
		(layer "In2.Cu")
		(net 162)
	)
	(arc
		(start 130.392256 72.551985)
		(mid 130.533677 72.493407)
		(end 130.6751 72.551985)
		(width 0.162)
		(layer "In2.Cu")
		(net 162)
	)
	(arc
		(start 125.258023 78.415)
		(mid 125.316602 78.273579)
		(end 125.458023 78.215)
		(width 0.162)
		(layer "In2.Cu")
		(net 162)
	)
	(arc
		(start 129.02256 75.101067)
		(mid 129.072641 74.98016)
		(end 129.022559 74.859254)
		(width 0.162)
		(layer "In2.Cu")
		(net 162)
	)
	(arc
		(start 129.154816 73.860136)
		(mid 129.096237 73.718715)
		(end 129.154815 73.577293)
		(width 0.162)
		(layer "In2.Cu")
		(net 162)
	)
	(arc
		(start 127.608343 76.273471)
		(mid 127.72925 76.323552)
		(end 127.850157 76.273471)
		(width 0.162)
		(layer "In2.Cu")
		(net 162)
	)
	(segment
		(start 127.9 85.5)
		(end 127.9 83.76)
		(width 0.15)
		(layer "F.Cu")
		(net 163)
	)
	(segment
		(start 125.86 63.34)
		(end 126.25 62.95)
		(width 0.182)
		(layer "F.Cu")
		(net 163)
	)
	(segment
		(start 128.3 85.9)
		(end 127.9 85.5)
		(width 0.15)
		(layer "F.Cu")
		(net 163)
	)
	(segment
		(start 127.9 83.76)
		(end 127.94 83.72)
		(width 0.15)
		(layer "F.Cu")
		(net 163)
	)
	(via
		(at 126.25 62.95)
		(size 0.45)
		(drill 0.2)
		(layers "F.Cu" "B.Cu")
		(remove_unused_layers yes)
		(keep_end_layers yes)
		(zone_layer_connections)
		(net 163)
	)
	(via
		(at 127.94 83.72)
		(size 0.45)
		(drill 0.2)
		(layers "F.Cu" "B.Cu")
		(remove_unused_layers yes)
		(keep_end_layers yes)
		(zone_layer_connections)
		(net 163)
	)
	(segment
		(start 126.25 62.95)
		(end 125.97 62.95)
		(width 0.15)
		(layer "B.Cu")
		(net 163)
	)
	(segment
		(start 125.97 62.95)
		(end 125.38 63.54)
		(width 0.15)
		(layer "B.Cu")
		(net 163)
	)
	(segment
		(start 125.38 63.54)
		(end 125.01 63.54)
		(width 0.15)
		(layer "B.Cu")
		(net 163)
	)
	(segment
		(start 128.22 63.34)
		(end 128.35 63.21)
		(width 0.162)
		(layer "In2.Cu")
		(net 163)
	)
	(segment
		(start 134.0151 66.54)
		(end 135.4649 66.54)
		(width 0.162)
		(layer "In2.Cu")
		(net 163)
	)
	(segment
		(start 134.0151 67.74)
		(end 135.4649 67.74)
		(width 0.162)
		(layer "In2.Cu")
		(net 163)
	)
	(segment
		(start 134.0151 68.14)
		(end 135.4649 68.14)
		(width 0.162)
		(layer "In2.Cu")
		(net 163)
	)
	(segment
		(start 127.73 63.34)
		(end 128.22 63.34)
		(width 0.162)
		(layer "In2.Cu")
		(net 163)
	)
	(segment
		(start 126.64 63.34)
		(end 127.73 63.34)
		(width 0.15)
		(layer "In2.Cu")
		(net 163)
	)
	(segment
		(start 134.89 65.74)
		(end 135.4649 65.74)
		(width 0.162)
		(layer "In2.Cu")
		(net 163)
	)
	(segment
		(start 126.64 63.34)
		(end 126.25 62.95)
		(width 0.15)
		(layer "In2.Cu")
		(net 163)
	)
	(segment
		(start 128.210812 83.459188)
		(end 128.200812 83.459188)
		(width 0.162)
		(layer "In2.Cu")
		(net 163)
	)
	(segment
		(start 128.35 63.21)
		(end 132.522894 63.21)
		(width 0.162)
		(layer "In2.Cu")
		(net 163)
	)
	(segment
		(start 134.0151 69.34)
		(end 135.4649 69.34)
		(width 0.162)
		(layer "In2.Cu")
		(net 163)
	)
	(segment
		(start 134.69 65.377106)
		(end 134.69 65.54)
		(width 0.162)
		(layer "In2.Cu")
		(net 163)
	)
	(segment
		(start 134.0151 66.94)
		(end 135.4649 66.94)
		(width 0.162)
		(layer "In2.Cu")
		(net 163)
	)
	(segment
		(start 128.210812 79.329188)
		(end 128.210812 83.459188)
		(width 0.162)
		(layer "In2.Cu")
		(net 163)
	)
	(segment
		(start 134.0151 67.34)
		(end 135.4649 67.34)
		(width 0.162)
		(layer "In2.Cu")
		(net 163)
	)
	(segment
		(start 134.0151 69.74)
		(end 134.49 69.74)
		(width 0.162)
		(layer "In2.Cu")
		(net 163)
	)
	(segment
		(start 134.69 69.94)
		(end 134.69 72.85)
		(width 0.162)
		(layer "In2.Cu")
		(net 163)
	)
	(segment
		(start 134.0151 66.14)
		(end 135.4649 66.14)
		(width 0.162)
		(layer "In2.Cu")
		(net 163)
	)
	(segment
		(start 134.0151 68.54)
		(end 135.4649 68.54)
		(width 0.162)
		(layer "In2.Cu")
		(net 163)
	)
	(segment
		(start 132.522894 63.21)
		(end 134.69 65.377106)
		(width 0.162)
		(layer "In2.Cu")
		(net 163)
	)
	(segment
		(start 134.0151 68.94)
		(end 135.4649 68.94)
		(width 0.162)
		(layer "In2.Cu")
		(net 163)
	)
	(segment
		(start 128.200812 83.459188)
		(end 127.94 83.72)
		(width 0.162)
		(layer "In2.Cu")
		(net 163)
	)
	(segment
		(start 134.69 72.85)
		(end 128.210812 79.329188)
		(width 0.162)
		(layer "In2.Cu")
		(net 163)
	)
	(arc
		(start 134.0151 69.34)
		(mid 133.873679 69.398579)
		(end 133.8151 69.54)
		(width 0.162)
		(layer "In2.Cu")
		(net 163)
	)
	(arc
		(start 135.4649 68.14)
		(mid 135.606321 68.198579)
		(end 135.6649 68.34)
		(width 0.162)
		(layer "In2.Cu")
		(net 163)
	)
	(arc
		(start 133.8151 66.34)
		(mid 133.873679 66.481421)
		(end 134.0151 66.54)
		(width 0.162)
		(layer "In2.Cu")
		(net 163)
	)
	(arc
		(start 133.8151 68.74)
		(mid 133.873679 68.881421)
		(end 134.0151 68.94)
		(width 0.162)
		(layer "In2.Cu")
		(net 163)
	)
	(arc
		(start 134.0151 67.74)
		(mid 133.873679 67.798579)
		(end 133.8151 67.94)
		(width 0.162)
		(layer "In2.Cu")
		(net 163)
	)
	(arc
		(start 133.8151 67.94)
		(mid 133.873679 68.081421)
		(end 134.0151 68.14)
		(width 0.162)
		(layer "In2.Cu")
		(net 163)
	)
	(arc
		(start 134.69 65.54)
		(mid 134.748579 65.681421)
		(end 134.89 65.74)
		(width 0.162)
		(layer "In2.Cu")
		(net 163)
	)
	(arc
		(start 134.0151 66.14)
		(mid 133.873679 66.198579)
		(end 133.8151 66.34)
		(width 0.162)
		(layer "In2.Cu")
		(net 163)
	)
	(arc
		(start 135.6649 68.34)
		(mid 135.606321 68.481421)
		(end 135.4649 68.54)
		(width 0.162)
		(layer "In2.Cu")
		(net 163)
	)
	(arc
		(start 135.6649 67.54)
		(mid 135.606321 67.681421)
		(end 135.4649 67.74)
		(width 0.162)
		(layer "In2.Cu")
		(net 163)
	)
	(arc
		(start 135.4649 66.54)
		(mid 135.606321 66.598579)
		(end 135.6649 66.74)
		(width 0.162)
		(layer "In2.Cu")
		(net 163)
	)
	(arc
		(start 134.0151 68.54)
		(mid 133.873679 68.598579)
		(end 133.8151 68.74)
		(width 0.162)
		(layer "In2.Cu")
		(net 163)
	)
	(arc
		(start 134.49 69.74)
		(mid 134.631421 69.798579)
		(end 134.69 69.94)
		(width 0.162)
		(layer "In2.Cu")
		(net 163)
	)
	(arc
		(start 135.4649 68.94)
		(mid 135.606321 68.998579)
		(end 135.6649 69.14)
		(width 0.162)
		(layer "In2.Cu")
		(net 163)
	)
	(arc
		(start 134.0151 66.94)
		(mid 133.873679 66.998579)
		(end 133.8151 67.14)
		(width 0.162)
		(layer "In2.Cu")
		(net 163)
	)
	(arc
		(start 135.6649 66.74)
		(mid 135.606321 66.881421)
		(end 135.4649 66.94)
		(width 0.162)
		(layer "In2.Cu")
		(net 163)
	)
	(arc
		(start 135.6649 65.94)
		(mid 135.606321 66.081421)
		(end 135.4649 66.14)
		(width 0.162)
		(layer "In2.Cu")
		(net 163)
	)
	(arc
		(start 135.4649 67.34)
		(mid 135.606321 67.398579)
		(end 135.6649 67.54)
		(width 0.162)
		(layer "In2.Cu")
		(net 163)
	)
	(arc
		(start 133.8151 67.14)
		(mid 133.873679 67.281421)
		(end 134.0151 67.34)
		(width 0.162)
		(layer "In2.Cu")
		(net 163)
	)
	(arc
		(start 135.6649 69.14)
		(mid 135.606321 69.281421)
		(end 135.4649 69.34)
		(width 0.162)
		(layer "In2.Cu")
		(net 163)
	)
	(arc
		(start 133.8151 69.54)
		(mid 133.873679 69.681421)
		(end 134.0151 69.74)
		(width 0.162)
		(layer "In2.Cu")
		(net 163)
	)
	(arc
		(start 135.4649 65.74)
		(mid 135.606321 65.798579)
		(end 135.6649 65.94)
		(width 0.162)
		(layer "In2.Cu")
		(net 163)
	)
	(segment
		(start 125.9 86.7)
		(end 126.28 87.08)
		(width 0.2)
		(layer "F.Cu")
		(net 164)
	)
	(segment
		(start 126.66 58.91)
		(end 126.67 58.9)
		(width 0.182)
		(layer "F.Cu")
		(net 164)
	)
	(segment
		(start 126.66 59.34)
		(end 126.66 58.91)
		(width 0.182)
		(layer "F.Cu")
		(net 164)
	)
	(via
		(at 126.67 58.9)
		(size 0.45)
		(drill 0.2)
		(layers "F.Cu" "B.Cu")
		(remove_unused_layers yes)
		(keep_end_layers yes)
		(zone_layer_connections)
		(net 164)
	)
	(via
		(at 126.28 87.08)
		(size 0.45)
		(drill 0.1)
		(layers "F.Cu" "B.Cu")
		(net 164)
	)
	(segment
		(start 126.81 58.48)
		(end 126.81 57.89)
		(width 0.15)
		(layer "B.Cu")
		(net 164)
	)
	(segment
		(start 126.67 58.62)
		(end 126.81 58.48)
		(width 0.15)
		(layer "B.Cu")
		(net 164)
	)
	(segment
		(start 126.67 58.9)
		(end 126.67 58.62)
		(width 0.15)
		(layer "B.Cu")
		(net 164)
	)
	(segment
		(start 127.12 58.31)
		(end 130.81 58.31)
		(width 0.162)
		(layer "In4.Cu")
		(net 164)
	)
	(segment
		(start 136.97 69.99)
		(end 137.008441 69.99)
		(width 0.162)
		(layer "In4.Cu")
		(net 164)
	)
	(segment
		(start 126.256798 87.08)
		(end 125.9 86.723202)
		(width 0.162)
		(layer "In4.Cu")
		(net 164)
	)
	(segment
		(start 137.008441 71.99)
		(end 136.97 71.99)
		(width 0.162)
		(layer "In4.Cu")
		(net 164)
	)
	(segment
		(start 136.381559 70.58422)
		(end 136.381559 70.59578)
		(width 0.162)
		(layer "In4.Cu")
		(net 164)
	)
	(segment
		(start 126.26 79.88)
		(end 126.26 84.1729)
		(width 0.162)
		(layer "In4.Cu")
		(net 164)
	)
	(segment
		(start 126.67 58.9)
		(end 126.67 58.76)
		(width 0.162)
		(layer "In4.Cu")
		(net 164)
	)
	(segment
		(start 136.97 70.39)
		(end 136.575779 70.39)
		(width 0.162)
		(layer "In4.Cu")
		(net 164)
	)
	(segment
		(start 136.575779 71.59)
		(end 137.008441 71.59)
		(width 0.162)
		(layer "In4.Cu")
		(net 164)
	)
	(segment
		(start 126.67 58.76)
		(end 127.12 58.31)
		(width 0.162)
		(layer "In4.Cu")
		(net 164)
	)
	(segment
		(start 136.77 63.22)
		(end 136.77 69.79)
		(width 0.162)
		(layer "In4.Cu")
		(net 164)
	)
	(segment
		(start 136.77 74.25)
		(end 132.53 78.49)
		(width 0.162)
		(layer "In4.Cu")
		(net 164)
	)
	(segment
		(start 136.77 72.19)
		(end 136.77 74.25)
		(width 0.162)
		(layer "In4.Cu")
		(net 164)
	)
	(segment
		(start 136.575779 70.79)
		(end 137.008441 70.79)
		(width 0.162)
		(layer "In4.Cu")
		(net 164)
	)
	(segment
		(start 132.53 78.49)
		(end 127.65 78.49)
		(width 0.162)
		(layer "In4.Cu")
		(net 164)
	)
	(segment
		(start 126.26 84.1729)
		(end 125.899 84.5339)
		(width 0.162)
		(layer "In4.Cu")
		(net 164)
	)
	(segment
		(start 130.81 58.31)
		(end 133.29 60.79)
		(width 0.162)
		(layer "In4.Cu")
		(net 164)
	)
	(segment
		(start 137.008441 70.39)
		(end 136.97 70.39)
		(width 0.162)
		(layer "In4.Cu")
		(net 164)
	)
	(segment
		(start 136.575779 71.19)
		(end 137.008441 71.19)
		(width 0.162)
		(layer "In4.Cu")
		(net 164)
	)
	(segment
		(start 125.9 86.723202)
		(end 125.9 85.3)
		(width 0.15)
		(layer "In4.Cu")
		(net 164)
	)
	(segment
		(start 126.28 87.08)
		(end 126.256798 87.08)
		(width 0.162)
		(layer "In4.Cu")
		(net 164)
	)
	(segment
		(start 127.65 78.49)
		(end 126.26 79.88)
		(width 0.162)
		(layer "In4.Cu")
		(net 164)
	)
	(segment
		(start 134.34 60.79)
		(end 136.77 63.22)
		(width 0.162)
		(layer "In4.Cu")
		(net 164)
	)
	(segment
		(start 125.899 84.5339)
		(end 125.899 85.299)
		(width 0.162)
		(layer "In4.Cu")
		(net 164)
	)
	(segment
		(start 125.899 85.299)
		(end 125.9 85.3)
		(width 0.162)
		(layer "In4.Cu")
		(net 164)
	)
	(segment
		(start 133.29 60.79)
		(end 134.34 60.79)
		(width 0.162)
		(layer "In4.Cu")
		(net 164)
	)
	(segment
		(start 136.381559 71.38422)
		(end 136.381559 71.39578)
		(width 0.162)
		(layer "In4.Cu")
		(net 164)
	)
	(arc
		(start 136.77 69.79)
		(mid 136.828579 69.931421)
		(end 136.97 69.99)
		(width 0.162)
		(layer "In4.Cu")
		(net 164)
	)
	(arc
		(start 137.008441 71.59)
		(mid 137.149862 71.648579)
		(end 137.208441 71.79)
		(width 0.162)
		(layer "In4.Cu")
		(net 164)
	)
	(arc
		(start 137.008441 69.99)
		(mid 137.149862 70.048579)
		(end 137.208441 70.19)
		(width 0.162)
		(layer "In4.Cu")
		(net 164)
	)
	(arc
		(start 136.381559 71.39578)
		(mid 136.438445 71.533114)
		(end 136.575779 71.59)
		(width 0.162)
		(layer "In4.Cu")
		(net 164)
	)
	(arc
		(start 136.575779 70.39)
		(mid 136.438445 70.446886)
		(end 136.381559 70.58422)
		(width 0.162)
		(layer "In4.Cu")
		(net 164)
	)
	(arc
		(start 137.208441 70.99)
		(mid 137.149862 71.131421)
		(end 137.008441 71.19)
		(width 0.162)
		(layer "In4.Cu")
		(net 164)
	)
	(arc
		(start 137.008441 70.79)
		(mid 137.149862 70.848579)
		(end 137.208441 70.99)
		(width 0.162)
		(layer "In4.Cu")
		(net 164)
	)
	(arc
		(start 136.381559 70.59578)
		(mid 136.438445 70.733114)
		(end 136.575779 70.79)
		(width 0.162)
		(layer "In4.Cu")
		(net 164)
	)
	(arc
		(start 137.208441 71.79)
		(mid 137.149862 71.931421)
		(end 137.008441 71.99)
		(width 0.162)
		(layer "In4.Cu")
		(net 164)
	)
	(arc
		(start 136.575779 71.19)
		(mid 136.438445 71.246886)
		(end 136.381559 71.38422)
		(width 0.162)
		(layer "In4.Cu")
		(net 164)
	)
	(arc
		(start 137.208441 70.19)
		(mid 137.149862 70.331421)
		(end 137.008441 70.39)
		(width 0.162)
		(layer "In4.Cu")
		(net 164)
	)
	(arc
		(start 136.97 71.99)
		(mid 136.828579 72.048579)
		(end 136.77 72.19)
		(width 0.162)
		(layer "In4.Cu")
		(net 164)
	)
	(segment
		(start 122.7 86.7)
		(end 123.1 86.3)
		(width 0.15)
		(layer "F.Cu")
		(net 165)
	)
	(segment
		(start 121.35 63.85)
		(end 121.06 64.14)
		(width 0.15)
		(layer "F.Cu")
		(net 165)
	)
	(segment
		(start 121.425 63.85)
		(end 121.35 63.85)
		(width 0.15)
		(layer "F.Cu")
		(net 165)
	)
	(via
		(at 121.425 63.85)
		(size 0.45)
		(drill 0.2)
		(layers "F.Cu" "B.Cu")
		(net 165)
	)
	(via
		(at 123.1 86.3)
		(size 0.45)
		(drill 0.2)
		(layers "F.Cu" "B.Cu")
		(remove_unused_layers yes)
		(keep_end_layers yes)
		(zone_layer_connections)
		(net 165)
	)
	(segment
		(start 124.69 66.88)
		(end 123.85 66.88)
		(width 0.15)
		(layer "B.Cu")
		(net 165)
	)
	(segment
		(start 123.85 66.88)
		(end 122.69 65.72)
		(width 0.15)
		(layer "B.Cu")
		(net 165)
	)
	(segment
		(start 125.01 66.04)
		(end 125.01 66.56)
		(width 0.15)
		(layer "B.Cu")
		(net 165)
	)
	(segment
		(start 121.95 65.72)
		(end 121.76 65.53)
		(width 0.15)
		(layer "B.Cu")
		(net 165)
	)
	(segment
		(start 121.76 65.53)
		(end 121.76 64.185)
		(width 0.15)
		(layer "B.Cu")
		(net 165)
	)
	(segment
		(start 121.76 64.185)
		(end 121.425 63.85)
		(width 0.15)
		(layer "B.Cu")
		(net 165)
	)
	(segment
		(start 125.01 66.56)
		(end 124.69 66.88)
		(width 0.15)
		(layer "B.Cu")
		(net 165)
	)
	(segment
		(start 122.69 65.72)
		(end 121.95 65.72)
		(width 0.15)
		(layer "B.Cu")
		(net 165)
	)
	(segment
		(start 121.425 63.85)
		(end 119.670002 63.85)
		(width 0.15)
		(layer "In2.Cu")
		(net 165)
	)
	(segment
		(start 118.913138 80.979598)
		(end 118.913137 80.979599)
		(width 0.162)
		(layer "In2.Cu")
		(net 165)
	)
	(segment
		(start 118.06461 80.413913)
		(end 118.064611 80.413913)
		(width 0.162)
		(layer "In2.Cu")
		(net 165)
	)
	(segment
		(start 118.829335 78.96)
		(end 118.25 78.96)
		(width 0.162)
		(layer "In2.Cu")
		(net 165)
	)
	(segment
		(start 119.322788 80.85279)
		(end 123.1 84.63)
		(width 0.162)
		(layer "In2.Cu")
		(net 165)
	)
	(segment
		(start 119.449598 79.877453)
		(end 119.449599 79.877452)
		(width 0.162)
		(layer "In2.Cu")
		(net 165)
	)
	(segment
		(start 118.25 72.96)
		(end 118.429335 72.96)
		(width 0.162)
		(layer "In2.Cu")
		(net 165)
	)
	(segment
		(start 117.770665 75.36)
		(end 118.429335 75.36)
		(width 0.162)
		(layer "In2.Cu")
		(net 165)
	)
	(segment
		(start 117.770665 74.56)
		(end 118.429335 74.56)
		(width 0.162)
		(layer "In2.Cu")
		(net 165)
	)
	(segment
		(start 118.630296 80.979599)
		(end 118.630295 80.979599)
		(width 0.162)
		(layer "In2.Cu")
		(net 165)
	)
	(segment
		(start 117.770665 78.56)
		(end 118.829335 78.56)
		(width 0.162)
		(layer "In2.Cu")
		(net 165)
	)
	(segment
		(start 118.05 79.16)
		(end 118.05 79.58)
		(width 0.162)
		(layer "In2.Cu")
		(net 165)
	)
	(segment
		(start 117.770665 73.36)
		(end 118.429335 73.36)
		(width 0.162)
		(layer "In2.Cu")
		(net 165)
	)
	(segment
		(start 117.770665 77.36)
		(end 118.479335 77.36)
		(width 0.162)
		(layer "In2.Cu")
		(net 165)
	)
	(segment
		(start 117.770665 76.96)
		(end 118.479335 76.96)
		(width 0.162)
		(layer "In2.Cu")
		(net 165)
	)
	(segment
		(start 117.770665 78.16)
		(end 118.829335 78.16)
		(width 0.162)
		(layer "In2.Cu")
		(net 165)
	)
	(segment
		(start 119.670002 63.85)
		(end 119.420002 64.1)
		(width 0.15)
		(layer "In2.Cu")
		(net 165)
	)
	(segment
		(start 117.770665 77.76)
		(end 118.829335 77.76)
		(width 0.162)
		(layer "In2.Cu")
		(net 165)
	)
	(segment
		(start 118.347454 80.413912)
		(end 118.347453 80.413913)
		(width 0.162)
		(layer "In2.Cu")
		(net 165)
	)
	(segment
		(start 118.05 65.470002)
		(end 118.05 72.76)
		(width 0.162)
		(layer "In2.Cu")
		(net 165)
	)
	(segment
		(start 117.770665 75.76)
		(end 118.429335 75.76)
		(width 0.162)
		(layer "In2.Cu")
		(net 165)
	)
	(segment
		(start 117.770665 76.16)
		(end 118.429335 76.16)
		(width 0.162)
		(layer "In2.Cu")
		(net 165)
	)
	(segment
		(start 119.322788 80.852789)
		(end 119.322788 80.85279)
		(width 0.162)
		(layer "In2.Cu")
		(net 165)
	)
	(segment
		(start 118.898526 80.428526)
		(end 118.630295 80.696756)
		(width 0.162)
		(layer "In2.Cu")
		(net 165)
	)
	(segment
		(start 123.1 84.63)
		(end 123.1 86.3)
		(width 0.162)
		(layer "In2.Cu")
		(net 165)
	)
	(segment
		(start 118.347453 80.413913)
		(end 119.166755 79.594608)
		(width 0.162)
		(layer "In2.Cu")
		(net 165)
	)
	(segment
		(start 119.420002 64.1)
		(end 118.05 65.470002)
		(width 0.162)
		(layer "In2.Cu")
		(net 165)
	)
	(segment
		(start 119.449599 79.877452)
		(end 118.898524 80.428524)
		(width 0.162)
		(layer "In2.Cu")
		(net 165)
	)
	(segment
		(start 117.770665 74.96)
		(end 118.429335 74.96)
		(width 0.162)
		(layer "In2.Cu")
		(net 165)
	)
	(segment
		(start 118.898524 80.428524)
		(end 118.898526 80.428526)
		(width 0.162)
		(layer "In2.Cu")
		(net 165)
	)
	(segment
		(start 118.19142 80.004262)
		(end 118.064611 80.13107)
		(width 0.162)
		(layer "In2.Cu")
		(net 165)
	)
	(segment
		(start 118.191419 80.004263)
		(end 118.19142 80.004262)
		(width 0.162)
		(layer "In2.Cu")
		(net 165)
	)
	(segment
		(start 117.770665 73.76)
		(end 118.429335 73.76)
		(width 0.162)
		(layer "In2.Cu")
		(net 165)
	)
	(segment
		(start 117.770665 76.56)
		(end 118.429335 76.56)
		(width 0.162)
		(layer "In2.Cu")
		(net 165)
	)
	(segment
		(start 119.4496 79.594611)
		(end 119.449599 79.59461)
		(width 0.162)
		(layer "In2.Cu")
		(net 165)
	)
	(segment
		(start 118.913137 80.979599)
		(end 119.039945 80.85279)
		(width 0.162)
		(layer "In2.Cu")
		(net 165)
	)
	(segment
		(start 117.770665 74.16)
		(end 118.429335 74.16)
		(width 0.162)
		(layer "In2.Cu")
		(net 165)
	)
	(segment
		(start 118.05 79.58)
		(end 118.19142 79.72142)
		(width 0.162)
		(layer "In2.Cu")
		(net 165)
	)
	(arc
		(start 117.770665 74.96)
		(mid 117.629244 75.018579)
		(end 117.570665 75.16)
		(width 0.162)
		(layer "In2.Cu")
		(net 165)
	)
	(arc
		(start 117.570665 78.36)
		(mid 117.629244 78.501421)
		(end 117.770665 78.56)
		(width 0.162)
		(layer "In2.Cu")
		(net 165)
	)
	(arc
		(start 118.429335 72.96)
		(mid 118.570756 73.018579)
		(end 118.629335 73.16)
		(width 0.162)
		(layer "In2.Cu")
		(net 165)
	)
	(arc
		(start 117.770665 77.36)
		(mid 117.629244 77.418579)
		(end 117.570665 77.56)
		(width 0.162)
		(layer "In2.Cu")
		(net 165)
	)
	(arc
		(start 119.166755 79.594608)
		(mid 119.308179 79.536032)
		(end 119.4496 79.594611)
		(width 0.162)
		(layer "In2.Cu")
		(net 165)
	)
	(arc
		(start 117.570665 77.56)
		(mid 117.629244 77.701421)
		(end 117.770665 77.76)
		(width 0.162)
		(layer "In2.Cu")
		(net 165)
	)
	(arc
		(start 118.064611 80.13107)
		(mid 118.006032 80.272491)
		(end 118.06461 80.413913)
		(width 0.162)
		(layer "In2.Cu")
		(net 165)
	)
	(arc
		(start 119.039945 80.85279)
		(mid 119.181366 80.794211)
		(end 119.322788 80.852789)
		(width 0.162)
		(layer "In2.Cu")
		(net 165)
	)
	(arc
		(start 118.829335 77.76)
		(mid 118.970756 77.818579)
		(end 119.029335 77.96)
		(width 0.162)
		(layer "In2.Cu")
		(net 165)
	)
	(arc
		(start 118.630295 80.979599)
		(mid 118.771717 81.038177)
		(end 118.913138 80.979598)
		(width 0.162)
		(layer "In2.Cu")
		(net 165)
	)
	(arc
		(start 118.629335 74.76)
		(mid 118.570756 74.901421)
		(end 118.429335 74.96)
		(width 0.162)
		(layer "In2.Cu")
		(net 165)
	)
	(arc
		(start 117.770665 73.36)
		(mid 117.629244 73.418579)
		(end 117.570665 73.56)
		(width 0.162)
		(layer "In2.Cu")
		(net 165)
	)
	(arc
		(start 118.429335 76.16)
		(mid 118.570756 76.218579)
		(end 118.629335 76.36)
		(width 0.162)
		(layer "In2.Cu")
		(net 165)
	)
	(arc
		(start 117.570665 76.76)
		(mid 117.629244 76.901421)
		(end 117.770665 76.96)
		(width 0.162)
		(layer "In2.Cu")
		(net 165)
	)
	(arc
		(start 118.429335 75.36)
		(mid 118.570756 75.418579)
		(end 118.629335 75.56)
		(width 0.162)
		(layer "In2.Cu")
		(net 165)
	)
	(arc
		(start 118.679335 77.16)
		(mid 118.620756 77.301421)
		(end 118.479335 77.36)
		(width 0.162)
		(layer "In2.Cu")
		(net 165)
	)
	(arc
		(start 118.19142 79.72142)
		(mid 118.249998 79.862842)
		(end 118.191419 80.004263)
		(width 0.162)
		(layer "In2.Cu")
		(net 165)
	)
	(arc
		(start 118.629335 73.16)
		(mid 118.570756 73.301421)
		(end 118.429335 73.36)
		(width 0.162)
		(layer "In2.Cu")
		(net 165)
	)
	(arc
		(start 118.064611 80.413913)
		(mid 118.206033 80.472491)
		(end 118.347454 80.413912)
		(width 0.162)
		(layer "In2.Cu")
		(net 165)
	)
	(arc
		(start 118.05 72.76)
		(mid 118.108579 72.901421)
		(end 118.25 72.96)
		(width 0.162)
		(layer "In2.Cu")
		(net 165)
	)
	(arc
		(start 117.770665 75.76)
		(mid 117.629244 75.818579)
		(end 117.570665 75.96)
		(width 0.162)
		(layer "In2.Cu")
		(net 165)
	)
	(arc
		(start 118.429335 74.56)
		(mid 118.570756 74.618579)
		(end 118.629335 74.76)
		(width 0.162)
		(layer "In2.Cu")
		(net 165)
	)
	(arc
		(start 117.570665 75.16)
		(mid 117.629244 75.301421)
		(end 117.770665 75.36)
		(width 0.162)
		(layer "In2.Cu")
		(net 165)
	)
	(arc
		(start 117.770665 76.56)
		(mid 117.629244 76.618579)
		(end 117.570665 76.76)
		(width 0.162)
		(layer "In2.Cu")
		(net 165)
	)
	(arc
		(start 118.25 78.96)
		(mid 118.108579 79.018579)
		(end 118.05 79.16)
		(width 0.162)
		(layer "In2.Cu")
		(net 165)
	)
	(arc
		(start 118.829335 78.56)
		(mid 118.970756 78.618579)
		(end 119.029335 78.76)
		(width 0.162)
		(layer "In2.Cu")
		(net 165)
	)
	(arc
		(start 117.570665 73.56)
		(mid 117.629244 73.701421)
		(end 117.770665 73.76)
		(width 0.162)
		(layer "In2.Cu")
		(net 165)
	)
	(arc
		(start 118.479335 76.96)
		(mid 118.620756 77.018579)
		(end 118.679335 77.16)
		(width 0.162)
		(layer "In2.Cu")
		(net 165)
	)
	(arc
		(start 119.449599 79.59461)
		(mid 119.508177 79.736032)
		(end 119.449598 79.877453)
		(width 0.162)
		(layer "In2.Cu")
		(net 165)
	)
	(arc
		(start 118.630295 80.696756)
		(mid 118.571717 80.838178)
		(end 118.630296 80.979599)
		(width 0.162)
		(layer "In2.Cu")
		(net 165)
	)
	(arc
		(start 117.770665 78.16)
		(mid 117.629244 78.218579)
		(end 117.570665 78.36)
		(width 0.162)
		(layer "In2.Cu")
		(net 165)
	)
	(arc
		(start 117.770665 74.16)
		(mid 117.629244 74.218579)
		(end 117.570665 74.36)
		(width 0.162)
		(layer "In2.Cu")
		(net 165)
	)
	(arc
		(start 117.570665 75.96)
		(mid 117.629244 76.101421)
		(end 117.770665 76.16)
		(width 0.162)
		(layer "In2.Cu")
		(net 165)
	)
	(arc
		(start 117.570665 74.36)
		(mid 117.629244 74.501421)
		(end 117.770665 74.56)
		(width 0.162)
		(layer "In2.Cu")
		(net 165)
	)
	(arc
		(start 118.629335 76.36)
		(mid 118.570756 76.501421)
		(end 118.429335 76.56)
		(width 0.162)
		(layer "In2.Cu")
		(net 165)
	)
	(arc
		(start 118.629335 75.56)
		(mid 118.570756 75.701421)
		(end 118.429335 75.76)
		(width 0.162)
		(layer "In2.Cu")
		(net 165)
	)
	(arc
		(start 119.029335 77.96)
		(mid 118.970756 78.101421)
		(end 118.829335 78.16)
		(width 0.162)
		(layer "In2.Cu")
		(net 165)
	)
	(arc
		(start 119.029335 78.76)
		(mid 118.970756 78.901421)
		(end 118.829335 78.96)
		(width 0.162)
		(layer "In2.Cu")
		(net 165)
	)
	(arc
		(start 118.629335 73.96)
		(mid 118.570756 74.101421)
		(end 118.429335 74.16)
		(width 0.162)
		(layer "In2.Cu")
		(net 165)
	)
	(arc
		(start 118.429335 73.76)
		(mid 118.570756 73.818579)
		(end 118.629335 73.96)
		(width 0.162)
		(layer "In2.Cu")
		(net 165)
	)
	(segment
		(start 127.06 63.74)
		(end 127.46 64.14)
		(width 0.182)
		(layer "F.Cu")
		(net 166)
	)
	(segment
		(start 127.5 84.3)
		(end 127.5 83.269303)
		(width 0.2)
		(layer "F.Cu")
		(net 166)
	)
	(segment
		(start 127.5 83.269303)
		(end 127.5255 83.243803)
		(width 0.2)
		(layer "F.Cu")
		(net 166)
	)
	(via
		(at 127.06 63.74)
		(size 0.45)
		(drill 0.2)
		(layers "F.Cu" "B.Cu")
		(remove_unused_layers yes)
		(keep_end_layers yes)
		(zone_layer_connections)
		(net 166)
	)
	(via
		(at 127.5255 83.243803)
		(size 0.45)
		(drill 0.2)
		(layers "F.Cu" "B.Cu")
		(remove_unused_layers yes)
		(keep_end_layers yes)
		(zone_layer_connections)
		(net 166)
	)
	(segment
		(start 125.83 63.74)
		(end 125.83 63.61)
		(width 0.15)
		(layer "B.Cu")
		(net 166)
	)
	(segment
		(start 125.13 64.44)
		(end 125.83 63.74)
		(width 0.15)
		(layer "B.Cu")
		(net 166)
	)
	(segment
		(start 126.7 63.38)
		(end 127.06 63.74)
		(width 0.15)
		(layer "B.Cu")
		(net 166)
	)
	(segment
		(start 126.06 63.38)
		(end 126.7 63.38)
		(width 0.15)
		(layer "B.Cu")
		(net 166)
	)
	(segment
		(start 125.83 63.61)
		(end 126.06 63.38)
		(width 0.15)
		(layer "B.Cu")
		(net 166)
	)
	(segment
		(start 128.806752 76.672538)
		(end 129.43368 77.299466)
		(width 0.162)
		(layer "In2.Cu")
		(net 166)
	)
	(segment
		(start 128.806753 76.672539)
		(end 128.806752 76.672538)
		(width 0.162)
		(layer "In2.Cu")
		(net 166)
	)
	(segment
		(start 129.150836 77.582307)
		(end 129.150836 77.582308)
		(width 0.162)
		(layer "In2.Cu")
		(net 166)
	)
	(segment
		(start 131.816695 73.186556)
		(end 131.826163 73.177089)
		(width 0.162)
		(layer "In2.Cu")
		(net 166)
	)
	(segment
		(start 131.533851 73.742775)
		(end 132.262111 74.471035)
		(width 0.162)
		(layer "In2.Cu")
		(net 166)
	)
	(segment
		(start 130.968165 74.308461)
		(end 131.696425 75.036721)
		(width 0.162)
		(layer "In2.Cu")
		(net 166)
	)
	(segment
		(start 128.5 63.75)
		(end 127.07 63.75)
		(width 0.162)
		(layer "In2.Cu")
		(net 166)
	)
	(segment
		(start 131.979268 75.03672)
		(end 131.979268 75.036721)
		(width 0.162)
		(layer "In2.Cu")
		(net 166)
	)
	(segment
		(start 131.979268 74.753877)
		(end 131.979268 74.753878)
		(width 0.162)
		(layer "In2.Cu")
		(net 166)
	)
	(segment
		(start 129.359495 76.093908)
		(end 129.407795 76.142208)
		(width 0.162)
		(layer "In2.Cu")
		(net 166)
	)
	(segment
		(start 133.676326 73.339662)
		(end 133.676326 73.339663)
		(width 0.162)
		(layer "In2.Cu")
		(net 166)
	)
	(segment
		(start 130.28221 76.733778)
		(end 130.28221 76.733779)
		(width 0.162)
		(layer "In2.Cu")
		(net 166)
	)
	(segment
		(start 130.28221 76.450935)
		(end 130.28221 76.450936)
		(width 0.162)
		(layer "In2.Cu")
		(net 166)
	)
	(segment
		(start 129.836794 75.439834)
		(end 129.836793 75.439833)
		(width 0.162)
		(layer "In2.Cu")
		(net 166)
	)
	(segment
		(start 129.150836 77.582308)
		(end 128.523909 76.955381)
		(width 0.162)
		(layer "In2.Cu")
		(net 166)
	)
	(segment
		(start 129.150836 77.865152)
		(end 129.150836 77.865151)
		(width 0.162)
		(layer "In2.Cu")
		(net 166)
	)
	(segment
		(start 131.251007 73.752243)
		(end 131.251009 73.752242)
		(width 0.162)
		(layer "In2.Cu")
		(net 166)
	)
	(segment
		(start 130.40248 74.874148)
		(end 130.402479 74.874147)
		(width 0.162)
		(layer "In2.Cu")
		(net 166)
	)
	(segment
		(start 127.07 63.75)
		(end 127.06 63.74)
		(width 0.162)
		(layer "In2.Cu")
		(net 166)
	)
	(segment
		(start 133.226173 72.323825)
		(end 133.226174 72.323825)
		(width 0.162)
		(layer "In2.Cu")
		(net 166)
	)
	(segment
		(start 127.5255 83.243803)
		(end 127.782 82.987303)
		(width 0.162)
		(layer "In2.Cu")
		(net 166)
	)
	(segment
		(start 131.865262 63.63)
		(end 128.62 63.63)
		(width 0.162)
		(layer "In2.Cu")
		(net 166)
	)
	(segment
		(start 130.119637 74.883614)
		(end 130.129105 74.874147)
		(width 0.162)
		(layer "In2.Cu")
		(net 166)
	)
	(segment
		(start 131.413582 75.319563)
		(end 131.413582 75.319564)
		(width 0.162)
		(layer "In2.Cu")
		(net 166)
	)
	(segment
		(start 132.544954 74.188192)
		(end 131.816694 73.459932)
		(width 0.162)
		(layer "In2.Cu")
		(net 166)
	)
	(segment
		(start 129.553949 75.449301)
		(end 129.553951 75.4493)
		(width 0.162)
		(layer "In2.Cu")
		(net 166)
	)
	(segment
		(start 130.685323 74.317928)
		(end 130.694791 74.308461)
		(width 0.162)
		(layer "In2.Cu")
		(net 166)
	)
	(segment
		(start 129.076651 76.280153)
		(end 129.262897 76.093908)
		(width 0.162)
		(layer "In2.Cu")
		(net 166)
	)
	(segment
		(start 130.685321 74.317929)
		(end 130.685323 74.317928)
		(width 0.162)
		(layer "In2.Cu")
		(net 166)
	)
	(segment
		(start 130.968166 74.308462)
		(end 130.968165 74.308461)
		(width 0.162)
		(layer "In2.Cu")
		(net 166)
	)
	(segment
		(start 128.417842 77.415)
		(end 128.867993 77.865151)
		(width 0.162)
		(layer "In2.Cu")
		(net 166)
	)
	(segment
		(start 133.11064 73.905348)
		(end 133.11064 73.905349)
		(width 0.162)
		(layer "In2.Cu")
		(net 166)
	)
	(segment
		(start 128.523909 76.884671)
		(end 128.52391 76.884669)
		(width 0.162)
		(layer "In2.Cu")
		(net 166)
	)
	(segment
		(start 127.782 82.987303)
		(end 127.782 77.768)
		(width 0.162)
		(layer "In2.Cu")
		(net 166)
	)
	(segment
		(start 133.676326 73.056819)
		(end 133.676326 73.05682)
		(width 0.162)
		(layer "In2.Cu")
		(net 166)
	)
	(segment
		(start 133.226174 72.323825)
		(end 133.485584 72.064416)
		(width 0.162)
		(layer "In2.Cu")
		(net 166)
	)
	(segment
		(start 129.716523 77.299465)
		(end 129.716523 77.299466)
		(width 0.162)
		(layer "In2.Cu")
		(net 166)
	)
	(segment
		(start 133.11064 73.622505)
		(end 133.11064 73.622506)
		(width 0.162)
		(layer "In2.Cu")
		(net 166)
	)
	(segment
		(start 131.413582 75.319564)
		(end 130.685322 74.591304)
		(width 0.162)
		(layer "In2.Cu")
		(net 166)
	)
	(segment
		(start 132.544954 74.188191)
		(end 132.544954 74.188192)
		(width 0.162)
		(layer "In2.Cu")
		(net 166)
	)
	(segment
		(start 129.407795 76.142208)
		(end 129.999367 76.733779)
		(width 0.162)
		(layer "In2.Cu")
		(net 166)
	)
	(segment
		(start 132.634602 72.580781)
		(end 133.393483 73.339663)
		(width 0.162)
		(layer "In2.Cu")
		(net 166)
	)
	(segment
		(start 133.11064 73.622506)
		(end 132.351758 72.863624)
		(width 0.162)
		(layer "In2.Cu")
		(net 166)
	)
	(segment
		(start 130.119635 74.883615)
		(end 130.119637 74.883614)
		(width 0.162)
		(layer "In2.Cu")
		(net 166)
	)
	(segment
		(start 133.676326 73.05682)
		(end 133.226174 72.606668)
		(width 0.162)
		(layer "In2.Cu")
		(net 166)
	)
	(segment
		(start 133.485584 65.250322)
		(end 131.865262 63.63)
		(width 0.162)
		(layer "In2.Cu")
		(net 166)
	)
	(segment
		(start 132.544954 74.471034)
		(end 132.544954 74.471035)
		(width 0.162)
		(layer "In2.Cu")
		(net 166)
	)
	(segment
		(start 130.847896 75.885249)
		(end 130.847896 75.88525)
		(width 0.162)
		(layer "In2.Cu")
		(net 166)
	)
	(segment
		(start 131.251009 73.752242)
		(end 131.260477 73.742775)
		(width 0.162)
		(layer "In2.Cu")
		(net 166)
	)
	(segment
		(start 130.847896 75.88525)
		(end 130.119636 75.15699)
		(width 0.162)
		(layer "In2.Cu")
		(net 166)
	)
	(segment
		(start 131.533852 73.742776)
		(end 131.533851 73.742775)
		(width 0.162)
		(layer "In2.Cu")
		(net 166)
	)
	(segment
		(start 127.782 77.768)
		(end 128.135 77.415)
		(width 0.162)
		(layer "In2.Cu")
		(net 166)
	)
	(segment
		(start 131.413582 75.602406)
		(end 131.413582 75.602407)
		(width 0.162)
		(layer "In2.Cu")
		(net 166)
	)
	(segment
		(start 129.553951 75.4493)
		(end 129.563419 75.439833)
		(width 0.162)
		(layer "In2.Cu")
		(net 166)
	)
	(segment
		(start 132.099537 73.177089)
		(end 132.827797 73.905349)
		(width 0.162)
		(layer "In2.Cu")
		(net 166)
	)
	(segment
		(start 129.716523 77.016623)
		(end 129.076651 76.376751)
		(width 0.162)
		(layer "In2.Cu")
		(net 166)
	)
	(segment
		(start 128.52391 76.884669)
		(end 128.736042 76.672538)
		(width 0.162)
		(layer "In2.Cu")
		(net 166)
	)
	(segment
		(start 130.28221 76.450936)
		(end 129.55395 75.722676)
		(width 0.162)
		(layer "In2.Cu")
		(net 166)
	)
	(segment
		(start 132.634602 72.580782)
		(end 132.634602 72.580781)
		(width 0.162)
		(layer "In2.Cu")
		(net 166)
	)
	(segment
		(start 130.402479 74.874147)
		(end 131.130739 75.602407)
		(width 0.162)
		(layer "In2.Cu")
		(net 166)
	)
	(segment
		(start 131.979268 74.753878)
		(end 131.251008 74.025618)
		(width 0.162)
		(layer "In2.Cu")
		(net 166)
	)
	(segment
		(start 132.351759 72.580781)
		(end 132.351758 72.580782)
		(width 0.162)
		(layer "In2.Cu")
		(net 166)
	)
	(segment
		(start 131.816693 73.186557)
		(end 131.816695 73.186556)
		(width 0.162)
		(layer "In2.Cu")
		(net 166)
	)
	(segment
		(start 130.847896 76.168092)
		(end 130.847896 76.168093)
		(width 0.162)
		(layer "In2.Cu")
		(net 166)
	)
	(segment
		(start 133.485584 72.064416)
		(end 133.485584 65.250322)
		(width 0.162)
		(layer "In2.Cu")
		(net 166)
	)
	(segment
		(start 129.716523 77.016622)
		(end 129.716523 77.016623)
		(width 0.162)
		(layer "In2.Cu")
		(net 166)
	)
	(segment
		(start 132.099538 73.17709)
		(end 132.099537 73.177089)
		(width 0.162)
		(layer "In2.Cu")
		(net 166)
	)
	(segment
		(start 128.62 63.63)
		(end 128.5 63.75)
		(width 0.162)
		(layer "In2.Cu")
		(net 166)
	)
	(segment
		(start 129.836793 75.439833)
		(end 130.565053 76.168093)
		(width 0.162)
		(layer "In2.Cu")
		(net 166)
	)
	(arc
		(start 129.150836 77.865151)
		(mid 129.209415 77.723729)
		(end 129.150836 77.582307)
		(width 0.162)
		(layer "In2.Cu")
		(net 166)
	)
	(arc
		(start 128.867993 77.865151)
		(mid 129.009414 77.92373)
		(end 129.150836 77.865152)
		(width 0.162)
		(layer "In2.Cu")
		(net 166)
	)
	(arc
		(start 129.563419 75.439833)
		(mid 129.700108 75.383215)
		(end 129.836794 75.439834)
		(width 0.162)
		(layer "In2.Cu")
		(net 166)
	)
	(arc
		(start 130.694791 74.308461)
		(mid 130.83148 74.251843)
		(end 130.968166 74.308462)
		(width 0.162)
		(layer "In2.Cu")
		(net 166)
	)
	(arc
		(start 130.119636 75.15699)
		(mid 130.063019 75.020302)
		(end 130.119635 74.883615)
		(width 0.162)
		(layer "In2.Cu")
		(net 166)
	)
	(arc
		(start 129.43368 77.299466)
		(mid 129.575102 77.358044)
		(end 129.716523 77.299465)
		(width 0.162)
		(layer "In2.Cu")
		(net 166)
	)
	(arc
		(start 132.827797 73.905349)
		(mid 132.969219 73.963927)
		(end 133.11064 73.905348)
		(width 0.162)
		(layer "In2.Cu")
		(net 166)
	)
	(arc
		(start 128.523909 76.955381)
		(mid 128.509264 76.920026)
		(end 128.523909 76.884671)
		(width 0.162)
		(layer "In2.Cu")
		(net 166)
	)
	(arc
		(start 129.55395 75.722676)
		(mid 129.497333 75.585988)
		(end 129.553949 75.449301)
		(width 0.162)
		(layer "In2.Cu")
		(net 166)
	)
	(arc
		(start 132.262111 74.471035)
		(mid 132.403533 74.529613)
		(end 132.544954 74.471034)
		(width 0.162)
		(layer "In2.Cu")
		(net 166)
	)
	(arc
		(start 131.696425 75.036721)
		(mid 131.837847 75.095299)
		(end 131.979268 75.03672)
		(width 0.162)
		(layer "In2.Cu")
		(net 166)
	)
	(arc
		(start 131.130739 75.602407)
		(mid 131.272161 75.660985)
		(end 131.413582 75.602406)
		(width 0.162)
		(layer "In2.Cu")
		(net 166)
	)
	(arc
		(start 131.260477 73.742775)
		(mid 131.397166 73.686157)
		(end 131.533852 73.742776)
		(width 0.162)
		(layer "In2.Cu")
		(net 166)
	)
	(arc
		(start 131.816694 73.459932)
		(mid 131.760077 73.323244)
		(end 131.816693 73.186557)
		(width 0.162)
		(layer "In2.Cu")
		(net 166)
	)
	(arc
		(start 130.565053 76.168093)
		(mid 130.706475 76.226671)
		(end 130.847896 76.168092)
		(width 0.162)
		(layer "In2.Cu")
		(net 166)
	)
	(arc
		(start 132.351758 72.863624)
		(mid 132.29318 72.722202)
		(end 132.351759 72.580781)
		(width 0.162)
		(layer "In2.Cu")
		(net 166)
	)
	(arc
		(start 131.413582 75.602407)
		(mid 131.472161 75.460985)
		(end 131.413582 75.319563)
		(width 0.162)
		(layer "In2.Cu")
		(net 166)
	)
	(arc
		(start 130.685322 74.591304)
		(mid 130.628705 74.454616)
		(end 130.685321 74.317929)
		(width 0.162)
		(layer "In2.Cu")
		(net 166)
	)
	(arc
		(start 129.262897 76.093908)
		(mid 129.311195 76.073903)
		(end 129.359495 76.093908)
		(width 0.162)
		(layer "In2.Cu")
		(net 166)
	)
	(arc
		(start 133.676326 73.339663)
		(mid 133.734905 73.198241)
		(end 133.676326 73.056819)
		(width 0.162)
		(layer "In2.Cu")
		(net 166)
	)
	(arc
		(start 133.226174 72.606668)
		(mid 133.167595 72.465247)
		(end 133.226173 72.323825)
		(width 0.162)
		(layer "In2.Cu")
		(net 166)
	)
	(arc
		(start 129.076651 76.376751)
		(mid 129.056646 76.328451)
		(end 129.076651 76.280153)
		(width 0.162)
		(layer "In2.Cu")
		(net 166)
	)
	(arc
		(start 132.351758 72.580782)
		(mid 132.493181 72.522202)
		(end 132.634602 72.580782)
		(width 0.162)
		(layer "In2.Cu")
		(net 166)
	)
	(arc
		(start 130.129105 74.874147)
		(mid 130.265794 74.817529)
		(end 130.40248 74.874148)
		(width 0.162)
		(layer "In2.Cu")
		(net 166)
	)
	(arc
		(start 133.11064 73.905349)
		(mid 133.169219 73.763927)
		(end 133.11064 73.622505)
		(width 0.162)
		(layer "In2.Cu")
		(net 166)
	)
	(arc
		(start 130.28221 76.733779)
		(mid 130.340789 76.592357)
		(end 130.28221 76.450935)
		(width 0.162)
		(layer "In2.Cu")
		(net 166)
	)
	(arc
		(start 132.544954 74.471035)
		(mid 132.603533 74.329613)
		(end 132.544954 74.188191)
		(width 0.162)
		(layer "In2.Cu")
		(net 166)
	)
	(arc
		(start 129.716523 77.299466)
		(mid 129.775102 77.158044)
		(end 129.716523 77.016622)
		(width 0.162)
		(layer "In2.Cu")
		(net 166)
	)
	(arc
		(start 133.393483 73.339663)
		(mid 133.534905 73.398241)
		(end 133.676326 73.339662)
		(width 0.162)
		(layer "In2.Cu")
		(net 166)
	)
	(arc
		(start 131.251008 74.025618)
		(mid 131.194391 73.88893)
		(end 131.251007 73.752243)
		(width 0.162)
		(layer "In2.Cu")
		(net 166)
	)
	(arc
		(start 128.736042 76.672538)
		(mid 128.771398 76.657894)
		(end 128.806753 76.672539)
		(width 0.162)
		(layer "In2.Cu")
		(net 166)
	)
	(arc
		(start 131.826163 73.177089)
		(mid 131.962852 73.120471)
		(end 132.099538 73.17709)
		(width 0.162)
		(layer "In2.Cu")
		(net 166)
	)
	(arc
		(start 129.999367 76.733779)
		(mid 130.140789 76.792357)
		(end 130.28221 76.733778)
		(width 0.162)
		(layer "In2.Cu")
		(net 166)
	)
	(arc
		(start 131.979268 75.036721)
		(mid 132.037847 74.895299)
		(end 131.979268 74.753877)
		(width 0.162)
		(layer "In2.Cu")
		(net 166)
	)
	(arc
		(start 130.847896 76.168093)
		(mid 130.906475 76.026671)
		(end 130.847896 75.885249)
		(width 0.162)
		(layer "In2.Cu")
		(net 166)
	)
	(arc
		(start 128.135 77.415)
		(mid 128.276421 77.356422)
		(end 128.417842 77.415)
		(width 0.162)
		(layer "In2.Cu")
		(net 166)
	)
	(segment
		(start 125.86 62.54)
		(end 126.26 62.14)
		(width 0.182)
		(layer "F.Cu")
		(net 167)
	)
	(segment
		(start 125.1 87.5)
		(end 125.5 87.1)
		(width 0.15)
		(layer "F.Cu")
		(net 167)
	)
	(via
		(at 125.5 87.1)
		(size 0.45)
		(drill 0.2)
		(layers "F.Cu" "B.Cu")
		(remove_unused_layers yes)
		(keep_end_layers yes)
		(zone_layer_connections)
		(net 167)
	)
	(via
		(at 126.26 62.14)
		(size 0.45)
		(drill 0.2)
		(layers "F.Cu" "B.Cu")
		(remove_unused_layers yes)
		(keep_end_layers yes)
		(zone_layer_connections)
		(net 167)
	)
	(segment
		(start 125.56 62.22)
		(end 125.29 62.49)
		(width 0.15)
		(layer "B.Cu")
		(net 167)
	)
	(segment
		(start 126.26 62.14)
		(end 126.18 62.22)
		(width 0.15)
		(layer "B.Cu")
		(net 167)
	)
	(segment
		(start 125.29 62.49)
		(end 125.01 62.49)
		(width 0.15)
		(layer "B.Cu")
		(net 167)
	)
	(segment
		(start 126.18 62.22)
		(end 125.56 62.22)
		(width 0.15)
		(layer "B.Cu")
		(net 167)
	)
	(segment
		(start 133.695115 75.996389)
		(end 134.23361 76.534886)
		(width 0.162)
		(layer "In2.Cu")
		(net 167)
	)
	(segment
		(start 133.950768 76.817728)
		(end 133.681521 76.548481)
		(width 0.162)
		(layer "In2.Cu")
		(net 167)
	)
	(segment
		(start 130.94 61.62)
		(end 133.088155 61.62)
		(width 0.162)
		(layer "In2.Cu")
		(net 167)
	)
	(segment
		(start 134.826488 74.865016)
		(end 135.364984 75.403512)
		(width 0.162)
		(layer "In2.Cu")
		(net 167)
	)
	(segment
		(start 133.129427 76.279235)
		(end 133.129428 76.279234)
		(width 0.162)
		(layer "In2.Cu")
		(net 167)
	)
	(segment
		(start 135.237157 74.71)
		(end 135.109331 74.582174)
		(width 0.162)
		(layer "In2.Cu")
		(net 167)
	)
	(segment
		(start 130.589 61.971)
		(end 130.94 61.62)
		(width 0.162)
		(layer "In2.Cu")
		(net 167)
	)
	(segment
		(start 137.32 72.91)
		(end 135.52 74.71)
		(width 0.162)
		(layer "In2.Cu")
		(net 167)
	)
	(segment
		(start 125.9 86.7)
		(end 125.5 87.1)
		(width 0.15)
		(layer "In2.Cu")
		(net 167)
	)
	(segment
		(start 133.115831 77.114169)
		(end 132.846583 76.844921)
		(width 0.162)
		(layer "In2.Cu")
		(net 167)
	)
	(segment
		(start 126.66 62.54)
		(end 126.26 62.14)
		(width 0.15)
		(layer "In2.Cu")
		(net 167)
	)
	(segment
		(start 132.563741 77.127763)
		(end 133.102236 77.66626)
		(width 0.162)
		(layer "In2.Cu")
		(net 167)
	)
	(segment
		(start 127.29 62.54)
		(end 127.859 61.971)
		(width 0.162)
		(layer "In2.Cu")
		(net 167)
	)
	(segment
		(start 134.260802 75.430702)
		(end 134.799297 75.969199)
		(width 0.162)
		(layer "In2.Cu")
		(net 167)
	)
	(segment
		(start 132.408726 77.821276)
		(end 132.408725 77.821278)
		(width 0.162)
		(layer "In2.Cu")
		(net 167)
	)
	(segment
		(start 133.088155 61.62)
		(end 137.32 65.851845)
		(width 0.162)
		(layer "In2.Cu")
		(net 167)
	)
	(segment
		(start 135.082142 75.686354)
		(end 134.812895 75.417107)
		(width 0.162)
		(layer "In2.Cu")
		(net 167)
	)
	(segment
		(start 132.56374 76.844922)
		(end 132.563741 76.844921)
		(width 0.162)
		(layer "In2.Cu")
		(net 167)
	)
	(segment
		(start 134.812892 75.417108)
		(end 134.543644 75.14786)
		(width 0.162)
		(layer "In2.Cu")
		(net 167)
	)
	(segment
		(start 137.32 65.851845)
		(end 137.32 72.91)
		(width 0.162)
		(layer "In2.Cu")
		(net 167)
	)
	(segment
		(start 127.29 62.54)
		(end 126.66 62.54)
		(width 0.15)
		(layer "In2.Cu")
		(net 167)
	)
	(segment
		(start 133.681521 76.548481)
		(end 133.681518 76.548482)
		(width 0.162)
		(layer "In2.Cu")
		(net 167)
	)
	(segment
		(start 133.667922 77.383416)
		(end 133.667923 77.383415)
		(width 0.162)
		(layer "In2.Cu")
		(net 167)
	)
	(segment
		(start 134.233609 76.817729)
		(end 134.23361 76.817728)
		(width 0.162)
		(layer "In2.Cu")
		(net 167)
	)
	(segment
		(start 134.812895 75.417107)
		(end 134.812892 75.417108)
		(width 0.162)
		(layer "In2.Cu")
		(net 167)
	)
	(segment
		(start 133.385081 77.383415)
		(end 133.115834 77.114168)
		(width 0.162)
		(layer "In2.Cu")
		(net 167)
	)
	(segment
		(start 129.596281 83.203719)
		(end 128.2 84.6)
		(width 0.162)
		(layer "In2.Cu")
		(net 167)
	)
	(segment
		(start 134.247205 75.982795)
		(end 133.977957 75.713547)
		(width 0.162)
		(layer "In2.Cu")
		(net 167)
	)
	(segment
		(start 133.681518 76.548482)
		(end 133.41227 76.279234)
		(width 0.162)
		(layer "In2.Cu")
		(net 167)
	)
	(segment
		(start 134.826488 74.582173)
		(end 134.826488 74.582174)
		(width 0.162)
		(layer "In2.Cu")
		(net 167)
	)
	(segment
		(start 135.364983 75.686355)
		(end 135.364984 75.686354)
		(width 0.162)
		(layer "In2.Cu")
		(net 167)
	)
	(segment
		(start 134.260801 75.147861)
		(end 134.260802 75.14786)
		(width 0.162)
		(layer "In2.Cu")
		(net 167)
	)
	(segment
		(start 133.129428 76.562076)
		(end 133.667923 77.100573)
		(width 0.162)
		(layer "In2.Cu")
		(net 167)
	)
	(segment
		(start 128.2 84.6)
		(end 126.9671 84.6)
		(width 0.162)
		(layer "In2.Cu")
		(net 167)
	)
	(segment
		(start 126.9671 84.6)
		(end 126.4681 85.099)
		(width 0.162)
		(layer "In2.Cu")
		(net 167)
	)
	(segment
		(start 135.237156 74.71)
		(end 135.237157 74.71)
		(width 0.162)
		(layer "In2.Cu")
		(net 167)
	)
	(segment
		(start 125.9 85.331385)
		(end 125.9 86.7)
		(width 0.15)
		(layer "In2.Cu")
		(net 167)
	)
	(segment
		(start 132.819394 77.949102)
		(end 132.691569 77.821277)
		(width 0.162)
		(layer "In2.Cu")
		(net 167)
	)
	(segment
		(start 132.408725 77.821278)
		(end 129.596281 80.633719)
		(width 0.162)
		(layer "In2.Cu")
		(net 167)
	)
	(segment
		(start 134.799296 76.252042)
		(end 134.799297 76.252041)
		(width 0.162)
		(layer "In2.Cu")
		(net 167)
	)
	(segment
		(start 133.102235 77.949103)
		(end 133.102236 77.949102)
		(width 0.162)
		(layer "In2.Cu")
		(net 167)
	)
	(segment
		(start 126.4681 85.099)
		(end 126.132385 85.099)
		(width 0.15)
		(layer "In2.Cu")
		(net 167)
	)
	(segment
		(start 133.115834 77.114168)
		(end 133.115831 77.114169)
		(width 0.162)
		(layer "In2.Cu")
		(net 167)
	)
	(segment
		(start 127.859 61.971)
		(end 130.589 61.971)
		(width 0.162)
		(layer "In2.Cu")
		(net 167)
	)
	(segment
		(start 133.695114 75.713548)
		(end 133.695115 75.713547)
		(width 0.162)
		(layer "In2.Cu")
		(net 167)
	)
	(segment
		(start 134.247208 75.982794)
		(end 134.247205 75.982795)
		(width 0.162)
		(layer "In2.Cu")
		(net 167)
	)
	(segment
		(start 129.596281 80.633719)
		(end 129.596281 83.203719)
		(width 0.162)
		(layer "In2.Cu")
		(net 167)
	)
	(segment
		(start 134.516455 76.252041)
		(end 134.247208 75.982794)
		(width 0.162)
		(layer "In2.Cu")
		(net 167)
	)
	(segment
		(start 126.132385 85.099)
		(end 125.9 85.331385)
		(width 0.15)
		(layer "In2.Cu")
		(net 167)
	)
	(arc
		(start 133.129428 76.279234)
		(mid 133.07085 76.420655)
		(end 133.129428 76.562076)
		(width 0.162)
		(layer "In2.Cu")
		(net 167)
	)
	(arc
		(start 135.109331 74.582174)
		(mid 134.96791 74.523595)
		(end 134.826488 74.582173)
		(width 0.162)
		(layer "In2.Cu")
		(net 167)
	)
	(arc
		(start 134.260802 75.14786)
		(mid 134.202224 75.289281)
		(end 134.260802 75.430702)
		(width 0.162)
		(layer "In2.Cu")
		(net 167)
	)
	(arc
		(start 134.23361 76.534886)
		(mid 134.292188 76.676308)
		(end 134.233609 76.817729)
		(width 0.162)
		(layer "In2.Cu")
		(net 167)
	)
	(arc
		(start 134.799297 75.969199)
		(mid 134.857875 76.110621)
		(end 134.799296 76.252042)
		(width 0.162)
		(layer "In2.Cu")
		(net 167)
	)
	(arc
		(start 132.846583 76.844921)
		(mid 132.705161 76.786343)
		(end 132.56374 76.844922)
		(width 0.162)
		(layer "In2.Cu")
		(net 167)
	)
	(arc
		(start 134.543644 75.14786)
		(mid 134.402222 75.089282)
		(end 134.260801 75.147861)
		(width 0.162)
		(layer "In2.Cu")
		(net 167)
	)
	(arc
		(start 133.667923 77.100573)
		(mid 133.726501 77.241995)
		(end 133.667922 77.383416)
		(width 0.162)
		(layer "In2.Cu")
		(net 167)
	)
	(arc
		(start 134.23361 76.817728)
		(mid 134.092188 76.876307)
		(end 133.950768 76.817728)
		(width 0.162)
		(layer "In2.Cu")
		(net 167)
	)
	(arc
		(start 135.364984 75.403512)
		(mid 135.423562 75.544934)
		(end 135.364983 75.686355)
		(width 0.162)
		(layer "In2.Cu")
		(net 167)
	)
	(arc
		(start 134.826488 74.582174)
		(mid 134.76791 74.723595)
		(end 134.826488 74.865016)
		(width 0.162)
		(layer "In2.Cu")
		(net 167)
	)
	(arc
		(start 132.691569 77.821277)
		(mid 132.550148 77.762698)
		(end 132.408726 77.821276)
		(width 0.162)
		(layer "In2.Cu")
		(net 167)
	)
	(arc
		(start 133.977957 75.713547)
		(mid 133.836535 75.654969)
		(end 133.695114 75.713548)
		(width 0.162)
		(layer "In2.Cu")
		(net 167)
	)
	(arc
		(start 133.667923 77.383415)
		(mid 133.526501 77.441994)
		(end 133.385081 77.383415)
		(width 0.162)
		(layer "In2.Cu")
		(net 167)
	)
	(arc
		(start 135.364984 75.686354)
		(mid 135.223562 75.744933)
		(end 135.082142 75.686354)
		(width 0.162)
		(layer "In2.Cu")
		(net 167)
	)
	(arc
		(start 133.102236 77.949102)
		(mid 132.960814 78.007681)
		(end 132.819394 77.949102)
		(width 0.162)
		(layer "In2.Cu")
		(net 167)
	)
	(arc
		(start 133.102236 77.66626)
		(mid 133.160814 77.807682)
		(end 133.102235 77.949103)
		(width 0.162)
		(layer "In2.Cu")
		(net 167)
	)
	(arc
		(start 132.563741 76.844921)
		(mid 132.505163 76.986342)
		(end 132.563741 77.127763)
		(width 0.162)
		(layer "In2.Cu")
		(net 167)
	)
	(arc
		(start 135.52 74.71)
		(mid 135.378578 74.768579)
		(end 135.237156 74.71)
		(width 0.162)
		(layer "In2.Cu")
		(net 167)
	)
	(arc
		(start 134.799297 76.252041)
		(mid 134.657875 76.31062)
		(end 134.516455 76.252041)
		(width 0.162)
		(layer "In2.Cu")
		(net 167)
	)
	(arc
		(start 133.41227 76.279234)
		(mid 133.270848 76.220656)
		(end 133.129427 76.279235)
		(width 0.162)
		(layer "In2.Cu")
		(net 167)
	)
	(arc
		(start 133.695115 75.713547)
		(mid 133.636537 75.854968)
		(end 133.695115 75.996389)
		(width 0.162)
		(layer "In2.Cu")
		(net 167)
	)
	(segment
		(start 126.66 63.34)
		(end 127.06 62.94)
		(width 0.182)
		(layer "F.Cu")
		(net 168)
	)
	(segment
		(start 125.1 86.7)
		(end 124.7 87.1)
		(width 0.2)
		(layer "F.Cu")
		(net 168)
	)
	(via
		(at 127.06 62.94)
		(size 0.45)
		(drill 0.2)
		(layers "F.Cu" "B.Cu")
		(remove_unused_layers yes)
		(keep_end_layers yes)
		(zone_layer_connections)
		(net 168)
	)
	(via
		(at 124.7 87.1)
		(size 0.45)
		(drill 0.2)
		(layers "F.Cu" "B.Cu")
		(remove_unused_layers yes)
		(keep_end_layers yes)
		(zone_layer_connections)
		(net 168)
	)
	(segment
		(start 125.52 62.99)
		(end 125.97 62.54)
		(width 0.15)
		(layer "B.Cu")
		(net 168)
	)
	(segment
		(start 126.66 62.54)
		(end 127.06 62.94)
		(width 0.15)
		(layer "B.Cu")
		(net 168)
	)
	(segment
		(start 125.01 62.99)
		(end 125.52 62.99)
		(width 0.15)
		(layer "B.Cu")
		(net 168)
	)
	(segment
		(start 125.97 62.54)
		(end 126.66 62.54)
		(width 0.15)
		(layer "B.Cu")
		(net 168)
	)
	(segment
		(start 135.477957 70.84)
		(end 136.742043 70.84)
		(width 0.162)
		(layer "In2.Cu")
		(net 168)
	)
	(segment
		(start 135.477957 71.24)
		(end 136.742043 71.24)
		(width 0.162)
		(layer "In2.Cu")
		(net 168)
	)
	(segment
		(start 136.21 65.61)
		(end 136.21 69.84)
		(width 0.162)
		(layer "In2.Cu")
		(net 168)
	)
	(segment
		(start 136.01 70.04)
		(end 135.477957 70.04)
		(width 0.162)
		(layer "In2.Cu")
		(net 168)
	)
	(segment
		(start 135.055972 72.842552)
		(end 135.055971 72.842552)
		(width 0.162)
		(layer "In2.Cu")
		(net 168)
	)
	(segment
		(start 127.69 62.8)
		(end 130.36 62.8)
		(width 0.162)
		(layer "In2.Cu")
		(net 168)
	)
	(segment
		(start 135.985172 73.48891)
		(end 135.891804 73.395542)
		(width 0.162)
		(layer "In2.Cu")
		(net 168)
	)
	(segment
		(start 135.477957 70.44)
		(end 136.742043 70.44)
		(width 0.162)
		(layer "In2.Cu")
		(net 168)
	)
	(segment
		(start 135.702329 74.054595)
		(end 135.702327 74.054596)
		(width 0.162)
		(layer "In2.Cu")
		(net 168)
	)
	(segment
		(start 134.760429 74.244069)
		(end 128.52 80.4845)
		(width 0.162)
		(layer "In2.Cu")
		(net 168)
	)
	(segment
		(start 125.901 84.299)
		(end 125.1 85.1)
		(width 0.162)
		(layer "In2.Cu")
		(net 168)
	)
	(segment
		(start 135.477957 71.64)
		(end 136.742043 71.64)
		(width 0.162)
		(layer "In2.Cu")
		(net 168)
	)
	(segment
		(start 136.174645 73.112699)
		(end 136.174644 73.112699)
		(width 0.162)
		(layer "In2.Cu")
		(net 168)
	)
	(segment
		(start 135.477957 72.04)
		(end 136.01 72.04)
		(width 0.162)
		(layer "In2.Cu")
		(net 168)
	)
	(segment
		(start 130.816 62.344)
		(end 132.655184 62.344)
		(width 0.162)
		(layer "In2.Cu")
		(net 168)
	)
	(segment
		(start 136.21 72.24)
		(end 136.21 72.7945)
		(width 0.162)
		(layer "In2.Cu")
		(net 168)
	)
	(segment
		(start 135.891804 73.395542)
		(end 135.338814 72.842552)
		(width 0.162)
		(layer "In2.Cu")
		(net 168)
	)
	(segment
		(start 132.655184 62.344)
		(end 133.611184 63.3)
		(width 0.162)
		(layer "In2.Cu")
		(net 168)
	)
	(segment
		(start 130.36 62.8)
		(end 130.816 62.344)
		(width 0.162)
		(layer "In2.Cu")
		(net 168)
	)
	(segment
		(start 135.055971 73.125394)
		(end 135.702328 73.771752)
		(width 0.162)
		(layer "In2.Cu")
		(net 168)
	)
	(segment
		(start 133.611184 63.3)
		(end 133.9 63.3)
		(width 0.162)
		(layer "In2.Cu")
		(net 168)
	)
	(segment
		(start 125.1 85.1)
		(end 125.1 85.3)
		(width 0.162)
		(layer "In2.Cu")
		(net 168)
	)
	(segment
		(start 134.760429 74.244068)
		(end 134.760429 74.244069)
		(width 0.162)
		(layer "In2.Cu")
		(net 168)
	)
	(segment
		(start 134.560995 73.761792)
		(end 134.760429 73.961226)
		(width 0.162)
		(layer "In2.Cu")
		(net 168)
	)
	(segment
		(start 136.21 72.7945)
		(end 136.174645 72.829855)
		(width 0.162)
		(layer "In2.Cu")
		(net 168)
	)
	(segment
		(start 136.268013 73.48891)
		(end 136.268014 73.48891)
		(width 0.162)
		(layer "In2.Cu")
		(net 168)
	)
	(segment
		(start 133.9 63.3)
		(end 136.21 65.61)
		(width 0.162)
		(layer "In2.Cu")
		(net 168)
	)
	(segment
		(start 128.52 83.77)
		(end 127.991 84.299)
		(width 0.162)
		(layer "In2.Cu")
		(net 168)
	)
	(segment
		(start 136.174644 73.112699)
		(end 136.268013 73.206068)
		(width 0.162)
		(layer "In2.Cu")
		(net 168)
	)
	(segment
		(start 134.560995 73.478949)
		(end 134.560995 73.47895)
		(width 0.162)
		(layer "In2.Cu")
		(net 168)
	)
	(segment
		(start 127.55 62.94)
		(end 127.69 62.8)
		(width 0.162)
		(layer "In2.Cu")
		(net 168)
	)
	(segment
		(start 128.52 80.4845)
		(end 128.52 83.77)
		(width 0.162)
		(layer "In2.Cu")
		(net 168)
	)
	(segment
		(start 134.843838 73.47895)
		(end 135.419485 74.054596)
		(width 0.162)
		(layer "In2.Cu")
		(net 168)
	)
	(segment
		(start 125.1 86.7)
		(end 125.1 85.3)
		(width 0.15)
		(layer "In2.Cu")
		(net 168)
	)
	(segment
		(start 127.06 62.94)
		(end 127.55 62.94)
		(width 0.162)
		(layer "In2.Cu")
		(net 168)
	)
	(segment
		(start 127.991 84.299)
		(end 125.901 84.299)
		(width 0.162)
		(layer "In2.Cu")
		(net 168)
	)
	(segment
		(start 124.7 87.1)
		(end 125.1 86.7)
		(width 0.15)
		(layer "In2.Cu")
		(net 168)
	)
	(arc
		(start 136.742043 71.24)
		(mid 136.883464 71.298579)
		(end 136.942043 71.44)
		(width 0.162)
		(layer "In2.Cu")
		(net 168)
	)
	(arc
		(start 135.338814 72.842552)
		(mid 135.197393 72.783974)
		(end 135.055972 72.842552)
		(width 0.162)
		(layer "In2.Cu")
		(net 168)
	)
	(arc
		(start 136.942043 71.44)
		(mid 136.883464 71.581421)
		(end 136.742043 71.64)
		(width 0.162)
		(layer "In2.Cu")
		(net 168)
	)
	(arc
		(start 135.277957 70.24)
		(mid 135.336536 70.381421)
		(end 135.477957 70.44)
		(width 0.162)
		(layer "In2.Cu")
		(net 168)
	)
	(arc
		(start 136.268014 73.48891)
		(mid 136.126592 73.547489)
		(end 135.985172 73.48891)
		(width 0.162)
		(layer "In2.Cu")
		(net 168)
	)
	(arc
		(start 136.942043 70.64)
		(mid 136.883464 70.781421)
		(end 136.742043 70.84)
		(width 0.162)
		(layer "In2.Cu")
		(net 168)
	)
	(arc
		(start 136.268013 73.206068)
		(mid 136.326592 73.347488)
		(end 136.268013 73.48891)
		(width 0.162)
		(layer "In2.Cu")
		(net 168)
	)
	(arc
		(start 135.477957 70.04)
		(mid 135.336536 70.098579)
		(end 135.277957 70.24)
		(width 0.162)
		(layer "In2.Cu")
		(net 168)
	)
	(arc
		(start 134.843838 73.47895)
		(mid 134.702417 73.420371)
		(end 134.560995 73.478949)
		(width 0.162)
		(layer "In2.Cu")
		(net 168)
	)
	(arc
		(start 135.055971 72.842552)
		(mid 134.997393 72.983973)
		(end 135.055971 73.125394)
		(width 0.162)
		(layer "In2.Cu")
		(net 168)
	)
	(arc
		(start 135.702328 73.771752)
		(mid 135.760907 73.913173)
		(end 135.702329 74.054595)
		(width 0.162)
		(layer "In2.Cu")
		(net 168)
	)
	(arc
		(start 136.21 69.84)
		(mid 136.151421 69.981421)
		(end 136.01 70.04)
		(width 0.162)
		(layer "In2.Cu")
		(net 168)
	)
	(arc
		(start 136.174645 72.829855)
		(mid 136.116065 72.971278)
		(end 136.174645 73.112699)
		(width 0.162)
		(layer "In2.Cu")
		(net 168)
	)
	(arc
		(start 135.477957 71.64)
		(mid 135.336536 71.698579)
		(end 135.277957 71.84)
		(width 0.162)
		(layer "In2.Cu")
		(net 168)
	)
	(arc
		(start 136.742043 70.44)
		(mid 136.883464 70.498579)
		(end 136.942043 70.64)
		(width 0.162)
		(layer "In2.Cu")
		(net 168)
	)
	(arc
		(start 135.277957 71.84)
		(mid 135.336536 71.981421)
		(end 135.477957 72.04)
		(width 0.162)
		(layer "In2.Cu")
		(net 168)
	)
	(arc
		(start 135.477957 70.84)
		(mid 135.336536 70.898579)
		(end 135.277957 71.04)
		(width 0.162)
		(layer "In2.Cu")
		(net 168)
	)
	(arc
		(start 136.01 72.04)
		(mid 136.151421 72.098579)
		(end 136.21 72.24)
		(width 0.162)
		(layer "In2.Cu")
		(net 168)
	)
	(arc
		(start 135.702327 74.054596)
		(mid 135.560907 74.113173)
		(end 135.419485 74.054596)
		(width 0.162)
		(layer "In2.Cu")
		(net 168)
	)
	(arc
		(start 134.760429 73.961226)
		(mid 134.819007 74.102647)
		(end 134.760429 74.244068)
		(width 0.162)
		(layer "In2.Cu")
		(net 168)
	)
	(arc
		(start 134.560995 73.47895)
		(mid 134.502417 73.620371)
		(end 134.560995 73.761792)
		(width 0.162)
		(layer "In2.Cu")
		(net 168)
	)
	(arc
		(start 135.277957 71.04)
		(mid 135.336536 71.181421)
		(end 135.477957 71.24)
		(width 0.162)
		(layer "In2.Cu")
		(net 168)
	)
	(segment
		(start 113.32 109.44)
		(end 106.08 109.44)
		(width 0.15)
		(layer "F.Cu")
		(net 169)
	)
	(segment
		(start 123.9 93.5)
		(end 124.3 93.1)
		(width 0.15)
		(layer "F.Cu")
		(net 169)
	)
	(segment
		(start 101.67 111.07)
		(end 98.94 113.8)
		(width 0.15)
		(layer "F.Cu")
		(net 169)
	)
	(segment
		(start 122.19 100.57)
		(end 113.32 109.44)
		(width 0.15)
		(layer "F.Cu")
		(net 169)
	)
	(segment
		(start 122.38 100.57)
		(end 122.19 100.57)
		(width 0.15)
		(layer "F.Cu")
		(net 169)
	)
	(segment
		(start 101.67 108.91)
		(end 101.67 111.07)
		(width 0.15)
		(layer "F.Cu")
		(net 169)
	)
	(segment
		(start 105.34 108.7)
		(end 105.34 107.37)
		(width 0.15)
		(layer "F.Cu")
		(net 169)
	)
	(segment
		(start 98.94 113.8)
		(end 98.94 114.7)
		(width 0.15)
		(layer "F.Cu")
		(net 169)
	)
	(segment
		(start 123.9 94.323234)
		(end 123.9 93.5)
		(width 0.15)
		(layer "F.Cu")
		(net 169)
	)
	(segment
		(start 105.34 107.37)
		(end 105.19 107.22)
		(width 0.15)
		(layer "F.Cu")
		(net 169)
	)
	(segment
		(start 106.08 109.44)
		(end 105.34 108.7)
		(width 0.15)
		(layer "F.Cu")
		(net 169)
	)
	(segment
		(start 103.36 107.22)
		(end 101.67 108.91)
		(width 0.15)
		(layer "F.Cu")
		(net 169)
	)
	(segment
		(start 105.19 107.22)
		(end 103.36 107.22)
		(width 0.15)
		(layer "F.Cu")
		(net 169)
	)
	(via
		(at 123.9 94.323234)
		(size 0.45)
		(drill 0.2)
		(layers "F.Cu" "B.Cu")
		(remove_unused_layers yes)
		(keep_end_layers yes)
		(free yes)
		(zone_layer_connections)
		(net 169)
	)
	(via
		(at 122.38 100.57)
		(size 0.45)
		(drill 0.2)
		(layers "F.Cu" "B.Cu")
		(remove_unused_layers yes)
		(keep_end_layers yes)
		(zone_layer_connections)
		(net 169)
	)
	(segment
		(start 122.38 98.42)
		(end 122.38 100.57)
		(width 0.125)
		(layer "B.Cu")
		(net 169)
	)
	(segment
		(start 123.5 97.3)
		(end 122.38 98.42)
		(width 0.125)
		(layer "B.Cu")
		(net 169)
	)
	(segment
		(start 123.5 94.723234)
		(end 123.5 97.3)
		(width 0.125)
		(layer "B.Cu")
		(net 169)
	)
	(segment
		(start 123.9 94.323234)
		(end 123.5 94.723234)
		(width 0.125)
		(layer "B.Cu")
		(net 169)
	)
	(segment
		(start 114.06 110.58)
		(end 102.67 110.58)
		(width 0.15)
		(layer "F.Cu")
		(net 170)
	)
	(segment
		(start 120 104.64)
		(end 114.06 110.58)
		(width 0.15)
		(layer "F.Cu")
		(net 170)
	)
	(segment
		(start 120 104.6)
		(end 120 104.64)
		(width 0.15)
		(layer "F.Cu")
		(net 170)
	)
	(segment
		(start 99.94 113.31)
		(end 99.94 114.7)
		(width 0.15)
		(layer "F.Cu")
		(net 170)
	)
	(segment
		(start 102.67 110.58)
		(end 99.94 113.31)
		(width 0.15)
		(layer "F.Cu")
		(net 170)
	)
	(via
		(at 121.9 92.3005)
		(size 0.45)
		(drill 0.2)
		(layers "F.Cu" "B.Cu")
		(remove_unused_layers yes)
		(keep_end_layers yes)
		(free yes)
		(zone_layer_connections)
		(net 170)
	)
	(via
		(at 120 104.6)
		(size 0.45)
		(drill 0.2)
		(layers "F.Cu" "B.Cu")
		(remove_unused_layers yes)
		(keep_end_layers yes)
		(zone_layer_connections)
		(net 170)
	)
	(segment
		(start 121.9 92.3005)
		(end 121.5995 92.3005)
		(width 0.125)
		(layer "B.Cu")
		(net 170)
	)
	(segment
		(start 121.5995 92.3005)
		(end 120 93.9)
		(width 0.125)
		(layer "B.Cu")
		(net 170)
	)
	(segment
		(start 120 93.9)
		(end 120 104.6)
		(width 0.125)
		(layer "B.Cu")
		(net 170)
	)
	(segment
		(start 113.99 111.52)
		(end 102.26 111.52)
		(width 0.15)
		(layer "F.Cu")
		(net 171)
	)
	(segment
		(start 120.7 105.5)
		(end 114.68 111.52)
		(width 0.125)
		(layer "F.Cu")
		(net 171)
	)
	(segment
		(start 102.26 111.52)
		(end 100.94 112.84)
		(width 0.15)
		(layer "F.Cu")
		(net 171)
	)
	(segment
		(start 100.94 112.84)
		(end 100.94 114.7)
		(width 0.15)
		(layer "F.Cu")
		(net 171)
	)
	(segment
		(start 121.9 93.1)
		(end 121.5 93.5)
		(width 0.15)
		(layer "F.Cu")
		(net 171)
	)
	(segment
		(start 114.68 111.52)
		(end 113.99 111.52)
		(width 0.125)
		(layer "F.Cu")
		(net 171)
	)
	(via
		(at 120.7 105.5)
		(size 0.45)
		(drill 0.2)
		(layers "F.Cu" "B.Cu")
		(remove_unused_layers yes)
		(keep_end_layers yes)
		(zone_layer_connections)
		(net 171)
	)
	(via
		(at 121.5 93.5)
		(size 0.45)
		(drill 0.2)
		(layers "F.Cu" "B.Cu")
		(remove_unused_layers yes)
		(keep_end_layers yes)
		(zone_layer_connections)
		(net 171)
	)
	(segment
		(start 121.217 94.717)
		(end 121.217 97.297998)
		(width 0.125)
		(layer "B.Cu")
		(net 171)
	)
	(segment
		(start 121 94)
		(end 121 94.5)
		(width 0.125)
		(layer "B.Cu")
		(net 171)
	)
	(segment
		(start 120.8 105.4)
		(end 120.7 105.5)
		(width 0.125)
		(layer "B.Cu")
		(net 171)
	)
	(segment
		(start 121 94.5)
		(end 121.217 94.717)
		(width 0.125)
		(layer "B.Cu")
		(net 171)
	)
	(segment
		(start 121.5 93.5)
		(end 121 94)
		(width 0.125)
		(layer "B.Cu")
		(net 171)
	)
	(segment
		(start 120.8 97.714998)
		(end 120.8 105.4)
		(width 0.125)
		(layer "B.Cu")
		(net 171)
	)
	(segment
		(start 121.217 97.297998)
		(end 120.8 97.714998)
		(width 0.125)
		(layer "B.Cu")
		(net 171)
	)
	(segment
		(start 122.446 105.064)
		(end 115.39 112.12)
		(width 0.15)
		(layer "F.Cu")
		(net 172)
	)
	(segment
		(start 123.9 92.7)
		(end 124.3 92.3)
		(width 0.15)
		(layer "F.Cu")
		(net 172)
	)
	(segment
		(start 102.99 112.12)
		(end 101.94 113.17)
		(width 0.15)
		(layer "F.Cu")
		(net 172)
	)
	(segment
		(start 115.39 112.12)
		(end 102.99 112.12)
		(width 0.15)
		(layer "F.Cu")
		(net 172)
	)
	(segment
		(start 101.94 113.17)
		(end 101.94 114.7)
		(width 0.15)
		(layer "F.Cu")
		(net 172)
	)
	(segment
		(start 122.446 104.81)
		(end 122.446 105.064)
		(width 0.15)
		(layer "F.Cu")
		(net 172)
	)
	(via
		(at 123.9 92.7)
		(size 0.45)
		(drill 0.2)
		(layers "F.Cu" "B.Cu")
		(remove_unused_layers yes)
		(keep_end_layers yes)
		(free yes)
		(zone_layer_connections)
		(net 172)
	)
	(via
		(at 122.446 104.81)
		(size 0.45)
		(drill 0.2)
		(layers "F.Cu" "B.Cu")
		(remove_unused_layers yes)
		(keep_end_layers yes)
		(zone_layer_connections)
		(net 172)
	)
	(segment
		(start 123.487499 93.112501)
		(end 122.887499 93.112501)
		(width 0.125)
		(layer "B.Cu")
		(net 172)
	)
	(segment
		(start 121.2 97.9)
		(end 121.2 103.564)
		(width 0.125)
		(layer "B.Cu")
		(net 172)
	)
	(segment
		(start 122.887499 93.112501)
		(end 122.7 93.3)
		(width 0.125)
		(layer "B.Cu")
		(net 172)
	)
	(segment
		(start 121.5 97.6)
		(end 121.2 97.9)
		(width 0.125)
		(layer "B.Cu")
		(net 172)
	)
	(segment
		(start 121.5 95)
		(end 121.5 97.6)
		(width 0.125)
		(layer "B.Cu")
		(net 172)
	)
	(segment
		(start 122.7 93.3)
		(end 122.7 93.8)
		(width 0.125)
		(layer "B.Cu")
		(net 172)
	)
	(segment
		(start 123.9 92.7)
		(end 123.487499 93.112501)
		(width 0.125)
		(layer "B.Cu")
		(net 172)
	)
	(segment
		(start 122.7 93.8)
		(end 121.5 95)
		(width 0.125)
		(layer "B.Cu")
		(net 172)
	)
	(segment
		(start 121.2 103.564)
		(end 122.446 104.81)
		(width 0.125)
		(layer "B.Cu")
		(net 172)
	)
	(segment
		(start 124.71 94.3)
		(end 124.71 94.29)
		(width 0.15)
		(layer "F.Cu")
		(net 173)
	)
	(segment
		(start 115.45 112.73)
		(end 103.69 112.73)
		(width 0.15)
		(layer "F.Cu")
		(net 173)
	)
	(segment
		(start 123.29 105.58)
		(end 122.6 105.58)
		(width 0.15)
		(layer "F.Cu")
		(net 173)
	)
	(segment
		(start 124.71 94.29)
		(end 125.1 93.9)
		(width 0.15)
		(layer "F.Cu")
		(net 173)
	)
	(segment
		(start 123.29 105.58)
		(end 122.975 105.895)
		(width 0.15)
		(layer "F.Cu")
		(net 173)
	)
	(segment
		(start 103.69 112.73)
		(end 102.94 113.48)
		(width 0.15)
		(layer "F.Cu")
		(net 173)
	)
	(segment
		(start 122.975 105.895)
		(end 122.975 106.16)
		(width 0.15)
		(layer "F.Cu")
		(net 173)
	)
	(segment
		(start 122.6 105.58)
		(end 115.45 112.73)
		(width 0.15)
		(layer "F.Cu")
		(net 173)
	)
	(segment
		(start 102.94 113.48)
		(end 102.94 114.7)
		(width 0.15)
		(layer "F.Cu")
		(net 173)
	)
	(via
		(at 123.29 105.58)
		(size 0.45)
		(drill 0.2)
		(layers "F.Cu" "B.Cu")
		(remove_unused_layers yes)
		(keep_end_layers yes)
		(zone_layer_connections)
		(net 173)
	)
	(via
		(at 124.71 94.3)
		(size 0.45)
		(drill 0.2)
		(layers "F.Cu" "B.Cu")
		(remove_unused_layers yes)
		(keep_end_layers yes)
		(free yes)
		(zone_layer_connections)
		(net 173)
	)
	(segment
		(start 121.9 99.7)
		(end 123.9 97.7)
		(width 0.125)
		(layer "In6.Cu")
		(net 173)
	)
	(segment
		(start 121.9 103.4)
		(end 121.9 99.7)
		(width 0.125)
		(layer "In6.Cu")
		(net 173)
	)
	(segment
		(start 123.9 95.11)
		(end 124.71 94.3)
		(width 0.125)
		(layer "In6.Cu")
		(net 173)
	)
	(segment
		(start 123.29 105.58)
		(end 123.29 104.79)
		(width 0.125)
		(layer "In6.Cu")
		(net 173)
	)
	(segment
		(start 123.9 97.7)
		(end 123.9 95.11)
		(width 0.125)
		(layer "In6.Cu")
		(net 173)
	)
	(segment
		(start 123.29 104.79)
		(end 121.9 103.4)
		(width 0.125)
		(layer "In6.Cu")
		(net 173)
	)
	(segment
		(start 129.9 93.9)
		(end 129.5 93.5)
		(width 0.15)
		(layer "F.Cu")
		(net 175)
	)
	(segment
		(start 97.1 75.41)
		(end 97.59 75.9)
		(width 0.15)
		(layer "F.Cu")
		(net 175)
	)
	(via
		(at 94.2905 84.91)
		(size 0.45)
		(drill 0.2)
		(layers "F.Cu" "B.Cu")
		(remove_unused_layers yes)
		(keep_end_layers yes)
		(zone_layer_connections)
		(net 175)
	)
	(via
		(at 129.5 93.5)
		(size 0.45)
		(drill 0.2)
		(layers "F.Cu" "B.Cu")
		(remove_unused_layers yes)
		(keep_end_layers yes)
		(free yes)
		(zone_layer_connections)
		(net 175)
	)
	(via
		(at 97.59 75.9)
		(size 0.45)
		(drill 0.2)
		(layers "F.Cu" "B.Cu")
		(remove_unused_layers yes)
		(keep_end_layers yes)
		(zone_layer_connections)
		(net 175)
	)
	(via
		(at 103.5305 82.63)
		(size 0.45)
		(drill 0.2)
		(layers "F.Cu" "B.Cu")
		(net 175)
	)
	(segment
		(start 131.9 93.5)
		(end 140 93.5)
		(width 0.125)
		(layer "B.Cu")
		(net 175)
	)
	(segment
		(start 140.4 84.7)
		(end 140.4 84)
		(width 0.125)
		(layer "B.Cu")
		(net 175)
	)
	(segment
		(start 130.478266 93.1)
		(end 130.705767 93.327501)
		(width 0.125)
		(layer "B.Cu")
		(net 175)
	)
	(segment
		(start 94.7408 87.1258)
		(end 94.7408 88.95)
		(width 0.15)
		(layer "B.Cu")
		(net 175)
	)
	(segment
		(start 97.165 76.325)
		(end 96.42396 76.325)
		(width 0.15)
		(layer "B.Cu")
		(net 175)
	)
	(segment
		(start 94.668807 80.61)
		(end 94.99 80.931193)
		(width 0.15)
		(layer "B.Cu")
		(net 175)
	)
	(segment
		(start 94.415 76.375)
		(end 94.03 76.76)
		(width 0.15)
		(layer "B.Cu")
		(net 175)
	)
	(segment
		(start 121.2 78.4)
		(end 117.59 82.01)
		(width 0.125)
		(layer "B.Cu")
		(net 175)
	)
	(segment
		(start 94.19 86.575)
		(end 94.7408 87.1258)
		(width 0.15)
		(layer "B.Cu")
		(net 175)
	)
	(segment
		(start 94.99 80.931193)
		(end 94.99 81.9)
		(width 0.15)
		(layer "B.Cu")
		(net 175)
	)
	(segment
		(start 104.1505 82.01)
		(end 103.5305 82.63)
		(width 0.125)
		(layer "B.Cu")
		(net 175)
	)
	(segment
		(start 94.03 77.11)
		(end 93.75 77.39)
		(width 0.15)
		(layer "B.Cu")
		(net 175)
	)
	(segment
		(start 129.5 93.5)
		(end 129.9 93.1)
		(width 0.125)
		(layer "B.Cu")
		(net 175)
	)
	(segment
		(start 140.4 84.7)
		(end 140.4 91.77473)
		(width 0.13)
		(layer "B.Cu")
		(net 175)
	)
	(segment
		(start 140.4 93.1)
		(end 140.4 86.4)
		(width 0.125)
		(layer "B.Cu")
		(net 175)
	)
	(segment
		(start 94.273128 80.61)
		(end 94.668807 80.61)
		(width 0.15)
		(layer "B.Cu")
		(net 175)
	)
	(segment
		(start 93.19 79.53)
		(end 94.271564 80.611564)
		(width 0.15)
		(layer "B.Cu")
		(net 175)
	)
	(segment
		(start 130.705767 93.327501)
		(end 131.7275 93.3275)
		(width 0.125)
		(layer "B.Cu")
		(net 175)
	)
	(segment
		(start 94.99 81.9)
		(end 94.2905 82.5995)
		(width 0.15)
		(layer "B.Cu")
		(net 175)
	)
	(segment
		(start 94.726041 76.375)
		(end 94.415 76.375)
		(width 0.15)
		(layer "B.Cu")
		(net 175)
	)
	(segment
		(start 131.7275 93.3275)
		(end 131.9 93.5)
		(width 0.125)
		(layer "B.Cu")
		(net 175)
	)
	(segment
		(start 94.2905 82.5995)
		(end 94.2905 84.91)
		(width 0.15)
		(layer "B.Cu")
		(net 175)
	)
	(segment
		(start 93.19 77.72)
		(end 93.19 79.53)
		(width 0.15)
		(layer "B.Cu")
		(net 175)
	)
	(segment
		(start 134.8 78.4)
		(end 121.2 78.4)
		(width 0.125)
		(layer "B.Cu")
		(net 175)
	)
	(segment
		(start 96.14896 76.05)
		(end 95.051041 76.05)
		(width 0.15)
		(layer "B.Cu")
		(net 175)
	)
	(segment
		(start 93.52 77.39)
		(end 93.19 77.72)
		(width 0.15)
		(layer "B.Cu")
		(net 175)
	)
	(segment
		(start 97.59 75.9)
		(end 97.165 76.325)
		(width 0.15)
		(layer "B.Cu")
		(net 175)
	)
	(segment
		(start 140 93.5)
		(end 140.4 93.1)
		(width 0.125)
		(layer "B.Cu")
		(net 175)
	)
	(segment
		(start 95.051041 76.05)
		(end 94.726041 76.375)
		(width 0.15)
		(layer "B.Cu")
		(net 175)
	)
	(segment
		(start 94.03 76.76)
		(end 94.03 77.11)
		(width 0.15)
		(layer "B.Cu")
		(net 175)
	)
	(segment
		(start 129.9 93.1)
		(end 130.478266 93.1)
		(width 0.125)
		(layer "B.Cu")
		(net 175)
	)
	(segment
		(start 94.2905 84.91)
		(end 94.19 85.0105)
		(width 0.15)
		(layer "B.Cu")
		(net 175)
	)
	(segment
		(start 117.59 82.01)
		(end 104.1505 82.01)
		(width 0.125)
		(layer "B.Cu")
		(net 175)
	)
	(segment
		(start 94.19 85.0105)
		(end 94.19 86.575)
		(width 0.15)
		(layer "B.Cu")
		(net 175)
	)
	(segment
		(start 94.271564 80.611564)
		(end 94.273128 80.61)
		(width 0.15)
		(layer "B.Cu")
		(net 175)
	)
	(segment
		(start 93.75 77.39)
		(end 93.52 77.39)
		(width 0.15)
		(layer "B.Cu")
		(net 175)
	)
	(segment
		(start 96.42396 76.325)
		(end 96.14896 76.05)
		(width 0.15)
		(layer "B.Cu")
		(net 175)
	)
	(segment
		(start 140.4 84)
		(end 134.8 78.4)
		(width 0.125)
		(layer "B.Cu")
		(net 175)
	)
	(segment
		(start 94.2905 85.7105)
		(end 94.81 86.23)
		(width 0.15)
		(layer "In2.Cu")
		(net 175)
	)
	(segment
		(start 103.5305 82.8095)
		(end 103.5305 82.63)
		(width 0.15)
		(layer "In2.Cu")
		(net 175)
	)
	(segment
		(start 94.2905 84.91)
		(end 94.2905 85.7105)
		(width 0.15)
		(layer "In2.Cu")
		(net 175)
	)
	(segment
		(start 94.81 86.23)
		(end 97.17 86.23)
		(width 0.15)
		(layer "In2.Cu")
		(net 175)
	)
	(segment
		(start 102.04 84.3)
		(end 103.5305 82.8095)
		(width 0.15)
		(layer "In2.Cu")
		(net 175)
	)
	(segment
		(start 99.1 84.3)
		(end 102.04 84.3)
		(width 0.15)
		(layer "In2.Cu")
		(net 175)
	)
	(segment
		(start 97.17 86.23)
		(end 99.1 84.3)
		(width 0.15)
		(layer "In2.Cu")
		(net 175)
	)
	(segment
		(start 92.41 81.89)
		(end 92.41 82.09)
		(width 0.15)
		(layer "F.Cu")
		(net 176)
	)
	(segment
		(start 92.41 82.09)
		(end 92.1 82.4)
		(width 0.15)
		(layer "F.Cu")
		(net 176)
	)
	(segment
		(start 128.323234 92.3)
		(end 128.723235 92.700001)
		(width 0.15)
		(layer "F.Cu")
		(net 176)
	)
	(via
		(at 136.1 81.5)
		(size 0.45)
		(drill 0.2)
		(layers "F.Cu" "B.Cu")
		(net 176)
	)
	(via
		(at 92.41 81.89)
		(size 0.45)
		(drill 0.2)
		(layers "F.Cu" "B.Cu")
		(remove_unused_layers yes)
		(keep_end_layers yes)
		(zone_layer_connections)
		(net 176)
	)
	(via
		(at 102.311146 85.308854)
		(size 0.45)
		(drill 0.2)
		(layers "F.Cu" "B.Cu")
		(remove_unused_layers yes)
		(keep_end_layers yes)
		(zone_layer_connections)
		(net 176)
	)
	(via
		(at 128.723235 92.700001)
		(size 0.45)
		(drill 0.2)
		(layers "F.Cu" "B.Cu")
		(remove_unused_layers yes)
		(keep_end_layers yes)
		(zone_layer_connections)
		(net 176)
	)
	(segment
		(start 121.9 79.6)
		(end 117.2 84.3)
		(width 0.125)
		(layer "B.Cu")
		(net 176)
	)
	(segment
		(start 117.2 84.3)
		(end 106.2 84.3)
		(width 0.125)
		(layer "B.Cu")
		(net 176)
	)
	(segment
		(start 134.2 79.6)
		(end 121.9 79.6)
		(width 0.125)
		(layer "B.Cu")
		(net 176)
	)
	(segment
		(start 106.2 84.3)
		(end 105.191146 85.308854)
		(width 0.125)
		(layer "B.Cu")
		(net 176)
	)
	(segment
		(start 136.1 81.5)
		(end 134.2 79.6)
		(width 0.125)
		(layer "B.Cu")
		(net 176)
	)
	(segment
		(start 92.19 82.2)
		(end 92.19 85.2)
		(width 0.15)
		(layer "B.Cu")
		(net 176)
	)
	(segment
		(start 91.69 85.7)
		(end 91.69 88.95)
		(width 0.15)
		(layer "B.Cu")
		(net 176)
	)
	(segment
		(start 92.19 85.2)
		(end 91.69 85.7)
		(width 0.15)
		(layer "B.Cu")
		(net 176)
	)
	(segment
		(start 92.41 81.89)
		(end 92.41 81.98)
		(width 0.15)
		(layer "B.Cu")
		(net 176)
	)
	(segment
		(start 105.191146 85.308854)
		(end 102.311146 85.308854)
		(width 0.125)
		(layer "B.Cu")
		(net 176)
	)
	(segment
		(start 92.41 81.98)
		(end 92.19 82.2)
		(width 0.15)
		(layer "B.Cu")
		(net 176)
	)
	(segment
		(start 129.3 91.5)
		(end 129.1 91.7)
		(width 0.125)
		(layer "In2.Cu")
		(net 176)
	)
	(segment
		(start 130.7 86)
		(end 130.7 86.5)
		(width 0.125)
		(layer "In2.Cu")
		(net 176)
	)
	(segment
		(start 129.1 92.323236)
		(end 128.723235 92.700001)
		(width 0.125)
		(layer "In2.Cu")
		(net 176)
	)
	(segment
		(start 130.7 86.5)
		(end 130.5 86.7)
		(width 0.125)
		(layer "In2.Cu")
		(net 176)
	)
	(segment
		(start 129.9 86.9)
		(end 129.9 91.3)
		(width 0.125)
		(layer "In2.Cu")
		(net 176)
	)
	(segment
		(start 130.5 86.7)
		(end 130.1 86.7)
		(width 0.125)
		(layer "In2.Cu")
		(net 176)
	)
	(segment
		(start 133.8 85.4)
		(end 131.3 85.4)
		(width 0.125)
		(layer "In2.Cu")
		(net 176)
	)
	(segment
		(start 136.1 83.1)
		(end 133.8 85.4)
		(width 0.125)
		(layer "In2.Cu")
		(net 176)
	)
	(segment
		(start 129.1 91.7)
		(end 129.1 92.323236)
		(width 0.125)
		(layer "In2.Cu")
		(net 176)
	)
	(segment
		(start 130.1 86.7)
		(end 129.9 86.9)
		(width 0.125)
		(layer "In2.Cu")
		(net 176)
	)
	(segment
		(start 129.7 91.5)
		(end 129.3 91.5)
		(width 0.125)
		(layer "In2.Cu")
		(net 176)
	)
	(segment
		(start 129.9 91.3)
		(end 129.7 91.5)
		(width 0.125)
		(layer "In2.Cu")
		(net 176)
	)
	(segment
		(start 131.3 85.4)
		(end 130.7 86)
		(width 0.125)
		(layer "In2.Cu")
		(net 176)
	)
	(segment
		(start 136.1 81.5)
		(end 136.1 83.1)
		(width 0.125)
		(layer "In2.Cu")
		(net 176)
	)
	(segment
		(start 101 84)
		(end 101.4 84.4)
		(width 0.15)
		(layer "In4.Cu")
		(net 176)
	)
	(segment
		(start 101.4 84.4)
		(end 101.5041 84.4)
		(width 0.15)
		(layer "In4.Cu")
		(net 176)
	)
	(segment
		(start 101 83.636777)
		(end 101 84)
		(width 0.15)
		(layer "In4.Cu")
		(net 176)
	)
	(segment
		(start 92.41 81.89)
		(end 92.92 82.4)
		(width 0.15)
		(layer "In4.Cu")
		(net 176)
	)
	(segment
		(start 99.763223 82.4)
		(end 101 83.636777)
		(width 0.15)
		(layer "In4.Cu")
		(net 176)
	)
	(segment
		(start 101.5041 84.4)
		(end 102.311146 85.207046)
		(width 0.15)
		(layer "In4.Cu")
		(net 176)
	)
	(segment
		(start 102.311146 85.207046)
		(end 102.311146 85.308854)
		(width 0.15)
		(layer "In4.Cu")
		(net 176)
	)
	(segment
		(start 92.92 82.4)
		(end 99.763223 82.4)
		(width 0.15)
		(layer "In4.Cu")
		(net 176)
	)
	(segment
		(start 127.905913 94.294087)
		(end 128.3 93.9)
		(width 0.15)
		(layer "F.Cu")
		(net 177)
	)
	(segment
		(start 96.59 76.91)
		(end 97.1 76.4)
		(width 0.15)
		(layer "F.Cu")
		(net 177)
	)
	(segment
		(start 96.59 77.1)
		(end 96.59 76.91)
		(width 0.15)
		(layer "F.Cu")
		(net 177)
	)
	(segment
		(start 127.905913 94.3)
		(end 127.905913 94.294087)
		(width 0.15)
		(layer "F.Cu")
		(net 177)
	)
	(via
		(at 103.38 80.8285)
		(size 0.45)
		(drill 0.2)
		(layers "F.Cu" "B.Cu")
		(remove_unused_layers yes)
		(keep_end_layers yes)
		(zone_layer_connections)
		(net 177)
	)
	(via
		(at 127.905913 94.3)
		(size 0.45)
		(drill 0.2)
		(layers "F.Cu" "B.Cu")
		(remove_unused_layers yes)
		(keep_end_layers yes)
		(free yes)
		(zone_layer_connections)
		(net 177)
	)
	(via
		(at 137.58 97.97)
		(size 0.45)
		(drill 0.2)
		(layers "F.Cu" "B.Cu")
		(remove_unused_layers yes)
		(keep_end_layers yes)
		(zone_layer_connections)
		(net 177)
	)
	(via
		(at 96.59 77.1)
		(size 0.45)
		(drill 0.2)
		(layers "F.Cu" "B.Cu")
		(remove_unused_layers yes)
		(keep_end_layers yes)
		(zone_layer_connections)
		(net 177)
	)
	(segment
		(start 95.11 80)
		(end 95.11 77.61)
		(width 0.15)
		(layer "B.Cu")
		(net 177)
	)
	(segment
		(start 95.19 82.7)
		(end 95.79 82.1)
		(width 0.15)
		(layer "B.Cu")
		(net 177)
	)
	(segment
		(start 133.75 77.25)
		(end 119.85 77.25)
		(width 0.15)
		(layer "B.Cu")
		(net 177)
	)
	(segment
		(start 96.19 87.45)
		(end 95.19 86.45)
		(width 0.15)
		(layer "B.Cu")
		(net 177)
	)
	(segment
		(start 116.78 80.32)
		(end 103.8885 80.32)
		(width 0.15)
		(layer "B.Cu")
		(net 177)
	)
	(segment
		(start 141.3 83.05)
		(end 141.3 95.45)
		(width 0.125)
		(layer "B.Cu")
		(net 177)
	)
	(segment
		(start 95.36 77.36)
		(end 96.33 77.36)
		(width 0.15)
		(layer "B.Cu")
		(net 177)
	)
	(segment
		(start 135.5 77.25)
		(end 141.3 83.05)
		(width 0.125)
		(layer "B.Cu")
		(net 177)
	)
	(segment
		(start 133.75 77.25)
		(end 135.5 77.25)
		(width 0.125)
		(layer "B.Cu")
		(net 177)
	)
	(segment
		(start 95.79 80.68)
		(end 95.11 80)
		(width 0.15)
		(layer "B.Cu")
		(net 177)
	)
	(segment
		(start 95.79 82.1)
		(end 95.79 80.68)
		(width 0.15)
		(layer "B.Cu")
		(net 177)
	)
	(segment
		(start 95.19 86.45)
		(end 95.19 82.7)
		(width 0.15)
		(layer "B.Cu")
		(net 177)
	)
	(segment
		(start 138.78 97.97)
		(end 141.3 95.45)
		(width 0.125)
		(layer "B.Cu")
		(net 177)
	)
	(segment
		(start 119.85 77.25)
		(end 116.78 80.32)
		(width 0.15)
		(layer "B.Cu")
		(net 177)
	)
	(segment
		(start 95.11 77.61)
		(end 95.36 77.36)
		(width 0.15)
		(layer "B.Cu")
		(net 177)
	)
	(segment
		(start 103.8885 80.32)
		(end 103.38 80.8285)
		(width 0.15)
		(layer "B.Cu")
		(net 177)
	)
	(segment
		(start 96.33 77.36)
		(end 96.59 77.1)
		(width 0.15)
		(layer "B.Cu")
		(net 177)
	)
	(segment
		(start 137.58 97.97)
		(end 138.78 97.97)
		(width 0.125)
		(layer "B.Cu")
		(net 177)
	)
	(segment
		(start 96.19 88.95)
		(end 96.19 87.45)
		(width 0.15)
		(layer "B.Cu")
		(net 177)
	)
	(segment
		(start 96.89 77.4)
		(end 96.59 77.1)
		(width 0.15)
		(layer "In2.Cu")
		(net 177)
	)
	(segment
		(start 100.1 79.5)
		(end 100.1 78.4)
		(width 0.15)
		(layer "In2.Cu")
		(net 177)
	)
	(segment
		(start 103.38 80.8285)
		(end 103.2785 80.8285)
		(width 0.15)
		(layer "In2.Cu")
		(net 177)
	)
	(segment
		(start 99.1 77.4)
		(end 96.89 77.4)
		(width 0.15)
		(layer "In2.Cu")
		(net 177)
	)
	(segment
		(start 103.2785 80.8285)
		(end 102.35 79.9)
		(width 0.15)
		(layer "In2.Cu")
		(net 177)
	)
	(segment
		(start 100.5 79.9)
		(end 100.1 79.5)
		(width 0.15)
		(layer "In2.Cu")
		(net 177)
	)
	(segment
		(start 102.35 79.9)
		(end 100.5 79.9)
		(width 0.15)
		(layer "In2.Cu")
		(net 177)
	)
	(segment
		(start 100.1 78.4)
		(end 99.1 77.4)
		(width 0.15)
		(layer "In2.Cu")
		(net 177)
	)
	(segment
		(start 130.6875 94.8375)
		(end 130.6875 97.3375)
		(width 0.125)
		(layer "In6.Cu")
		(net 177)
	)
	(segment
		(start 131.3325 97.9825)
		(end 137.5675 97.9825)
		(width 0.125)
		(layer "In6.Cu")
		(net 177)
	)
	(segment
		(start 127.95 94.3)
		(end 128.35 94.7)
		(width 0.125)
		(layer "In6.Cu")
		(net 177)
	)
	(segment
		(start 130.55 94.7)
		(end 130.6875 94.8375)
		(width 0.125)
		(layer "In6.Cu")
		(net 177)
	)
	(segment
		(start 127.905913 94.3)
		(end 127.95 94.3)
		(width 0.125)
		(layer "In6.Cu")
		(net 177)
	)
	(segment
		(start 128.35 94.7)
		(end 130.55 94.7)
		(width 0.125)
		(layer "In6.Cu")
		(net 177)
	)
	(segment
		(start 137.5675 97.9825)
		(end 137.58 97.97)
		(width 0.125)
		(layer "In6.Cu")
		(net 177)
	)
	(segment
		(start 130.6875 97.3375)
		(end 131.3325 97.9825)
		(width 0.125)
		(layer "In6.Cu")
		(net 177)
	)
	(segment
		(start 130.294647 93.504647)
		(end 130.294647 93.494647)
		(width 0.15)
		(layer "F.Cu")
		(net 178)
	)
	(segment
		(start 104.4 84.2)
		(end 114.5 84.2)
		(width 0.125)
		(layer "F.Cu")
		(net 178)
	)
	(segment
		(start 97.09 78.3)
		(end 96.69 77.9)
		(width 0.15)
		(layer "F.Cu")
		(net 178)
	)
	(segment
		(start 130.294647 93.494647)
		(end 129.9 93.1)
		(width 0.15)
		(layer "F.Cu")
		(net 178)
	)
	(segment
		(start 114.5 84.2)
		(end 117.4 81.3)
		(width 0.125)
		(layer "F.Cu")
		(net 178)
	)
	(via
		(at 101.555205 86.368698)
		(size 0.45)
		(drill 0.2)
		(layers "F.Cu" "B.Cu")
		(remove_unused_layers yes)
		(keep_end_layers yes)
		(zone_layer_connections)
		(net 178)
	)
	(via
		(at 130.294647 93.504647)
		(size 0.45)
		(drill 0.2)
		(layers "F.Cu" "B.Cu")
		(remove_unused_layers yes)
		(keep_end_layers yes)
		(free yes)
		(zone_layer_connections)
		(net 178)
	)
	(via
		(at 117.4 81.3)
		(size 0.45)
		(drill 0.2)
		(layers "F.Cu" "B.Cu")
		(net 178)
	)
	(via
		(at 96.67 87.39)
		(size 0.45)
		(drill 0.2)
		(layers "F.Cu" "B.Cu")
		(remove_unused_layers yes)
		(keep_end_layers yes)
		(zone_layer_connections)
		(net 178)
	)
	(via
		(at 96.69 77.9)
		(size 0.45)
		(drill 0.2)
		(layers "F.Cu" "B.Cu")
		(remove_unused_layers yes)
		(keep_end_layers yes)
		(zone_layer_connections)
		(net 178)
	)
	(via
		(at 104.4 84.2)
		(size 0.45)
		(drill 0.2)
		(layers "F.Cu" "B.Cu")
		(net 178)
	)
	(segment
		(start 131.5 93.6)
		(end 130.39 93.6)
		(width 0.125)
		(layer "B.Cu")
		(net 178)
	)
	(segment
		(start 96.14 82.25)
		(end 95.69 82.7)
		(width 0.15)
		(layer "B.Cu")
		(net 178)
	)
	(segment
		(start 140.7 93.4)
		(end 140.7 83.7)
		(width 0.125)
		(layer "B.Cu")
		(net 178)
	)
	(segment
		(start 130.39 93.6)
		(end 130.294647 93.504647)
		(width 0.125)
		(layer "B.Cu")
		(net 178)
	)
	(segment
		(start 140.3 93.8)
		(end 140.7 93.4)
		(width 0.125)
		(layer "B.Cu")
		(net 178)
	)
	(segment
		(start 135 78)
		(end 140.7 83.7)
		(width 0.125)
		(layer "B.Cu")
		(net 178)
	)
	(segment
		(start 102.7 84.2)
		(end 104.4 84.2)
		(width 0.125)
		(layer "B.Cu")
		(net 178)
	)
	(segment
		(start 95.69 86.45)
		(end 96.9908 87.7508)
		(width 0.15)
		(layer "B.Cu")
		(net 178)
	)
	(segment
		(start 95.69 82.7)
		(end 95.69 86.45)
		(width 0.15)
		(layer "B.Cu")
		(net 178)
	)
	(segment
		(start 131.7 93.8)
		(end 140.3 93.8)
		(width 0.125)
		(layer "B.Cu")
		(net 178)
	)
	(segment
		(start 117.4 81.4)
		(end 117.4 81.3)
		(width 0.125)
		(layer "B.Cu")
		(net 178)
	)
	(segment
		(start 117.4 81.4)
		(end 120.8 78)
		(width 0.125)
		(layer "B.Cu")
		(net 178)
	)
	(segment
		(start 101.9 85)
		(end 101.9 86.023903)
		(width 0.125)
		(layer "B.Cu")
		(net 178)
	)
	(segment
		(start 131.7 93.8)
		(end 131.5 93.6)
		(width 0.125)
		(layer "B.Cu")
		(net 178)
	)
	(segment
		(start 96.14 78.05)
		(end 96.14 82.25)
		(width 0.15)
		(layer "B.Cu")
		(net 178)
	)
	(segment
		(start 96.29 77.9)
		(end 96.14 78.05)
		(width 0.15)
		(layer "B.Cu")
		(net 178)
	)
	(segment
		(start 101.9 86.023903)
		(end 101.555205 86.368698)
		(width 0.125)
		(layer "B.Cu")
		(net 178)
	)
	(segment
		(start 101.9 85)
		(end 102.7 84.2)
		(width 0.125)
		(layer "B.Cu")
		(net 178)
	)
	(segment
		(start 96.9908 87.7508)
		(end 96.9908 88.2)
		(width 0.15)
		(layer "B.Cu")
		(net 178)
	)
	(segment
		(start 120.8 78)
		(end 135 78)
		(width 0.125)
		(layer "B.Cu")
		(net 178)
	)
	(segment
		(start 96.69 77.9)
		(end 96.29 77.9)
		(width 0.15)
		(layer "B.Cu")
		(net 178)
	)
	(segment
		(start 96.67 87.39)
		(end 100.533903 87.39)
		(width 0.15)
		(layer "In2.Cu")
		(net 178)
	)
	(segment
		(start 100.533903 87.39)
		(end 101.555205 86.368698)
		(width 0.15)
		(layer "In2.Cu")
		(net 178)
	)
	(segment
		(start 129.1 93.1)
		(end 129.5 92.7)
		(width 0.15)
		(layer "F.Cu")
		(net 179)
	)
	(segment
		(start 98.465686 78.4)
		(end 98.1 78.4)
		(width 0.15)
		(layer "F.Cu")
		(net 179)
	)
	(segment
		(start 103.58 80.37)
		(end 103.58 80.12)
		(width 0.15)
		(layer "F.Cu")
		(net 179)
	)
	(segment
		(start 98.09 78.4)
		(end 97.59 77.9)
		(width 0.15)
		(layer "F.Cu")
		(net 179)
	)
	(segment
		(start 98.925686 78.86)
		(end 98.465686 78.4)
		(width 0.15)
		(layer "F.Cu")
		(net 179)
	)
	(segment
		(start 104.12 80.91)
		(end 103.58 80.37)
		(width 0.15)
		(layer "F.Cu")
		(net 179)
	)
	(segment
		(start 103.58 80.12)
		(end 103.39 79.93)
		(width 0.15)
		(layer "F.Cu")
		(net 179)
	)
	(segment
		(start 101.19 79.19)
		(end 100.86 78.86)
		(width 0.15)
		(layer "F.Cu")
		(net 179)
	)
	(segment
		(start 101.78 79.93)
		(end 101.19 79.34)
		(width 0.15)
		(layer "F.Cu")
		(net 179)
	)
	(segment
		(start 103.39 79.93)
		(end 101.78 79.93)
		(width 0.15)
		(layer "F.Cu")
		(net 179)
	)
	(segment
		(start 101.19 79.34)
		(end 101.19 79.19)
		(width 0.15)
		(layer "F.Cu")
		(net 179)
	)
	(segment
		(start 100.86 78.86)
		(end 98.925686 78.86)
		(width 0.15)
		(layer "F.Cu")
		(net 179)
	)
	(via
		(at 104.12 80.91)
		(size 0.45)
		(drill 0.2)
		(layers "F.Cu" "B.Cu")
		(remove_unused_layers yes)
		(keep_end_layers yes)
		(zone_layer_connections)
		(net 179)
	)
	(via
		(at 97.59 77.9)
		(size 0.45)
		(drill 0.2)
		(layers "F.Cu" "B.Cu")
		(remove_unused_layers yes)
		(keep_end_layers yes)
		(zone_layer_connections)
		(net 179)
	)
	(via
		(at 129.5 92.7)
		(size 0.45)
		(drill 0.2)
		(layers "F.Cu" "B.Cu")
		(remove_unused_layers yes)
		(keep_end_layers yes)
		(zone_layer_connections)
		(net 179)
	)
	(segment
		(start 98.322468 79.994625)
		(end 98.322468 79.561382)
		(width 0.15)
		(layer "B.Cu")
		(net 179)
	)
	(segment
		(start 98.09 78.4)
		(end 97.59 77.9)
		(width 0.15)
		(layer "B.Cu")
		(net 179)
	)
	(segment
		(start 120.3 77.6)
		(end 135.2 77.6)
		(width 0.125)
		(layer "B.Cu")
		(net 179)
	)
	(segment
		(start 116.41 80.91)
		(end 104.12 80.91)
		(width 0.15)
		(layer "B.Cu")
		(net 179)
	)
	(segment
		(start 129.1 93.7)
		(end 129.3 93.9)
		(width 0.125)
		(layer "B.Cu")
		(net 179)
	)
	(segment
		(start 129.1 93.1)
		(end 129.1 93.7)
		(width 0.125)
		(layer "B.Cu")
		(net 179)
	)
	(segment
		(start 140.7 94.1)
		(end 141 93.8)
		(width 0.125)
		(layer "B.Cu")
		(net 179)
	)
	(segment
		(start 141 83.4)
		(end 135.2 77.6)
		(width 0.125)
		(layer "B.Cu")
		(net 179)
	)
	(segment
		(start 116.41 80.91)
		(end 116.99 80.91)
		(width 0.125)
		(layer "B.Cu")
		(net 179)
	)
	(segment
		(start 131.6 94.1)
		(end 140.7 94.1)
		(width 0.125)
		(layer "B.Cu")
		(net 179)
	)
	(segment
		(start 131.4 93.9)
		(end 131.6 94.1)
		(width 0.125)
		(layer "B.Cu")
		(net 179)
	)
	(segment
		(start 129.3 93.9)
		(end 131.4 93.9)
		(width 0.125)
		(layer "B.Cu")
		(net 179)
	)
	(segment
		(start 99.9908 88.2)
		(end 99.9908 87.7508)
		(width 0.15)
		(layer "B.Cu")
		(net 179)
	)
	(segment
		(start 99.9908 87.7508)
		(end 99.27 87.03)
		(width 0.15)
		(layer "B.Cu")
		(net 179)
	)
	(segment
		(start 116.99 80.91)
		(end 120.3 77.6)
		(width 0.125)
		(layer "B.Cu")
		(net 179)
	)
	(segment
		(start 129.5 92.7)
		(end 129.1 93.1)
		(width 0.125)
		(layer "B.Cu")
		(net 179)
	)
	(segment
		(start 141 93.8)
		(end 141 83.4)
		(width 0.125)
		(layer "B.Cu")
		(net 179)
	)
	(segment
		(start 98.09 79.328914)
		(end 98.09 78.4)
		(width 0.15)
		(layer "B.Cu")
		(net 179)
	)
	(segment
		(start 98.322468 79.561382)
		(end 98.09 79.328914)
		(width 0.15)
		(layer "B.Cu")
		(net 179)
	)
	(segment
		(start 99.27 87.03)
		(end 99.27 80.942157)
		(width 0.15)
		(layer "B.Cu")
		(net 179)
	)
	(segment
		(start 99.27 80.942157)
		(end 98.322468 79.994625)
		(width 0.15)
		(layer "B.Cu")
		(net 179)
	)
	(segment
		(start 95.09 80.4)
		(end 94.584685 80.905315)
		(width 0.15)
		(layer "F.Cu")
		(net 180)
	)
	(segment
		(start 131.1 91.1)
		(end 130.7 90.7)
		(width 0.182)
		(layer "F.Cu")
		(net 180)
	)
	(segment
		(start 94.584685 80.905315)
		(end 94.584685 81.091564)
		(width 0.15)
		(layer "F.Cu")
		(net 180)
	)
	(via
		(at 131.1 91.1)
		(size 0.45)
		(drill 0.2)
		(layers "F.Cu" "B.Cu")
		(remove_unused_layers yes)
		(keep_end_layers yes)
		(zone_layer_connections)
		(net 180)
	)
	(via
		(at 94.584685 81.091564)
		(size 0.45)
		(drill 0.2)
		(layers "F.Cu" "B.Cu")
		(remove_unused_layers yes)
		(keep_end_layers yes)
		(zone_layer_connections)
		(net 180)
	)
	(via
		(at 102.091146 83.518854)
		(size 0.45)
		(drill 0.2)
		(layers "F.Cu" "B.Cu")
		(remove_unused_layers yes)
		(keep_end_layers yes)
		(zone_layer_connections)
		(net 180)
	)
	(segment
		(start 134.5 79.2)
		(end 139.8 84.5)
		(width 0.125)
		(layer "B.Cu")
		(net 180)
	)
	(segment
		(start 131.5125 91.5125)
		(end 131.5125 92.2125)
		(width 0.125)
		(layer "B.Cu")
		(net 180)
	)
	(segment
		(start 131.5125 92.2125)
		(end 132.2 92.9)
		(width 0.125)
		(layer "B.Cu")
		(net 180)
	)
	(segment
		(start 121.7 79.2)
		(end 134.5 79.2)
		(width 0.125)
		(layer "B.Cu")
		(net 180)
	)
	(segment
		(start 93.69 86.95)
		(end 93.9908 87.2508)
		(width 0.15)
		(layer "B.Cu")
		(net 180)
	)
	(segment
		(start 94.584685 81.205315)
		(end 94.09 81.7)
		(width 0.15)
		(layer "B.Cu")
		(net 180)
	)
	(segment
		(start 132.2 92.9)
		(end 139.4 92.9)
		(width 0.125)
		(layer "B.Cu")
		(net 180)
	)
	(segment
		(start 117.4 83.5)
		(end 121.7 79.2)
		(width 0.125)
		(layer "B.Cu")
		(net 180)
	)
	(segment
		(start 139.8 85.3)
		(end 139.8 92.2)
		(width 0.13)
		(layer "B.Cu")
		(net 180)
	)
	(segment
		(start 94.584685 81.091564)
		(end 94.584685 81.205315)
		(width 0.15)
		(layer "B.Cu")
		(net 180)
	)
	(segment
		(start 93.69 82.7)
		(end 93.69 86.95)
		(width 0.15)
		(layer "B.Cu")
		(net 180)
	)
	(segment
		(start 94.09 81.7)
		(end 94.09 82.3)
		(width 0.15)
		(layer "B.Cu")
		(net 180)
	)
	(segment
		(start 139.8 92.5)
		(end 139.8 85.8)
		(width 0.125)
		(layer "B.Cu")
		(net 180)
	)
	(segment
		(start 94.09 82.3)
		(end 93.69 82.7)
		(width 0.15)
		(layer "B.Cu")
		(net 180)
	)
	(segment
		(start 113.581146 83.518854)
		(end 113.6 83.5)
		(width 0.125)
		(layer "B.Cu")
		(net 180)
	)
	(segment
		(start 139.8 84.5)
		(end 139.8 85.3)
		(width 0.125)
		(layer "B.Cu")
		(net 180)
	)
	(segment
		(start 113.6 83.5)
		(end 117.4 83.5)
		(width 0.125)
		(layer "B.Cu")
		(net 180)
	)
	(segment
		(start 131.1 91.1)
		(end 131.5125 91.5125)
		(width 0.125)
		(layer "B.Cu")
		(net 180)
	)
	(segment
		(start 93.9908 87.2508)
		(end 93.9908 88.2)
		(width 0.15)
		(layer "B.Cu")
		(net 180)
	)
	(segment
		(start 139.4 92.9)
		(end 139.8 92.5)
		(width 0.125)
		(layer "B.Cu")
		(net 180)
	)
	(segment
		(start 102.091146 83.518854)
		(end 113.581146 83.518854)
		(width 0.125)
		(layer "B.Cu")
		(net 180)
	)
	(segment
		(start 101.3 83.5)
		(end 101.655686 83.5)
		(width 0.15)
		(layer "In4.Cu")
		(net 180)
	)
	(segment
		(start 101.67454 83.518854)
		(end 102.091146 83.518854)
		(width 0.15)
		(layer "In4.Cu")
		(net 180)
	)
	(segment
		(start 95.223121 81.73)
		(end 99.98 81.73)
		(width 0.15)
		(layer "In4.Cu")
		(net 180)
	)
	(segment
		(start 94.584685 81.091564)
		(end 95.223121 81.73)
		(width 0.15)
		(layer "In4.Cu")
		(net 180)
	)
	(segment
		(start 100.24 82.44)
		(end 101.3 83.5)
		(width 0.15)
		(layer "In4.Cu")
		(net 180)
	)
	(segment
		(start 100.24 81.99)
		(end 100.24 82.44)
		(width 0.15)
		(layer "In4.Cu")
		(net 180)
	)
	(segment
		(start 99.98 81.73)
		(end 100.24 81.99)
		(width 0.15)
		(layer "In4.Cu")
		(net 180)
	)
	(segment
		(start 101.655686 83.5)
		(end 101.67454 83.518854)
		(width 0.15)
		(layer "In4.Cu")
		(net 180)
	)
	(segment
		(start 130.295386 92.671807)
		(end 129.923579 92.3)
		(width 0.15)
		(layer "F.Cu")
		(net 181)
	)
	(segment
		(start 97.1 77.39)
		(end 97.59 76.9)
		(width 0.15)
		(layer "F.Cu")
		(net 181)
	)
	(via
		(at 97.59 76.9)
		(size 0.45)
		(drill 0.2)
		(layers "F.Cu" "B.Cu")
		(remove_unused_layers yes)
		(keep_end_layers yes)
		(zone_layer_connections)
		(net 181)
	)
	(via
		(at 130.295386 92.671807)
		(size 0.45)
		(drill 0.2)
		(layers "F.Cu" "B.Cu")
		(remove_unused_layers yes)
		(keep_end_layers yes)
		(free yes)
		(zone_layer_connections)
		(net 181)
	)
	(segment
		(start 132.1 93.2)
		(end 139.7 93.2)
		(width 0.125)
		(layer "B.Cu")
		(net 181)
	)
	(segment
		(start 139.7 93.2)
		(end 140.1 92.8)
		(width 0.125)
		(layer "B.Cu")
		(net 181)
	)
	(segment
		(start 96.24 76.7)
		(end 96 76.46)
		(width 0.15)
		(layer "B.Cu")
		(net 181)
	)
	(segment
		(start 97.67 76.9)
		(end 97.59 76.9)
		(width 0.15)
		(layer "B.Cu")
		(net 181)
	)
	(segment
		(start 95.31 76.46)
		(end 95.04 76.73)
		(width 0.15)
		(layer "B.Cu")
		(net 181)
	)
	(segment
		(start 140.1 84.3)
		(end 134.6 78.8)
		(width 0.125)
		(layer "B.Cu")
		(net 181)
	)
	(segment
		(start 101.8 79.108916)
		(end 101.531084 78.84)
		(width 0.125)
		(layer "B.Cu")
		(net 181)
	)
	(segment
		(start 96 76.46)
		(end 95.31 76.46)
		(width 0.15)
		(layer "B.Cu")
		(net 181)
	)
	(segment
		(start 98.36 75.46)
		(end 98.08 75.74)
		(width 0.15)
		(layer "B.Cu")
		(net 181)
	)
	(segment
		(start 97.59 76.9)
		(end 97.39 76.7)
		(width 0.15)
		(layer "B.Cu")
		(net 181)
	)
	(segment
		(start 94.69 86.45)
		(end 95.4908 87.2508)
		(width 0.15)
		(layer "B.Cu")
		(net 181)
	)
	(segment
		(start 100.33 78.84)
		(end 100.07 78.58)
		(width 0.15)
		(layer "B.Cu")
		(net 181)
	)
	(segment
		(start 95.39 82)
		(end 94.69 82.7)
		(width 0.15)
		(layer "B.Cu")
		(net 181)
	)
	(segment
		(start 103.9 83.1)
		(end 103.2 83.1)
		(width 0.125)
		(layer "B.Cu")
		(net 181)
	)
	(segment
		(start 94.19 77.54)
		(end 94.19 80.055686)
		(width 0.15)
		(layer "B.Cu")
		(net 181)
	)
	(segment
		(start 132 93.1)
		(end 132.1 93.2)
		(width 0.13)
		(layer "B.Cu")
		(net 181)
	)
	(segment
		(start 130.371807 92.671807)
		(end 130.8 93.1)
		(width 0.13)
		(layer "B.Cu")
		(net 181)
	)
	(segment
		(start 94.19 80.055686)
		(end 94.434314 80.3)
		(width 0.15)
		(layer "B.Cu")
		(net 181)
	)
	(segment
		(start 101.531084 78.84)
		(end 100.33 78.84)
		(width 0.15)
		(layer "B.Cu")
		(net 181)
	)
	(segment
		(start 130.295386 92.671807)
		(end 130.371807 92.671807)
		(width 0.13)
		(layer "B.Cu")
		(net 181)
	)
	(segment
		(start 95.39 80.82)
		(end 95.39 82)
		(width 0.15)
		(layer "B.Cu")
		(net 181)
	)
	(segment
		(start 104.37 82.63)
		(end 103.9 83.1)
		(width 0.125)
		(layer "B.Cu")
		(net 181)
	)
	(segment
		(start 102.88 80.84)
		(end 101.8 79.76)
		(width 0.125)
		(layer "B.Cu")
		(net 181)
	)
	(segment
		(start 100.07 78.58)
		(end 100.07 77.79)
		(width 0.15)
		(layer "B.Cu")
		(net 181)
	)
	(segment
		(start 94.41 77.32)
		(end 94.19 77.54)
		(width 0.15)
		(layer "B.Cu")
		(net 181)
	)
	(segment
		(start 140.1 84.8)
		(end 140.1 91.8)
		(width 0.13)
		(layer "B.Cu")
		(net 181)
	)
	(segment
		(start 102.88 82.78)
		(end 102.88 80.84)
		(width 0.125)
		(layer "B.Cu")
		(net 181)
	)
	(segment
		(start 101.8 79.76)
		(end 101.8 79.108916)
		(width 0.125)
		(layer "B.Cu")
		(net 181)
	)
	(segment
		(start 98.99 75.74)
		(end 98.99 75.734314)
		(width 0.15)
		(layer "B.Cu")
		(net 181)
	)
	(segment
		(start 94.83 77.32)
		(end 94.41 77.32)
		(width 0.15)
		(layer "B.Cu")
		(net 181)
	)
	(segment
		(start 100.07 77.79)
		(end 99.75 77.47)
		(width 0.15)
		(layer "B.Cu")
		(net 181)
	)
	(segment
		(start 98.715686 75.46)
		(end 98.36 75.46)
		(width 0.15)
		(layer "B.Cu")
		(net 181)
	)
	(segment
		(start 140.1 92.8)
		(end 140.1 86.1)
		(width 0.125)
		(layer "B.Cu")
		(net 181)
	)
	(segment
		(start 98.08 76.49)
		(end 97.67 76.9)
		(width 0.15)
		(layer "B.Cu")
		(net 181)
	)
	(segment
		(start 95.4908 87.2508)
		(end 95.4908 88.2)
		(width 0.15)
		(layer "B.Cu")
		(net 181)
	)
	(segment
		(start 98.99 75.734314)
		(end 98.715686 75.46)
		(width 0.15)
		(layer "B.Cu")
		(net 181)
	)
	(segment
		(start 103.2 83.1)
		(end 102.88 82.78)
		(width 0.125)
		(layer "B.Cu")
		(net 181)
	)
	(segment
		(start 134.6 78.8)
		(end 121.425 78.8)
		(width 0.125)
		(layer "B.Cu")
		(net 181)
	)
	(segment
		(start 131.7 93.1)
		(end 132 93.1)
		(width 0.13)
		(layer "B.Cu")
		(net 181)
	)
	(segment
		(start 140.1 84.8)
		(end 140.1 84.3)
		(width 0.125)
		(layer "B.Cu")
		(net 181)
	)
	(segment
		(start 99.75 76.5)
		(end 98.99 75.74)
		(width 0.15)
		(layer "B.Cu")
		(net 181)
	)
	(segment
		(start 121.425 78.8)
		(end 117.595 82.63)
		(width 0.125)
		(layer "B.Cu")
		(net 181)
	)
	(segment
		(start 131.6 93.1)
		(end 131.7 93.1)
		(width 0.13)
		(layer "B.Cu")
		(net 181)
	)
	(segment
		(start 131.7 93.1)
		(end 130.8 93.1)
		(width 0.13)
		(layer "B.Cu")
		(net 181)
	)
	(segment
		(start 99.75 77.47)
		(end 99.75 76.5)
		(width 0.15)
		(layer "B.Cu")
		(net 181)
	)
	(segment
		(start 94.69 82.7)
		(end 94.69 86.45)
		(width 0.15)
		(layer "B.Cu")
		(net 181)
	)
	(segment
		(start 95.04 76.73)
		(end 95.04 77.11)
		(width 0.15)
		(layer "B.Cu")
		(net 181)
	)
	(segment
		(start 94.434314 80.3)
		(end 94.87 80.3)
		(width 0.15)
		(layer "B.Cu")
		(net 181)
	)
	(segment
		(start 97.39 76.7)
		(end 96.24 76.7)
		(width 0.15)
		(layer "B.Cu")
		(net 181)
	)
	(segment
		(start 117.595 82.63)
		(end 104.37 82.63)
		(width 0.125)
		(layer "B.Cu")
		(net 181)
	)
	(segment
		(start 98.08 75.74)
		(end 98.08 76.49)
		(width 0.15)
		(layer "B.Cu")
		(net 181)
	)
	(segment
		(start 94.87 80.3)
		(end 95.39 80.82)
		(width 0.15)
		(layer "B.Cu")
		(net 181)
	)
	(segment
		(start 131.6 93.1)
		(end 130.8 93.1)
		(width 0.125)
		(layer "B.Cu")
		(net 181)
	)
	(segment
		(start 95.04 77.11)
		(end 94.83 77.32)
		(width 0.15)
		(layer "B.Cu")
		(net 181)
	)
	(segment
		(start 128.3 90.7)
		(end 128.7 91.1)
		(width 0.182)
		(layer "F.Cu")
		(net 182)
	)
	(segment
		(start 98.1 77.41)
		(end 98.59 77.9)
		(width 0.15)
		(layer "F.Cu")
		(net 182)
	)
	(via
		(at 98.59 77.9)
		(size 0.45)
		(drill 0.2)
		(layers "F.Cu" "B.Cu")
		(remove_unused_layers yes)
		(keep_end_layers yes)
		(zone_layer_connections)
		(net 182)
	)
	(via
		(at 128.7 91.1)
		(size 0.45)
		(drill 0.2)
		(layers "F.Cu" "B.Cu")
		(remove_unused_layers yes)
		(keep_end_layers yes)
		(zone_layer_connections)
		(net 182)
	)
	(segment
		(start 100.44 87.1492)
		(end 101.4908 88.2)
		(width 0.15)
		(layer "B.Cu")
		(net 182)
	)
	(segment
		(start 99.19 80.09)
		(end 100.44 81.34)
		(width 0.15)
		(layer "B.Cu")
		(net 182)
	)
	(segment
		(start 98.59 77.9)
		(end 99.19 78.5)
		(width 0.15)
		(layer "B.Cu")
		(net 182)
	)
	(segment
		(start 100.44 81.34)
		(end 100.44 87.1492)
		(width 0.15)
		(layer "B.Cu")
		(net 182)
	)
	(segment
		(start 99.19 78.5)
		(end 99.19 80.09)
		(width 0.15)
		(layer "B.Cu")
		(net 182)
	)
	(segment
		(start 112.51 75.71)
		(end 112.51 88.99)
		(width 0.15)
		(layer "In4.Cu")
		(net 182)
	)
	(segment
		(start 112.51 88.99)
		(end 117.42 93.9)
		(width 0.15)
		(layer "In4.Cu")
		(net 182)
	)
	(segment
		(start 129.9 90.5)
		(end 129.7 90.7)
		(width 0.15)
		(layer "In4.Cu")
		(net 182)
	)
	(segment
		(start 108.04 75.51)
		(end 108.73 74.82)
		(width 0.15)
		(layer "In4.Cu")
		(net 182)
	)
	(segment
		(start 100.08 77.9)
		(end 101.825 79.645)
		(width 0.15)
		(layer "In4.Cu")
		(net 182)
	)
	(segment
		(start 130.1 89.9)
		(end 129.9 90.1)
		(width 0.15)
		(layer "In4.Cu")
		(net 182)
	)
	(segment
		(start 101.825 79.645)
		(end 106.695 79.645)
		(width 0.15)
		(layer "In4.Cu")
		(net 182)
	)
	(segment
		(start 130.5 89.9)
		(end 130.1 89.9)
		(width 0.15)
		(layer "In4.Cu")
		(net 182)
	)
	(segment
		(start 108.73 74.82)
		(end 111.62 74.82)
		(width 0.15)
		(layer "In4.Cu")
		(net 182)
	)
	(segment
		(start 129.7 90.7)
		(end 129.3 90.7)
		(width 0.15)
		(layer "In4.Cu")
		(net 182)
	)
	(segment
		(start 108.04 78.3)
		(end 108.04 75.51)
		(width 0.15)
		(layer "In4.Cu")
		(net 182)
	)
	(segment
		(start 111.62 74.82)
		(end 112.51 75.71)
		(width 0.15)
		(layer "In4.Cu")
		(net 182)
	)
	(segment
		(start 129.9 90.1)
		(end 129.9 90.5)
		(width 0.15)
		(layer "In4.Cu")
		(net 182)
	)
	(segment
		(start 130.7 90.1)
		(end 130.5 89.9)
		(width 0.15)
		(layer "In4.Cu")
		(net 182)
	)
	(segment
		(start 106.695 79.645)
		(end 108.04 78.3)
		(width 0.15)
		(layer "In4.Cu")
		(net 182)
	)
	(segment
		(start 130.7 93.7)
		(end 130.7 90.1)
		(width 0.15)
		(layer "In4.Cu")
		(net 182)
	)
	(segment
		(start 129.3 90.7)
		(end 128.9 91.1)
		(width 0.15)
		(layer "In4.Cu")
		(net 182)
	)
	(segment
		(start 128.9 91.1)
		(end 128.7 91.1)
		(width 0.15)
		(layer "In4.Cu")
		(net 182)
	)
	(segment
		(start 98.59 77.9)
		(end 100.08 77.9)
		(width 0.15)
		(layer "In4.Cu")
		(net 182)
	)
	(segment
		(start 130.5 93.9)
		(end 130.7 93.7)
		(width 0.15)
		(layer "In4.Cu")
		(net 182)
	)
	(segment
		(start 117.42 93.9)
		(end 130.5 93.9)
		(width 0.15)
		(layer "In4.Cu")
		(net 182)
	)
	(segment
		(start 105.58 69.28)
		(end 105.3 69)
		(width 0.15)
		(layer "F.Cu")
		(net 183)
	)
	(segment
		(start 105.58 69.85)
		(end 105.58 69.28)
		(width 0.15)
		(layer "F.Cu")
		(net 183)
	)
	(segment
		(start 95.86 69.247151)
		(end 95.9695 69.137651)
		(width 0.15)
		(layer "F.Cu")
		(net 183)
	)
	(segment
		(start 130.3 91.9)
		(end 130.7 91.5)
		(width 0.15)
		(layer "F.Cu")
		(net 183)
	)
	(segment
		(start 95.65 73.22)
		(end 95.86 73.01)
		(width 0.15)
		(layer "F.Cu")
		(net 183)
	)
	(segment
		(start 105.3 69)
		(end 104.98 69)
		(width 0.15)
		(layer "F.Cu")
		(net 183)
	)
	(segment
		(start 95.86 73.01)
		(end 95.86 69.247151)
		(width 0.15)
		(layer "F.Cu")
		(net 183)
	)
	(segment
		(start 96.1 75.4)
		(end 95.65 74.95)
		(width 0.15)
		(layer "F.Cu")
		(net 183)
	)
	(segment
		(start 95.65 74.95)
		(end 95.65 73.22)
		(width 0.15)
		(layer "F.Cu")
		(net 183)
	)
	(via
		(at 104.98 69)
		(size 0.45)
		(drill 0.2)
		(layers "F.Cu" "B.Cu")
		(remove_unused_layers yes)
		(keep_end_layers yes)
		(zone_layer_connections)
		(net 183)
	)
	(via
		(at 139.8 79.6)
		(size 0.45)
		(drill 0.2)
		(layers "F.Cu" "B.Cu")
		(remove_unused_layers yes)
		(keep_end_layers yes)
		(zone_layer_connections)
		(net 183)
	)
	(via
		(at 130.3 91.9)
		(size 0.45)
		(drill 0.2)
		(layers "F.Cu" "B.Cu")
		(remove_unused_layers yes)
		(keep_end_layers yes)
		(free yes)
		(zone_layer_connections)
		(net 183)
	)
	(via
		(at 95.9695 69.137651)
		(size 0.45)
		(drill 0.2)
		(layers "F.Cu" "B.Cu")
		(remove_unused_layers yes)
		(keep_end_layers yes)
		(zone_layer_connections)
		(net 183)
	)
	(segment
		(start 107.53 71.54)
		(end 103.88 67.89)
		(width 0.15)
		(layer "B.Cu")
		(net 183)
	)
	(segment
		(start 107.53 78.59)
		(end 107.53 71.54)
		(width 0.15)
		(layer "B.Cu")
		(net 183)
	)
	(segment
		(start 119.655 76.75)
		(end 116.675 79.73)
		(width 0.15)
		(layer "B.Cu")
		(net 183)
	)
	(segment
		(start 138.4 79.6)
		(end 139.8 79.6)
		(width 0.125)
		(layer "B.Cu")
		(net 183)
	)
	(segment
		(start 116.675 79.73)
		(end 108.67 79.73)
		(width 0.15)
		(layer "B.Cu")
		(net 183)
	)
	(segment
		(start 108.67 79.73)
		(end 107.53 78.59)
		(width 0.15)
		(layer "B.Cu")
		(net 183)
	)
	(segment
		(start 134.05 76.75)
		(end 119.655 76.75)
		(width 0.15)
		(layer "B.Cu")
		(net 183)
	)
	(segment
		(start 97.217151 67.89)
		(end 95.9695 69.137651)
		(width 0.15)
		(layer "B.Cu")
		(net 183)
	)
	(segment
		(start 135.55 76.75)
		(end 138.4 79.6)
		(width 0.125)
		(layer "B.Cu")
		(net 183)
	)
	(segment
		(start 134.05 76.75)
		(end 135.55 76.75)
		(width 0.125)
		(layer "B.Cu")
		(net 183)
	)
	(segment
		(start 103.88 67.89)
		(end 97.217151 67.89)
		(width 0.15)
		(layer "B.Cu")
		(net 183)
	)
	(segment
		(start 139.8 79.9)
		(end 133.8 85.9)
		(width 0.125)
		(layer "In2.Cu")
		(net 183)
	)
	(segment
		(start 130.9 87.5)
		(end 130.7 87.7)
		(width 0.125)
		(layer "In2.Cu")
		(net 183)
	)
	(segment
		(start 131.5 86.1)
		(end 131.5 87.3)
		(width 0.125)
		(layer "In2.Cu")
		(net 183)
	)
	(segment
		(start 131.7 85.9)
		(end 131.5 86.1)
		(width 0.125)
		(layer "In2.Cu")
		(net 183)
	)
	(segment
		(start 139.8 79.6)
		(end 139.8 79.9)
		(width 0.125)
		(layer "In2.Cu")
		(net 183)
	)
	(segment
		(start 130.7 87.7)
		(end 130.7 91.5)
		(width 0.125)
		(layer "In2.Cu")
		(net 183)
	)
	(segment
		(start 131.5 87.3)
		(end 131.3 87.5)
		(width 0.125)
		(layer "In2.Cu")
		(net 183)
	)
	(segment
		(start 133.8 85.9)
		(end 131.7 85.9)
		(width 0.125)
		(layer "In2.Cu")
		(net 183)
	)
	(segment
		(start 131.3 87.5)
		(end 130.9 87.5)
		(width 0.125)
		(layer "In2.Cu")
		(net 183)
	)
	(segment
		(start 130.7 91.5)
		(end 130.3 91.9)
		(width 0.125)
		(layer "In2.Cu")
		(net 183)
	)
	(segment
		(start 130.29351 91.1)
		(end 130.29351 91.129413)
		(width 0.15)
		(layer "F.Cu")
		(net 184)
	)
	(segment
		(start 106.8385 86.2915)
		(end 104.43 88.7)
		(width 0.15)
		(layer "F.Cu")
		(net 184)
	)
	(segment
		(start 103.33 88.7)
		(end 100.92 91.11)
		(width 0.15)
		(layer "F.Cu")
		(net 184)
	)
	(segment
		(start 89.38 102.8)
		(end 89.38 103.82)
		(width 0.15)
		(layer "F.Cu")
		(net 184)
	)
	(segment
		(start 100.92 98.9395)
		(end 100.38 99.4795)
		(width 0.15)
		(layer "F.Cu")
		(net 184)
	)
	(segment
		(start 130.29351 91.129413)
		(end 129.922923 91.5)
		(width 0.15)
		(layer "F.Cu")
		(net 184)
	)
	(segment
		(start 104.43 88.7)
		(end 103.33 88.7)
		(width 0.15)
		(layer "F.Cu")
		(net 184)
	)
	(segment
		(start 100.92 91.11)
		(end 100.92 98.9395)
		(width 0.15)
		(layer "F.Cu")
		(net 184)
	)
	(segment
		(start 106.8385 85.45)
		(end 106.8385 86.2915)
		(width 0.15)
		(layer "F.Cu")
		(net 184)
	)
	(via
		(at 106.8385 85.45)
		(size 0.45)
		(drill 0.2)
		(layers "F.Cu" "B.Cu")
		(remove_unused_layers yes)
		(keep_end_layers yes)
		(zone_layer_connections)
		(net 184)
	)
	(via
		(at 130.29351 91.1)
		(size 0.45)
		(drill 0.2)
		(layers "F.Cu" "B.Cu")
		(remove_unused_layers yes)
		(keep_end_layers yes)
		(free yes)
		(zone_layer_connections)
		(net 184)
	)
	(via
		(at 100.38 99.4795)
		(size 0.45)
		(drill 0.2)
		(layers "F.Cu" "B.Cu")
		(remove_unused_layers yes)
		(keep_end_layers yes)
		(zone_layer_connections)
		(net 184)
	)
	(via
		(at 89.38 102.8)
		(size 0.45)
		(drill 0.2)
		(layers "F.Cu" "B.Cu")
		(remove_unused_layers yes)
		(keep_end_layers yes)
		(zone_layer_connections)
		(net 184)
	)
	(segment
		(start 130.29351 91.1)
		(end 130.69351 90.7)
		(width 0.125)
		(layer "B.Cu")
		(net 184)
	)
	(segment
		(start 122.2 80)
		(end 117.5 84.7)
		(width 0.125)
		(layer "B.Cu")
		(net 184)
	)
	(segment
		(start 139.5 92.2)
		(end 139.5 85.5)
		(width 0.125)
		(layer "B.Cu")
		(net 184)
	)
	(segment
		(start 132.6 92.6)
		(end 139.1 92.6)
		(width 0.125)
		(layer "B.Cu")
		(net 184)
	)
	(segment
		(start 132.1 90.7)
		(end 132.3 90.9)
		(width 0.125)
		(layer "B.Cu")
		(net 184)
	)
	(segment
		(start 117.5 84.7)
		(end 107.5885 84.7)
		(width 0.125)
		(layer "B.Cu")
		(net 184)
	)
	(segment
		(start 130.69351 90.7)
		(end 132.1 90.7)
		(width 0.125)
		(layer "B.Cu")
		(net 184)
	)
	(segment
		(start 132.3 90.9)
		(end 132.3 92.3)
		(width 0.125)
		(layer "B.Cu")
		(net 184)
	)
	(segment
		(start 139.5 85.5)
		(end 134 80)
		(width 0.125)
		(layer "B.Cu")
		(net 184)
	)
	(segment
		(start 100.38 99.4795)
		(end 92.7005 99.4795)
		(width 0.15)
		(layer "B.Cu")
		(net 184)
	)
	(segment
		(start 139.1 92.6)
		(end 139.5 92.2)
		(width 0.125)
		(layer "B.Cu")
		(net 184)
	)
	(segment
		(start 92.7005 99.4795)
		(end 89.38 102.8)
		(width 0.15)
		(layer "B.Cu")
		(net 184)
	)
	(segment
		(start 107.5885 84.7)
		(end 106.8385 85.45)
		(width 0.125)
		(layer "B.Cu")
		(net 184)
	)
	(segment
		(start 132.3 92.3)
		(end 132.6 92.6)
		(width 0.125)
		(layer "B.Cu")
		(net 184)
	)
	(segment
		(start 134 80)
		(end 122.2 80)
		(width 0.125)
		(layer "B.Cu")
		(net 184)
	)
	(segment
		(start 128.3 91.5)
		(end 127.9 91.1)
		(width 0.15)
		(layer "F.Cu")
		(net 185)
	)
	(segment
		(start 92.09 81.4)
		(end 91.59 80.9)
		(width 0.15)
		(layer "F.Cu")
		(net 185)
	)
	(via
		(at 91.59 80.9)
		(size 0.45)
		(drill 0.2)
		(layers "F.Cu" "B.Cu")
		(remove_unused_layers yes)
		(keep_end_layers yes)
		(zone_layer_connections)
		(net 185)
	)
	(via
		(at 127.9 91.1)
		(size 0.45)
		(drill 0.2)
		(layers "F.Cu" "B.Cu")
		(remove_unused_layers yes)
		(keep_end_layers yes)
		(free yes)
		(zone_layer_connections)
		(net 185)
	)
	(via
		(at 122.3045 85.5)
		(size 0.45)
		(drill 0.2)
		(layers "F.Cu" "B.Cu")
		(net 185)
	)
	(via
		(at 101.439207 84.900793)
		(size 0.45)
		(drill 0.2)
		(layers "F.Cu" "B.Cu")
		(remove_unused_layers yes)
		(keep_end_layers yes)
		(zone_layer_connections)
		(net 185)
	)
	(segment
		(start 107.8875 85.1125)
		(end 121.917 85.1125)
		(width 0.125)
		(layer "B.Cu")
		(net 185)
	)
	(segment
		(start 91.6 80.91)
		(end 91.6 85.04)
		(width 0.15)
		(layer "B.Cu")
		(net 185)
	)
	(segment
		(start 106.2 86.8)
		(end 107.8875 85.1125)
		(width 0.125)
		(layer "B.Cu")
		(net 185)
	)
	(segment
		(start 101.4 86.8)
		(end 106.2 86.8)
		(width 0.125)
		(layer "B.Cu")
		(net 185)
	)
	(segment
		(start 101.1275 85.2125)
		(end 101.1275 86.5275)
		(width 0.125)
		(layer "B.Cu")
		(net 185)
	)
	(segment
		(start 101.439207 84.900793)
		(end 101.1275 85.2125)
		(width 0.125)
		(layer "B.Cu")
		(net 185)
	)
	(segment
		(start 101.1275 86.5275)
		(end 101.4 86.8)
		(width 0.125)
		(layer "B.Cu")
		(net 185)
	)
	(segment
		(start 121.917 85.1125)
		(end 122.3045 85.5)
		(width 0.125)
		(layer "B.Cu")
		(net 185)
	)
	(segment
		(start 90.9908 85.6492)
		(end 90.9908 88.2)
		(width 0.15)
		(layer "B.Cu")
		(net 185)
	)
	(segment
		(start 91.6 85.04)
		(end 90.9908 85.6492)
		(width 0.15)
		(layer "B.Cu")
		(net 185)
	)
	(segment
		(start 91.59 80.9)
		(end 91.6 80.91)
		(width 0.15)
		(layer "B.Cu")
		(net 185)
	)
	(segment
		(start 122.7 88.1)
		(end 122.7 85.7)
		(width 0.125)
		(layer "In2.Cu")
		(net 185)
	)
	(segment
		(start 122.7 85.7)
		(end 122.5 85.5)
		(width 0.125)
		(layer "In2.Cu")
		(net 185)
	)
	(segment
		(start 128.3 90.7)
		(end 128.9 90.7)
		(width 0.125)
		(layer "In2.Cu")
		(net 185)
	)
	(segment
		(start 122.5 85.5)
		(end 122.3 85.5)
		(width 0.125)
		(layer "In2.Cu")
		(net 185)
	)
	(segment
		(start 127.9 91.1)
		(end 128.3 90.7)
		(width 0.125)
		(layer "In2.Cu")
		(net 185)
	)
	(segment
		(start 122.3 85.5)
		(end 122.3045 85.5)
		(width 0.125)
		(layer "In2.Cu")
		(net 185)
	)
	(segment
		(start 122.8625 88.2625)
		(end 123.4625 88.2625)
		(width 0.125)
		(layer "In2.Cu")
		(net 185)
	)
	(segment
		(start 128.9 90.7)
		(end 129.1 90.5)
		(width 0.125)
		(layer "In2.Cu")
		(net 185)
	)
	(segment
		(start 129.1 90.5)
		(end 129.1 88.3)
		(width 0.125)
		(layer "In2.Cu")
		(net 185)
	)
	(segment
		(start 123.4625 88.2625)
		(end 123.5 88.3)
		(width 0.125)
		(layer "In2.Cu")
		(net 185)
	)
	(segment
		(start 122.8625 88.2625)
		(end 122.7 88.1)
		(width 0.125)
		(layer "In2.Cu")
		(net 185)
	)
	(segment
		(start 129.1 88.3)
		(end 123.5 88.3)
		(width 0.125)
		(layer "In2.Cu")
		(net 185)
	)
	(segment
		(start 95.95 83.07)
		(end 92.65 83.07)
		(width 0.15)
		(layer "In4.Cu")
		(net 185)
	)
	(segment
		(start 96.35 83.47)
		(end 95.95 83.07)
		(width 0.15)
		(layer "In4.Cu")
		(net 185)
	)
	(segment
		(start 99.89 84.32)
		(end 98.57 83)
		(width 0.15)
		(layer "In4.Cu")
		(net 185)
	)
	(segment
		(start 91.59 82.01)
		(end 91.59 80.9)
		(width 0.13)
		(layer "In4.Cu")
		(net 185)
	)
	(segment
		(start 98.57 83)
		(end 97.85 83)
		(width 0.15)
		(layer "In4.Cu")
		(net 185)
	)
	(segment
		(start 97.38 83.47)
		(end 96.35 83.47)
		(width 0.15)
		(layer "In4.Cu")
		(net 185)
	)
	(segment
		(start 100.858414 84.32)
		(end 99.89 84.32)
		(width 0.15)
		(layer "In4.Cu")
		(net 185)
	)
	(segment
		(start 97.85 83)
		(end 97.38 83.47)
		(width 0.15)
		(layer "In4.Cu")
		(net 185)
	)
	(segment
		(start 101.439207 84.900793)
		(end 100.858414 84.32)
		(width 0.15)
		(layer "In4.Cu")
		(net 185)
	)
	(segment
		(start 92.65 83.07)
		(end 91.59 82.01)
		(width 0.13)
		(layer "In4.Cu")
		(net 185)
	)
	(segment
		(start 115.48 91.76)
		(end 119.93 91.76)
		(width 0.15)
		(layer "F.Cu")
		(net 186)
	)
	(segment
		(start 120.07 91.9)
		(end 120.7 91.9)
		(width 0.15)
		(layer "F.Cu")
		(net 186)
	)
	(segment
		(start 119.93 91.76)
		(end 120.07 91.9)
		(width 0.15)
		(layer "F.Cu")
		(net 186)
	)
	(segment
		(start 120.7 91.9)
		(end 121.1 91.5)
		(width 0.15)
		(layer "F.Cu")
		(net 186)
	)
	(segment
		(start 114.24 90.52)
		(end 115.48 91.76)
		(width 0.15)
		(layer "F.Cu")
		(net 186)
	)
	(segment
		(start 132.325 89.925)
		(end 132.7 90.3)
		(width 0.2)
		(layer "F.Cu")
		(net 187)
	)
	(segment
		(start 99.69 81.91)
		(end 100.364264 81.91)
		(width 0.2)
		(layer "F.Cu")
		(net 187)
	)
	(segment
		(start 100.662132 82.207868)
		(end 101.612132 82.207868)
		(width 0.2)
		(layer "F.Cu")
		(net 187)
	)
	(segment
		(start 101.612132 82.207868)
		(end 101.83 81.99)
		(width 0.2)
		(layer "F.Cu")
		(net 187)
	)
	(segment
		(start 99.18 81.4)
		(end 99.69 81.91)
		(width 0.2)
		(layer "F.Cu")
		(net 187)
	)
	(segment
		(start 100.364264 81.91)
		(end 100.662132 82.207868)
		(width 0.2)
		(layer "F.Cu")
		(net 187)
	)
	(via
		(at 132.7 90.3)
		(size 0.45)
		(drill 0.2)
		(layers "F.Cu" "B.Cu")
		(remove_unused_layers yes)
		(keep_end_layers yes)
		(zone_layer_connections)
		(net 187)
	)
	(via
		(at 101.83 81.99)
		(size 0.45)
		(drill 0.2)
		(layers "F.Cu" "B.Cu")
		(remove_unused_layers yes)
		(keep_end_layers yes)
		(zone_layer_connections)
		(net 187)
	)
	(segment
		(start 106.045383 82.53451)
		(end 106.045384 82.534509)
		(width 0.13)
		(layer "In4.Cu")
		(net 187)
	)
	(segment
		(start 132.55 96.4)
		(end 133.646146 95.303854)
		(width 0.13)
		(layer "In4.Cu")
		(net 187)
	)
	(segment
		(start 105.161502 82.004183)
		(end 105.161502 82.004182)
		(width 0.13)
		(layer "In4.Cu")
		(net 187)
	)
	(segment
		(start 133.6 91.109871)
		(end 133.6 90.85)
		(width 0.13)
		(layer "In4.Cu")
		(net 187)
	)
	(segment
		(start 106.079894 84.479895)
		(end 106.079894 84.479896)
		(width 0.13)
		(layer "In4.Cu")
		(net 187)
	)
	(segment
		(start 103.639536 84.091831)
		(end 103.639535 84.091831)
		(width 0.13)
		(layer "In4.Cu")
		(net 187)
	)
	(segment
		(start 104.524262 82.924262)
		(end 103.639535 83.808988)
		(width 0.13)
		(layer "In4.Cu")
		(net 187)
	)
	(segment
		(start 106.045384 82.534509)
		(end 105.089945 83.489945)
		(width 0.13)
		(layer "In4.Cu")
		(net 187)
	)
	(segment
		(start 105.053747 85.223201)
		(end 105.797051 84.479896)
		(width 0.13)
		(layer "In4.Cu")
		(net 187)
	)
	(segment
		(start 106.611069 83.100194)
		(end 105.65563 84.05563)
		(width 0.13)
		(layer "In4.Cu")
		(net 187)
	)
	(segment
		(start 103.59 81.99)
		(end 104.1 82.5)
		(width 0.13)
		(layer "In4.Cu")
		(net 187)
	)
	(segment
		(start 105.089945 83.489945)
		(end 105.089947 83.489947)
		(width 0.13)
		(layer "In4.Cu")
		(net 187)
	)
	(segment
		(start 103.922377 84.091831)
		(end 105.76254 82.251665)
		(width 0.13)
		(layer "In4.Cu")
		(net 187)
	)
	(segment
		(start 106.415 84.815)
		(end 106.415 86.065)
		(width 0.13)
		(layer "In4.Cu")
		(net 187)
	)
	(segment
		(start 106.079894 84.479896)
		(end 106.415 84.815)
		(width 0.13)
		(layer "In4.Cu")
		(net 187)
	)
	(segment
		(start 133.05 90.3)
		(end 132.7 90.3)
		(width 0.13)
		(layer "In4.Cu")
		(net 187)
	)
	(segment
		(start 105.053748 85.2232)
		(end 105.053747 85.223201)
		(width 0.13)
		(layer "In4.Cu")
		(net 187)
	)
	(segment
		(start 133.9 91.409871)
		(end 133.6 91.109871)
		(width 0.13)
		(layer "In4.Cu")
		(net 187)
	)
	(segment
		(start 105.655632 84.055632)
		(end 104.770905 84.940358)
		(width 0.13)
		(layer "In4.Cu")
		(net 187)
	)
	(segment
		(start 105.161502 82.287024)
		(end 104.524264 82.924263)
		(width 0.13)
		(layer "In4.Cu")
		(net 187)
	)
	(segment
		(start 103.922378 84.09183)
		(end 103.922377 84.091831)
		(width 0.13)
		(layer "In4.Cu")
		(net 187)
	)
	(segment
		(start 105.124458 84.021119)
		(end 106.328225 82.81735)
		(width 0.13)
		(layer "In4.Cu")
		(net 187)
	)
	(segment
		(start 104.770906 85.223201)
		(end 104.770905 85.223201)
		(width 0.13)
		(layer "In4.Cu")
		(net 187)
	)
	(segment
		(start 105.089947 83.489947)
		(end 104.841616 83.738277)
		(width 0.13)
		(layer "In4.Cu")
		(net 187)
	)
	(segment
		(start 127.2 97)
		(end 130.860027 97)
		(width 0.13)
		(layer "In4.Cu")
		(net 187)
	)
	(segment
		(start 133.6 90.85)
		(end 133.05 90.3)
		(width 0.13)
		(layer "In4.Cu")
		(net 187)
	)
	(segment
		(start 104.382843 82.499999)
		(end 104.382842 82.5)
		(width 0.13)
		(layer "In4.Cu")
		(net 187)
	)
	(segment
		(start 117.895 97.545)
		(end 126.655 97.545)
		(width 0.13)
		(layer "In4.Cu")
		(net 187)
	)
	(segment
		(start 106.611068 83.100195)
		(end 106.611069 83.100194)
		(width 0.13)
		(layer "In4.Cu")
		(net 187)
	)
	(segment
		(start 104.382842 82.5)
		(end 104.87866 82.004183)
		(width 0.13)
		(layer "In4.Cu")
		(net 187)
	)
	(segment
		(start 105.65563 84.05563)
		(end 105.655632 84.055632)
		(width 0.13)
		(layer "In4.Cu")
		(net 187)
	)
	(segment
		(start 105.124459 84.021118)
		(end 105.124458 84.021119)
		(width 0.13)
		(layer "In4.Cu")
		(net 187)
	)
	(segment
		(start 133.646146 95.303854)
		(end 133.646146 94.551673)
		(width 0.13)
		(layer "In4.Cu")
		(net 187)
	)
	(segment
		(start 104.524264 82.924263)
		(end 104.524262 82.924262)
		(width 0.13)
		(layer "In4.Cu")
		(net 187)
	)
	(segment
		(start 130.860027 97)
		(end 131.460027 96.4)
		(width 0.13)
		(layer "In4.Cu")
		(net 187)
	)
	(segment
		(start 133.646146 94.551673)
		(end 133.9 94.297819)
		(width 0.13)
		(layer "In4.Cu")
		(net 187)
	)
	(segment
		(start 106.415 86.065)
		(end 117.895 97.545)
		(width 0.13)
		(layer "In4.Cu")
		(net 187)
	)
	(segment
		(start 104.841617 84.02112)
		(end 104.841616 84.021119)
		(width 0.13)
		(layer "In4.Cu")
		(net 187)
	)
	(segment
		(start 106.61107 82.817353)
		(end 106.611069 82.817352)
		(width 0.13)
		(layer "In4.Cu")
		(net 187)
	)
	(segment
		(start 131.460027 96.4)
		(end 132.55 96.4)
		(width 0.13)
		(layer "In4.Cu")
		(net 187)
	)
	(segment
		(start 105.161501 82.287025)
		(end 105.161502 82.287024)
		(width 0.13)
		(layer "In4.Cu")
		(net 187)
	)
	(segment
		(start 126.655 97.545)
		(end 127.2 97)
		(width 0.13)
		(layer "In4.Cu")
		(net 187)
	)
	(segment
		(start 106.045385 82.251668)
		(end 106.045384 82.251667)
		(width 0.13)
		(layer "In4.Cu")
		(net 187)
	)
	(segment
		(start 101.83 81.99)
		(end 103.59 81.99)
		(width 0.13)
		(layer "In4.Cu")
		(net 187)
	)
	(segment
		(start 133.9 94.297819)
		(end 133.9 91.409871)
		(width 0.13)
		(layer "In4.Cu")
		(net 187)
	)
	(arc
		(start 104.87866 82.004183)
		(mid 105.02008 81.945604)
		(end 105.161502 82.004183)
		(width 0.13)
		(layer "In4.Cu")
		(net 187)
	)
	(arc
		(start 105.797051 84.479896)
		(mid 105.938472 84.421317)
		(end 106.079894 84.479895)
		(width 0.13)
		(layer "In4.Cu")
		(net 187)
	)
	(arc
		(start 104.841616 84.021119)
		(mid 104.983038 84.079697)
		(end 105.124459 84.021118)
		(width 0.13)
		(layer "In4.Cu")
		(net 187)
	)
	(arc
		(start 105.161502 82.004182)
		(mid 105.22008 82.145604)
		(end 105.161501 82.287025)
		(width 0.13)
		(layer "In4.Cu")
		(net 187)
	)
	(arc
		(start 105.76254 82.251665)
		(mid 105.903964 82.193089)
		(end 106.045385 82.251668)
		(width 0.13)
		(layer "In4.Cu")
		(net 187)
	)
	(arc
		(start 106.045384 82.251667)
		(mid 106.103962 82.393089)
		(end 106.045383 82.53451)
		(width 0.13)
		(layer "In4.Cu")
		(net 187)
	)
	(arc
		(start 106.611069 82.817352)
		(mid 106.669647 82.958774)
		(end 106.611068 83.100195)
		(width 0.13)
		(layer "In4.Cu")
		(net 187)
	)
	(arc
		(start 103.639535 84.091831)
		(mid 103.780957 84.150409)
		(end 103.922378 84.09183)
		(width 0.13)
		(layer "In4.Cu")
		(net 187)
	)
	(arc
		(start 104.841616 83.738277)
		(mid 104.783038 83.879699)
		(end 104.841617 84.02112)
		(width 0.13)
		(layer "In4.Cu")
		(net 187)
	)
	(arc
		(start 106.328225 82.81735)
		(mid 106.469649 82.758774)
		(end 106.61107 82.817353)
		(width 0.13)
		(layer "In4.Cu")
		(net 187)
	)
	(arc
		(start 104.770905 85.223201)
		(mid 104.912327 85.281779)
		(end 105.053748 85.2232)
		(width 0.13)
		(layer "In4.Cu")
		(net 187)
	)
	(arc
		(start 103.639535 83.808988)
		(mid 103.580957 83.95041)
		(end 103.639536 84.091831)
		(width 0.13)
		(layer "In4.Cu")
		(net 187)
	)
	(arc
		(start 104.770905 84.940358)
		(mid 104.712327 85.08178)
		(end 104.770906 85.223201)
		(width 0.13)
		(layer "In4.Cu")
		(net 187)
	)
	(arc
		(start 104.1 82.5)
		(mid 104.241422 82.558578)
		(end 104.382843 82.499999)
		(width 0.13)
		(layer "In4.Cu")
		(net 187)
	)
	(segment
		(start 100.1 81.4)
		(end 100.53 81.4)
		(width 0.2)
		(layer "F.Cu")
		(net 188)
	)
	(segment
		(start 131.9 90.3)
		(end 131.5 89.9)
		(width 0.15)
		(layer "F.Cu")
		(net 188)
	)
	(segment
		(start 100.53 81.4)
		(end 100.58 81.35)
		(width 0.2)
		(layer "F.Cu")
		(net 188)
	)
	(segment
		(start 101.77 81.35)
		(end 101.83 81.41)
		(width 0.2)
		(layer "F.Cu")
		(net 188)
	)
	(segment
		(start 100.58 81.35)
		(end 101.77 81.35)
		(width 0.2)
		(layer "F.Cu")
		(net 188)
	)
	(via
		(at 101.83 81.41)
		(size 0.45)
		(drill 0.2)
		(layers "F.Cu" "B.Cu")
		(remove_unused_layers yes)
		(keep_end_layers yes)
		(zone_layer_connections)
		(net 188)
	)
	(via
		(at 131.9 90.3)
		(size 0.45)
		(drill 0.2)
		(layers "F.Cu" "B.Cu")
		(remove_unused_layers yes)
		(keep_end_layers yes)
		(zone_layer_connections)
		(net 188)
	)
	(segment
		(start 122.935 96.515)
		(end 122.95 96.5)
		(width 0.13)
		(layer "In4.Cu")
		(net 188)
	)
	(segment
		(start 132.3 90.7)
		(end 131.9 90.3)
		(width 0.13)
		(layer "In4.Cu")
		(net 188)
	)
	(segment
		(start 133.5 94.1)
		(end 133.5 91.55)
		(width 0.13)
		(layer "In4.Cu")
		(net 188)
	)
	(segment
		(start 107.66 81.66)
		(end 108.481777 82.481777)
		(width 0.13)
		(layer "In4.Cu")
		(net 188)
	)
	(segment
		(start 130.5 96.4)
		(end 131.05 95.85)
		(width 0.13)
		(layer "In4.Cu")
		(net 188)
	)
	(segment
		(start 108.681777 83.081777)
		(end 109.369666 83.081777)
		(width 0.13)
		(layer "In4.Cu")
		(net 188)
	)
	(segment
		(start 107.593888 83.881777)
		(end 109.369666 83.881777)
		(width 0.13)
		(layer "In4.Cu")
		(net 188)
	)
	(segment
		(start 108.48 86.54)
		(end 108.48 87.13)
		(width 0.13)
		(layer "In4.Cu")
		(net 188)
	)
	(segment
		(start 107.593888 84.281777)
		(end 109.369666 84.281777)
		(width 0.13)
		(layer "In4.Cu")
		(net 188)
	)
	(segment
		(start 131.05 95.85)
		(end 132.4 95.85)
		(width 0.13)
		(layer "In4.Cu")
		(net 188)
	)
	(segment
		(start 107.593888 85.081777)
		(end 109.369666 85.081777)
		(width 0.13)
		(layer "In4.Cu")
		(net 188)
	)
	(segment
		(start 122.95 96.5)
		(end 123.45 96.5)
		(width 0.13)
		(layer "In4.Cu")
		(net 188)
	)
	(segment
		(start 108.481777 86.490625)
		(end 108.48 86.54)
		(width 0.13)
		(layer "In4.Cu")
		(net 188)
	)
	(segment
		(start 107.593888 85.481777)
		(end 109.369666 85.481777)
		(width 0.13)
		(layer "In4.Cu")
		(net 188)
	)
	(segment
		(start 132.4 95.85)
		(end 133.25 95)
		(width 0.13)
		(layer "In4.Cu")
		(net 188)
	)
	(segment
		(start 109.369666 85.881777)
		(end 108.681777 85.881777)
		(width 0.13)
		(layer "In4.Cu")
		(net 188)
	)
	(segment
		(start 126.95 96.4)
		(end 130.5 96.4)
		(width 0.13)
		(layer "In4.Cu")
		(net 188)
	)
	(segment
		(start 120.685 96.515)
		(end 122.935 96.515)
		(width 0.13)
		(layer "In4.Cu")
		(net 188)
	)
	(segment
		(start 107.593888 83.481777)
		(end 109.369666 83.481777)
		(width 0.13)
		(layer "In4.Cu")
		(net 188)
	)
	(segment
		(start 132.9 90.7)
		(end 132.3 90.7)
		(width 0.13)
		(layer "In4.Cu")
		(net 188)
	)
	(segment
		(start 108.48 87.13)
		(end 118.4245 97.0745)
		(width 0.13)
		(layer "In4.Cu")
		(net 188)
	)
	(segment
		(start 124.235 97.285)
		(end 126.065 97.285)
		(width 0.13)
		(layer "In4.Cu")
		(net 188)
	)
	(segment
		(start 102.08 81.66)
		(end 107.66 81.66)
		(width 0.13)
		(layer "In4.Cu")
		(net 188)
	)
	(segment
		(start 126.065 97.285)
		(end 126.95 96.4)
		(width 0.13)
		(layer "In4.Cu")
		(net 188)
	)
	(segment
		(start 133.5 91.55)
		(end 133.37 91.42)
		(width 0.13)
		(layer "In4.Cu")
		(net 188)
	)
	(segment
		(start 107.593888 84.681777)
		(end 109.369666 84.681777)
		(width 0.13)
		(layer "In4.Cu")
		(net 188)
	)
	(segment
		(start 101.83 81.41)
		(end 102.08 81.66)
		(width 0.13)
		(layer "In4.Cu")
		(net 188)
	)
	(segment
		(start 133.37 91.17)
		(end 132.9 90.7)
		(width 0.13)
		(layer "In4.Cu")
		(net 188)
	)
	(segment
		(start 133.25 94.35)
		(end 133.5 94.1)
		(width 0.13)
		(layer "In4.Cu")
		(net 188)
	)
	(segment
		(start 108.481777 82.481777)
		(end 108.481777 82.881777)
		(width 0.13)
		(layer "In4.Cu")
		(net 188)
	)
	(segment
		(start 133.37 91.42)
		(end 133.37 91.17)
		(width 0.13)
		(layer "In4.Cu")
		(net 188)
	)
	(segment
		(start 133.25 95)
		(end 133.25 94.35)
		(width 0.13)
		(layer "In4.Cu")
		(net 188)
	)
	(segment
		(start 118.4245 97.0745)
		(end 120.1255 97.0745)
		(width 0.13)
		(layer "In4.Cu")
		(net 188)
	)
	(segment
		(start 123.45 96.5)
		(end 124.235 97.285)
		(width 0.13)
		(layer "In4.Cu")
		(net 188)
	)
	(segment
		(start 120.1255 97.0745)
		(end 120.685 96.515)
		(width 0.13)
		(layer "In4.Cu")
		(net 188)
	)
	(segment
		(start 108.481777 86.081777)
		(end 108.481777 86.490625)
		(width 0.13)
		(layer "In4.Cu")
		(net 188)
	)
	(arc
		(start 107.393888 83.681777)
		(mid 107.452467 83.823198)
		(end 107.593888 83.881777)
		(width 0.13)
		(layer "In4.Cu")
		(net 188)
	)
	(arc
		(start 109.369666 84.681777)
		(mid 109.511087 84.740356)
		(end 109.569666 84.881777)
		(width 0.13)
		(layer "In4.Cu")
		(net 188)
	)
	(arc
		(start 107.393888 85.281777)
		(mid 107.452467 85.423198)
		(end 107.593888 85.481777)
		(width 0.13)
		(layer "In4.Cu")
		(net 188)
	)
	(arc
		(start 109.369666 85.481777)
		(mid 109.511087 85.540356)
		(end 109.569666 85.681777)
		(width 0.13)
		(layer "In4.Cu")
		(net 188)
	)
	(arc
		(start 109.569666 83.281777)
		(mid 109.511087 83.423198)
		(end 109.369666 83.481777)
		(width 0.13)
		(layer "In4.Cu")
		(net 188)
	)
	(arc
		(start 108.681777 85.881777)
		(mid 108.540356 85.940356)
		(end 108.481777 86.081777)
		(width 0.13)
		(layer "In4.Cu")
		(net 188)
	)
	(arc
		(start 107.593888 84.281777)
		(mid 107.452467 84.340356)
		(end 107.393888 84.481777)
		(width 0.13)
		(layer "In4.Cu")
		(net 188)
	)
	(arc
		(start 107.593888 83.481777)
		(mid 107.452467 83.540356)
		(end 107.393888 83.681777)
		(width 0.13)
		(layer "In4.Cu")
		(net 188)
	)
	(arc
		(start 109.569666 84.881777)
		(mid 109.511087 85.023198)
		(end 109.369666 85.081777)
		(width 0.13)
		(layer "In4.Cu")
		(net 188)
	)
	(arc
		(start 109.369666 83.881777)
		(mid 109.511087 83.940356)
		(end 109.569666 84.081777)
		(width 0.13)
		(layer "In4.Cu")
		(net 188)
	)
	(arc
		(start 109.569666 85.681777)
		(mid 109.511087 85.823198)
		(end 109.369666 85.881777)
		(width 0.13)
		(layer "In4.Cu")
		(net 188)
	)
	(arc
		(start 109.369666 83.081777)
		(mid 109.511087 83.140356)
		(end 109.569666 83.281777)
		(width 0.13)
		(layer "In4.Cu")
		(net 188)
	)
	(arc
		(start 108.481777 82.881777)
		(mid 108.540356 83.023198)
		(end 108.681777 83.081777)
		(width 0.13)
		(layer "In4.Cu")
		(net 188)
	)
	(arc
		(start 107.593888 85.081777)
		(mid 107.452467 85.140356)
		(end 107.393888 85.281777)
		(width 0.13)
		(layer "In4.Cu")
		(net 188)
	)
	(arc
		(start 109.569666 84.081777)
		(mid 109.511087 84.223198)
		(end 109.369666 84.281777)
		(width 0.13)
		(layer "In4.Cu")
		(net 188)
	)
	(arc
		(start 107.393888 84.481777)
		(mid 107.452467 84.623198)
		(end 107.593888 84.681777)
		(width 0.13)
		(layer "In4.Cu")
		(net 188)
	)
	(segment
		(start 100.545 82.515)
		(end 101.665 82.515)
		(width 0.2)
		(layer "F.Cu")
		(net 189)
	)
	(segment
		(start 101.665 82.515)
		(end 101.85 82.7)
		(width 0.2)
		(layer "F.Cu")
		(net 189)
	)
	(segment
		(start 100.1 82.4)
		(end 100.43 82.4)
		(width 0.2)
		(layer "F.Cu")
		(net 189)
	)
	(segment
		(start 131.9 89.5)
		(end 131.5 89.1)
		(width 0.15)
		(layer "F.Cu")
		(net 189)
	)
	(segment
		(start 100.43 82.4)
		(end 100.545 82.515)
		(width 0.2)
		(layer "F.Cu")
		(net 189)
	)
	(via
		(at 131.9 89.5)
		(size 0.45)
		(drill 0.2)
		(layers "F.Cu" "B.Cu")
		(remove_unused_layers yes)
		(keep_end_layers yes)
		(zone_layer_connections)
		(net 189)
	)
	(via
		(at 101.85 82.7)
		(size 0.45)
		(drill 0.2)
		(layers "F.Cu" "B.Cu")
		(remove_unused_layers yes)
		(keep_end_layers yes)
		(zone_layer_connections)
		(net 189)
	)
	(segment
		(start 108.752688 89.086994)
		(end 108.752689 89.086993)
		(width 0.13)
		(layer "In4.Cu")
		(net 189)
	)
	(segment
		(start 107.529889 89.46127)
		(end 107.529888 89.461269)
		(width 0.13)
		(layer "In4.Cu")
		(net 189)
	)
	(segment
		(start 107.62132 87.955626)
		(end 107.621321 87.955625)
		(width 0.13)
		(layer "In4.Cu")
		(net 189)
	)
	(segment
		(start 106.489953 86.824257)
		(end 105.832836 87.481375)
		(width 0.13)
		(layer "In4.Cu")
		(net 189)
	)
	(segment
		(start 101.85 82.7)
		(end 105.525 86.375)
		(width 0.13)
		(layer "In4.Cu")
		(net 189)
	)
	(segment
		(start 107.055636 87.389942)
		(end 107.055637 87.389941)
		(width 0.13)
		(layer "In4.Cu")
		(net 189)
	)
	(segment
		(start 105.832837 87.764218)
		(end 105.832836 87.764217)
		(width 0.13)
		(layer "In4.Cu")
		(net 189)
	)
	(segment
		(start 108.752689 89.086993)
		(end 108.095572 89.744111)
		(width 0.13)
		(layer "In4.Cu")
		(net 189)
	)
	(segment
		(start 109.318372 89.652678)
		(end 109.318373 89.652677)
		(width 0.13)
		(layer "In4.Cu")
		(net 189)
	)
	(segment
		(start 108.378415 90.026952)
		(end 108.378414 90.026953)
		(width 0.13)
		(layer "In4.Cu")
		(net 189)
	)
	(segment
		(start 106.115678 87.764217)
		(end 106.772793 87.107098)
		(width 0.13)
		(layer "In4.Cu")
		(net 189)
	)
	(segment
		(start 108.75269 88.804151)
		(end 108.752689 88.804151)
		(width 0.13)
		(layer "In4.Cu")
		(net 189)
	)
	(segment
		(start 134.416146 91.410619)
		(end 133.89251 90.886983)
		(width 0.13)
		(layer "In4.Cu")
		(net 189)
	)
	(segment
		(start 117.54 98.39)
		(end 126.56 98.39)
		(width 0.13)
		(layer "In4.Cu")
		(net 189)
	)
	(segment
		(start 133.25 89.9)
		(end 132.3 89.9)
		(width 0.13)
		(layer "In4.Cu")
		(net 189)
	)
	(segment
		(start 108.095573 90.026954)
		(end 108.095572 90.026953)
		(width 0.13)
		(layer "In4.Cu")
		(net 189)
	)
	(segment
		(start 107.247046 88.895585)
		(end 107.904161 88.238466)
		(width 0.13)
		(layer "In4.Cu")
		(net 189)
	)
	(segment
		(start 109.318374 89.369835)
		(end 109.318373 89.369835)
		(width 0.13)
		(layer "In4.Cu")
		(net 189)
	)
	(segment
		(start 133.89251 90.886983)
		(end 133.89251 90.54251)
		(width 0.13)
		(layer "In4.Cu")
		(net 189)
	)
	(segment
		(start 105.525 86.657842)
		(end 105.267152 86.915689)
		(width 0.13)
		(layer "In4.Cu")
		(net 189)
	)
	(segment
		(start 106.398521 88.329902)
		(end 106.39852 88.329901)
		(width 0.13)
		(layer "In4.Cu")
		(net 189)
	)
	(segment
		(start 107.055637 87.389941)
		(end 106.39852 88.047059)
		(width 0.13)
		(layer "In4.Cu")
		(net 189)
	)
	(segment
		(start 109.201946 90.051946)
		(end 117.54 98.39)
		(width 0.13)
		(layer "In4.Cu")
		(net 189)
	)
	(segment
		(start 133.89251 90.54251)
		(end 133.25 89.9)
		(width 0.13)
		(layer "In4.Cu")
		(net 189)
	)
	(segment
		(start 105.549994 87.198532)
		(end 106.207109 86.541414)
		(width 0.13)
		(layer "In4.Cu")
		(net 189)
	)
	(segment
		(start 105.549995 87.198531)
		(end 105.549994 87.198532)
		(width 0.13)
		(layer "In4.Cu")
		(net 189)
	)
	(segment
		(start 106.489952 86.824258)
		(end 106.489953 86.824257)
		(width 0.13)
		(layer "In4.Cu")
		(net 189)
	)
	(segment
		(start 109.318373 89.652677)
		(end 109.201947 89.769104)
		(width 0.13)
		(layer "In4.Cu")
		(net 189)
	)
	(segment
		(start 132.254027 97.185)
		(end 132.865 97.185)
		(width 0.13)
		(layer "In4.Cu")
		(net 189)
	)
	(segment
		(start 106.964205 88.895586)
		(end 106.964204 88.895585)
		(width 0.13)
		(layer "In4.Cu")
		(net 189)
	)
	(segment
		(start 109.201947 90.051946)
		(end 109.201946 90.051946)
		(width 0.13)
		(layer "In4.Cu")
		(net 189)
	)
	(segment
		(start 106.489954 86.541415)
		(end 106.489953 86.541415)
		(width 0.13)
		(layer "In4.Cu")
		(net 189)
	)
	(segment
		(start 134.416146 95.633854)
		(end 134.416146 91.410619)
		(width 0.13)
		(layer "In4.Cu")
		(net 189)
	)
	(segment
		(start 107.621321 87.955625)
		(end 106.964204 88.612743)
		(width 0.13)
		(layer "In4.Cu")
		(net 189)
	)
	(segment
		(start 132.3 89.9)
		(end 131.9 89.5)
		(width 0.13)
		(layer "In4.Cu")
		(net 189)
	)
	(segment
		(start 132.865 97.185)
		(end 134.416146 95.633854)
		(width 0.13)
		(layer "In4.Cu")
		(net 189)
	)
	(segment
		(start 131.839027 97.6)
		(end 132.254027 97.185)
		(width 0.13)
		(layer "In4.Cu")
		(net 189)
	)
	(segment
		(start 107.81273 89.461269)
		(end 108.469845 88.80415)
		(width 0.13)
		(layer "In4.Cu")
		(net 189)
	)
	(segment
		(start 108.187004 88.52131)
		(end 108.187005 88.521309)
		(width 0.13)
		(layer "In4.Cu")
		(net 189)
	)
	(segment
		(start 106.681362 88.329901)
		(end 107.338477 87.672782)
		(width 0.13)
		(layer "In4.Cu")
		(net 189)
	)
	(segment
		(start 108.187006 88.238467)
		(end 108.187005 88.238467)
		(width 0.13)
		(layer "In4.Cu")
		(net 189)
	)
	(segment
		(start 107.621322 87.672783)
		(end 107.621321 87.672783)
		(width 0.13)
		(layer "In4.Cu")
		(net 189)
	)
	(segment
		(start 105.524999 86.657843)
		(end 105.525 86.657842)
		(width 0.13)
		(layer "In4.Cu")
		(net 189)
	)
	(segment
		(start 105.267151 87.198532)
		(end 105.267152 87.198532)
		(width 0.13)
		(layer "In4.Cu")
		(net 189)
	)
	(segment
		(start 107.812731 89.461268)
		(end 107.81273 89.461269)
		(width 0.13)
		(layer "In4.Cu")
		(net 189)
	)
	(segment
		(start 127.35 97.6)
		(end 131.839027 97.6)
		(width 0.13)
		(layer "In4.Cu")
		(net 189)
	)
	(segment
		(start 106.115679 87.764216)
		(end 106.115678 87.764217)
		(width 0.13)
		(layer "In4.Cu")
		(net 189)
	)
	(segment
		(start 107.247047 88.895584)
		(end 107.247046 88.895585)
		(width 0.13)
		(layer "In4.Cu")
		(net 189)
	)
	(segment
		(start 126.56 98.39)
		(end 127.35 97.6)
		(width 0.13)
		(layer "In4.Cu")
		(net 189)
	)
	(segment
		(start 108.378414 90.026953)
		(end 109.035529 89.369834)
		(width 0.13)
		(layer "In4.Cu")
		(net 189)
	)
	(segment
		(start 106.681363 88.3299)
		(end 106.681362 88.329901)
		(width 0.13)
		(layer "In4.Cu")
		(net 189)
	)
	(segment
		(start 107.055638 87.107099)
		(end 107.055637 87.107099)
		(width 0.13)
		(layer "In4.Cu")
		(net 189)
	)
	(segment
		(start 108.187005 88.521309)
		(end 107.529888 89.178427)
		(width 0.13)
		(layer "In4.Cu")
		(net 189)
	)
	(arc
		(start 106.39852 88.047059)
		(mid 106.339942 88.188481)
		(end 106.398521 88.329902)
		(width 0.13)
		(layer "In4.Cu")
		(net 189)
	)
	(arc
		(start 108.187005 88.238467)
		(mid 108.245583 88.379889)
		(end 108.187004 88.52131)
		(width 0.13)
		(layer "In4.Cu")
		(net 189)
	)
	(arc
		(start 106.964204 88.612743)
		(mid 106.905626 88.754165)
		(end 106.964205 88.895586)
		(width 0.13)
		(layer "In4.Cu")
		(net 189)
	)
	(arc
		(start 106.207109 86.541414)
		(mid 106.348532 86.482837)
		(end 106.489954 86.541415)
		(width 0.13)
		(layer "In4.Cu")
		(net 189)
	)
	(arc
		(start 108.469845 88.80415)
		(mid 108.611268 88.745573)
		(end 108.75269 88.804151)
		(width 0.13)
		(layer "In4.Cu")
		(net 189)
	)
	(arc
		(start 105.267152 86.915689)
		(mid 105.208573 87.05711)
		(end 105.267151 87.198532)
		(width 0.13)
		(layer "In4.Cu")
		(net 189)
	)
	(arc
		(start 106.964204 88.895585)
		(mid 107.105626 88.954163)
		(end 107.247047 88.895584)
		(width 0.13)
		(layer "In4.Cu")
		(net 189)
	)
	(arc
		(start 109.201947 89.769104)
		(mid 109.143368 89.910524)
		(end 109.201947 90.051946)
		(width 0.13)
		(layer "In4.Cu")
		(net 189)
	)
	(arc
		(start 107.055637 87.107099)
		(mid 107.114215 87.248521)
		(end 107.055636 87.389942)
		(width 0.13)
		(layer "In4.Cu")
		(net 189)
	)
	(arc
		(start 106.489953 86.541415)
		(mid 106.548531 86.682837)
		(end 106.489952 86.824258)
		(width 0.13)
		(layer "In4.Cu")
		(net 189)
	)
	(arc
		(start 105.832836 87.481375)
		(mid 105.774258 87.622797)
		(end 105.832837 87.764218)
		(width 0.13)
		(layer "In4.Cu")
		(net 189)
	)
	(arc
		(start 107.529888 89.178427)
		(mid 107.47131 89.319849)
		(end 107.529889 89.46127)
		(width 0.13)
		(layer "In4.Cu")
		(net 189)
	)
	(arc
		(start 105.525 86.375)
		(mid 105.583578 86.516422)
		(end 105.524999 86.657843)
		(width 0.13)
		(layer "In4.Cu")
		(net 189)
	)
	(arc
		(start 108.095572 90.026953)
		(mid 108.236994 90.085531)
		(end 108.378415 90.026952)
		(width 0.13)
		(layer "In4.Cu")
		(net 189)
	)
	(arc
		(start 106.39852 88.329901)
		(mid 106.539942 88.388479)
		(end 106.681363 88.3299)
		(width 0.13)
		(layer "In4.Cu")
		(net 189)
	)
	(arc
		(start 108.095572 89.744111)
		(mid 108.036994 89.885533)
		(end 108.095573 90.026954)
		(width 0.13)
		(layer "In4.Cu")
		(net 189)
	)
	(arc
		(start 107.621321 87.672783)
		(mid 107.679899 87.814205)
		(end 107.62132 87.955626)
		(width 0.13)
		(layer "In4.Cu")
		(net 189)
	)
	(arc
		(start 108.752689 88.804151)
		(mid 108.811267 88.945573)
		(end 108.752688 89.086994)
		(width 0.13)
		(layer "In4.Cu")
		(net 189)
	)
	(arc
		(start 107.904161 88.238466)
		(mid 108.045584 88.179889)
		(end 108.187006 88.238467)
		(width 0.13)
		(layer "In4.Cu")
		(net 189)
	)
	(arc
		(start 107.338477 87.672782)
		(mid 107.4799 87.614205)
		(end 107.621322 87.672783)
		(width 0.13)
		(layer "In4.Cu")
		(net 189)
	)
	(arc
		(start 105.832836 87.764217)
		(mid 105.974258 87.822795)
		(end 106.115679 87.764216)
		(width 0.13)
		(layer "In4.Cu")
		(net 189)
	)
	(arc
		(start 106.772793 87.107098)
		(mid 106.914216 87.048521)
		(end 107.055638 87.107099)
		(width 0.13)
		(layer "In4.Cu")
		(net 189)
	)
	(arc
		(start 105.267152 87.198532)
		(mid 105.408574 87.25711)
		(end 105.549995 87.198531)
		(width 0.13)
		(layer "In4.Cu")
		(net 189)
	)
	(arc
		(start 107.529888 89.461269)
		(mid 107.67131 89.519847)
		(end 107.812731 89.461268)
		(width 0.13)
		(layer "In4.Cu")
		(net 189)
	)
	(arc
		(start 109.318373 89.369835)
		(mid 109.376951 89.511257)
		(end 109.318372 89.652678)
		(width 0.13)
		(layer "In4.Cu")
		(net 189)
	)
	(arc
		(start 109.035529 89.369834)
		(mid 109.176952 89.311257)
		(end 109.318374 89.369835)
		(width 0.13)
		(layer "In4.Cu")
		(net 189)
	)
	(segment
		(start 101.49 83.9)
		(end 99.99 83.9)
		(width 0.2)
		(layer "F.Cu")
		(net 190)
	)
	(segment
		(start 99.99 83.9)
		(end 99.1 83.01)
		(width 0.2)
		(layer "F.Cu")
		(net 190)
	)
	(segment
		(start 99.1 83.01)
		(end 99.1 82.4)
		(width 0.2)
		(layer "F.Cu")
		(net 190)
	)
	(segment
		(start 132.3 89.1)
		(end 132.7 89.5)
		(width 0.2)
		(layer "F.Cu")
		(net 190)
	)
	(via
		(at 101.49 83.9)
		(size 0.45)
		(drill 0.2)
		(layers "F.Cu" "B.Cu")
		(remove_unused_layers yes)
		(keep_end_layers yes)
		(zone_layer_connections)
		(net 190)
	)
	(via
		(at 132.7 89.5)
		(size 0.45)
		(drill 0.2)
		(layers "F.Cu" "B.Cu")
		(remove_unused_layers yes)
		(keep_end_layers yes)
		(zone_layer_connections)
		(net 190)
	)
	(segment
		(start 133.000527 98.005)
		(end 135.25 95.755527)
		(width 0.13)
		(layer "In4.Cu")
		(net 190)
	)
	(segment
		(start 115.685233 98.040231)
		(end 116.545 98.9)
		(width 0.13)
		(layer "In4.Cu")
		(net 190)
	)
	(segment
		(start 114.836379 96.060676)
		(end 114.836378 96.060674)
		(width 0.13)
		(layer "In4.Cu")
		(net 190)
	)
	(segment
		(start 113.59961 97.014602)
		(end 113.599609 97.014603)
		(width 0.13)
		(layer "In4.Cu")
		(net 190)
	)
	(segment
		(start 114.448132 98.145967)
		(end 114.448131 98.145967)
		(width 0.13)
		(layer "In4.Cu")
		(net 190)
	)
	(segment
		(start 113.599609 97.014603)
		(end 114.553534 96.060673)
		(width 0.13)
		(layer "In4.Cu")
		(net 190)
	)
	(segment
		(start 115.967743 97.19204)
		(end 115.967742 97.192038)
		(width 0.13)
		(layer "In4.Cu")
		(net 190)
	)
	(segment
		(start 134.75 90.65)
		(end 133.6 89.5)
		(width 0.13)
		(layer "In4.Cu")
		(net 190)
	)
	(segment
		(start 114.730974 98.145966)
		(end 114.730973 98.145967)
		(width 0.13)
		(layer "In4.Cu")
		(net 190)
	)
	(segment
		(start 113.705343 95.777499)
		(end 113.705342 95.7775)
		(width 0.13)
		(layer "In4.Cu")
		(net 190)
	)
	(segment
		(start 115.40206 96.909198)
		(end 114.97813 97.333129)
		(width 0.13)
		(layer "In4.Cu")
		(net 190)
	)
	(segment
		(start 114.165291 97.580285)
		(end 115.119216 96.626355)
		(width 0.13)
		(layer "In4.Cu")
		(net 190)
	)
	(segment
		(start 135.25 95.755527)
		(end 135.25 92.75)
		(width 0.13)
		(layer "In4.Cu")
		(net 190)
	)
	(segment
		(start 133.6 89.5)
		(end 132.7 89.5)
		(width 0.13)
		(layer "In4.Cu")
		(net 190)
	)
	(segment
		(start 115.685233 98.040232)
		(end 115.685233 98.040231)
		(width 0.13)
		(layer "In4.Cu")
		(net 190)
	)
	(segment
		(start 127 98.9)
		(end 127.895 98.005)
		(width 0.13)
		(layer "In4.Cu")
		(net 190)
	)
	(segment
		(start 114.730973 98.145967)
		(end 115.684898 97.192037)
		(width 0.13)
		(layer "In4.Cu")
		(net 190)
	)
	(segment
		(start 114.270694 95.494991)
		(end 114.270693 95.494991)
		(width 0.13)
		(layer "In4.Cu")
		(net 190)
	)
	(segment
		(start 114.270693 95.777833)
		(end 113.316767 96.73176)
		(width 0.13)
		(layer "In4.Cu")
		(net 190)
	)
	(segment
		(start 114.836377 96.343517)
		(end 114.836378 96.343516)
		(width 0.13)
		(layer "In4.Cu")
		(net 190)
	)
	(segment
		(start 113.705342 95.7775)
		(end 113.987851 95.494992)
		(width 0.13)
		(layer "In4.Cu")
		(net 190)
	)
	(segment
		(start 115.402059 96.909199)
		(end 115.40206 96.909198)
		(width 0.13)
		(layer "In4.Cu")
		(net 190)
	)
	(segment
		(start 127.895 98.005)
		(end 133.000527 98.005)
		(width 0.13)
		(layer "In4.Cu")
		(net 190)
	)
	(segment
		(start 113.316768 97.014603)
		(end 113.316767 97.014603)
		(width 0.13)
		(layer "In4.Cu")
		(net 190)
	)
	(segment
		(start 114.836378 96.343516)
		(end 114.412448 96.767447)
		(width 0.13)
		(layer "In4.Cu")
		(net 190)
	)
	(segment
		(start 114.978128 97.333128)
		(end 114.448131 97.863124)
		(width 0.13)
		(layer "In4.Cu")
		(net 190)
	)
	(segment
		(start 101.49 83.9)
		(end 101.545 83.9)
		(width 0.13)
		(layer "In4.Cu")
		(net 190)
	)
	(segment
		(start 114.165292 97.580284)
		(end 114.165291 97.580285)
		(width 0.13)
		(layer "In4.Cu")
		(net 190)
	)
	(segment
		(start 115.402061 96.626358)
		(end 115.40206 96.626356)
		(width 0.13)
		(layer "In4.Cu")
		(net 190)
	)
	(segment
		(start 134.75 92.25)
		(end 134.75 90.65)
		(width 0.13)
		(layer "In4.Cu")
		(net 190)
	)
	(segment
		(start 114.412446 96.767446)
		(end 113.882449 97.297442)
		(width 0.13)
		(layer "In4.Cu")
		(net 190)
	)
	(segment
		(start 115.967742 97.47488)
		(end 115.685234 97.757389)
		(width 0.13)
		(layer "In4.Cu")
		(net 190)
	)
	(segment
		(start 114.270692 95.777834)
		(end 114.270693 95.777833)
		(width 0.13)
		(layer "In4.Cu")
		(net 190)
	)
	(segment
		(start 115.967741 97.474881)
		(end 115.967742 97.47488)
		(width 0.13)
		(layer "In4.Cu")
		(net 190)
	)
	(segment
		(start 113.88245 97.580285)
		(end 113.882449 97.580285)
		(width 0.13)
		(layer "In4.Cu")
		(net 190)
	)
	(segment
		(start 114.412448 96.767447)
		(end 114.412446 96.767446)
		(width 0.13)
		(layer "In4.Cu")
		(net 190)
	)
	(segment
		(start 101.545 83.9)
		(end 113.4225 95.7775)
		(width 0.13)
		(layer "In4.Cu")
		(net 190)
	)
	(segment
		(start 116.545 98.9)
		(end 127 98.9)
		(width 0.13)
		(layer "In4.Cu")
		(net 190)
	)
	(segment
		(start 114.97813 97.333129)
		(end 114.978128 97.333128)
		(width 0.13)
		(layer "In4.Cu")
		(net 190)
	)
	(segment
		(start 135.25 92.75)
		(end 134.75 92.25)
		(width 0.13)
		(layer "In4.Cu")
		(net 190)
	)
	(arc
		(start 113.316767 96.73176)
		(mid 113.258189 96.873182)
		(end 113.316768 97.014603)
		(width 0.13)
		(layer "In4.Cu")
		(net 190)
	)
	(arc
		(start 115.967742 97.192038)
		(mid 116.02632 97.33346)
		(end 115.967741 97.474881)
		(width 0.13)
		(layer "In4.Cu")
		(net 190)
	)
	(arc
		(start 114.553534 96.060673)
		(mid 114.694958 96.002097)
		(end 114.836379 96.060676)
		(width 0.13)
		(layer "In4.Cu")
		(net 190)
	)
	(arc
		(start 114.270693 95.494991)
		(mid 114.329271 95.636413)
		(end 114.270692 95.777834)
		(width 0.13)
		(layer "In4.Cu")
		(net 190)
	)
	(arc
		(start 115.685234 97.757389)
		(mid 115.626655 97.89881)
		(end 115.685233 98.040232)
		(width 0.13)
		(layer "In4.Cu")
		(net 190)
	)
	(arc
		(start 114.836378 96.060674)
		(mid 114.894956 96.202096)
		(end 114.836377 96.343517)
		(width 0.13)
		(layer "In4.Cu")
		(net 190)
	)
	(arc
		(start 113.316767 97.014603)
		(mid 113.458189 97.073181)
		(end 113.59961 97.014602)
		(width 0.13)
		(layer "In4.Cu")
		(net 190)
	)
	(arc
		(start 114.448131 97.863124)
		(mid 114.389553 98.004546)
		(end 114.448132 98.145967)
		(width 0.13)
		(layer "In4.Cu")
		(net 190)
	)
	(arc
		(start 113.882449 97.297442)
		(mid 113.823871 97.438864)
		(end 113.88245 97.580285)
		(width 0.13)
		(layer "In4.Cu")
		(net 190)
	)
	(arc
		(start 113.882449 97.580285)
		(mid 114.023871 97.638863)
		(end 114.165292 97.580284)
		(width 0.13)
		(layer "In4.Cu")
		(net 190)
	)
	(arc
		(start 115.40206 96.626356)
		(mid 115.460638 96.767778)
		(end 115.402059 96.909199)
		(width 0.13)
		(layer "In4.Cu")
		(net 190)
	)
	(arc
		(start 114.448131 98.145967)
		(mid 114.589553 98.204545)
		(end 114.730974 98.145966)
		(width 0.13)
		(layer "In4.Cu")
		(net 190)
	)
	(arc
		(start 115.684898 97.192037)
		(mid 115.826322 97.133461)
		(end 115.967743 97.19204)
		(width 0.13)
		(layer "In4.Cu")
		(net 190)
	)
	(arc
		(start 115.119216 96.626355)
		(mid 115.26064 96.567779)
		(end 115.402061 96.626358)
		(width 0.13)
		(layer "In4.Cu")
		(net 190)
	)
	(arc
		(start 113.4225 95.7775)
		(mid 113.563922 95.836078)
		(end 113.705343 95.777499)
		(width 0.13)
		(layer "In4.Cu")
		(net 190)
	)
	(arc
		(start 113.987851 95.494992)
		(mid 114.129272 95.436413)
		(end 114.270694 95.494991)
		(width 0.13)
		(layer "In4.Cu")
		(net 190)
	)
	(segment
		(start 98.61 84.19)
		(end 98.61 81.91)
		(width 0.2)
		(layer "F.Cu")
		(net 191)
	)
	(segment
		(start 131.9 88.700001)
		(end 131.5 88.3)
		(width 0.15)
		(layer "F.Cu")
		(net 191)
	)
	(segment
		(start 98.61 81.91)
		(end 98.1 81.4)
		(width 0.2)
		(layer "F.Cu")
		(net 191)
	)
	(via
		(at 131.9 88.700001)
		(size 0.45)
		(drill 0.2)
		(layers "F.Cu" "B.Cu")
		(remove_unused_layers yes)
		(keep_end_layers yes)
		(zone_layer_connections)
		(net 191)
	)
	(via
		(at 98.61 84.19)
		(size 0.45)
		(drill 0.2)
		(layers "F.Cu" "B.Cu")
		(remove_unused_layers yes)
		(keep_end_layers yes)
		(zone_layer_connections)
		(net 191)
	)
	(segment
		(start 136.045 92.595)
		(end 135.145 91.695)
		(width 0.13)
		(layer "In4.Cu")
		(net 191)
	)
	(segment
		(start 98.61 84.19)
		(end 98.61 84.71)
		(width 0.13)
		(layer "In4.Cu")
		(net 191)
	)
	(segment
		(start 134.7 89.1)
		(end 132.299999 89.1)
		(width 0.13)
		(layer "In4.Cu")
		(net 191)
	)
	(segment
		(start 98.61 84.71)
		(end 99.3 85.4)
		(width 0.13)
		(layer "In4.Cu")
		(net 191)
	)
	(segment
		(start 110.145684 94.185684)
		(end 110.145683 94.185683)
		(width 0.13)
		(layer "In4.Cu")
		(net 191)
	)
	(segment
		(start 99.3 85.4)
		(end 101.36 85.4)
		(width 0.13)
		(layer "In4.Cu")
		(net 191)
	)
	(segment
		(start 115.44 99.48)
		(end 127.356187 99.48)
		(width 0.13)
		(layer "In4.Cu")
		(net 191)
	)
	(segment
		(start 127.356187 99.48)
		(end 128.536187 98.3)
		(width 0.13)
		(layer "In4.Cu")
		(net 191)
	)
	(segment
		(start 110.44046 93.608067)
		(end 110.145683 93.902841)
		(width 0.13)
		(layer "In4.Cu")
		(net 191)
	)
	(segment
		(start 109.862843 93.619999)
		(end 109.862842 93.62)
		(width 0.13)
		(layer "In4.Cu")
		(net 191)
	)
	(segment
		(start 132.299999 89.1)
		(end 131.9 88.700001)
		(width 0.13)
		(layer "In4.Cu")
		(net 191)
	)
	(segment
		(start 128.536187 98.3)
		(end 134.7 98.3)
		(width 0.13)
		(layer "In4.Cu")
		(net 191)
	)
	(segment
		(start 135.145 89.545)
		(end 134.7 89.1)
		(width 0.13)
		(layer "In4.Cu")
		(net 191)
	)
	(segment
		(start 110.145683 94.185683)
		(end 115.44 99.48)
		(width 0.13)
		(layer "In4.Cu")
		(net 191)
	)
	(segment
		(start 101.36 85.4)
		(end 109.58 93.62)
		(width 0.13)
		(layer "In4.Cu")
		(net 191)
	)
	(segment
		(start 135.145 91.695)
		(end 135.145 89.545)
		(width 0.13)
		(layer "In4.Cu")
		(net 191)
	)
	(segment
		(start 110.440459 93.608068)
		(end 110.44046 93.608067)
		(width 0.13)
		(layer "In4.Cu")
		(net 191)
	)
	(segment
		(start 136.045 96.955)
		(end 136.045 92.595)
		(width 0.13)
		(layer "In4.Cu")
		(net 191)
	)
	(segment
		(start 109.862842 93.62)
		(end 110.157618 93.325225)
		(width 0.13)
		(layer "In4.Cu")
		(net 191)
	)
	(segment
		(start 134.7 98.3)
		(end 136.045 96.955)
		(width 0.13)
		(layer "In4.Cu")
		(net 191)
	)
	(segment
		(start 110.440461 93.325226)
		(end 110.44046 93.325225)
		(width 0.13)
		(layer "In4.Cu")
		(net 191)
	)
	(arc
		(start 110.145683 93.902841)
		(mid 110.087105 94.044263)
		(end 110.145684 94.185684)
		(width 0.13)
		(layer "In4.Cu")
		(net 191)
	)
	(arc
		(start 109.58 93.62)
		(mid 109.721422 93.678578)
		(end 109.862843 93.619999)
		(width 0.13)
		(layer "In4.Cu")
		(net 191)
	)
	(arc
		(start 110.44046 93.325225)
		(mid 110.499038 93.466647)
		(end 110.440459 93.608068)
		(width 0.13)
		(layer "In4.Cu")
		(net 191)
	)
	(arc
		(start 110.157618 93.325225)
		(mid 110.29904 93.266647)
		(end 110.440461 93.325226)
		(width 0.13)
		(layer "In4.Cu")
		(net 191)
	)
	(segment
		(start 132.3 88.3)
		(end 132.7 88.7)
		(width 0.2)
		(layer "F.Cu")
		(net 192)
	)
	(segment
		(start 98.09 83.78)
		(end 98.09 82.41)
		(width 0.2)
		(layer "F.Cu")
		(net 192)
	)
	(via
		(at 132.7 88.7)
		(size 0.45)
		(drill 0.2)
		(layers "F.Cu" "B.Cu")
		(remove_unused_layers yes)
		(keep_end_layers yes)
		(zone_layer_connections)
		(net 192)
	)
	(via
		(at 98.09 83.78)
		(size 0.45)
		(drill 0.2)
		(layers "F.Cu" "B.Cu")
		(remove_unused_layers yes)
		(keep_end_layers yes)
		(zone_layer_connections)
		(net 192)
	)
	(segment
		(start 130.076973 98.6)
		(end 135.3 98.6)
		(width 0.13)
		(layer "In4.Cu")
		(net 192)
	)
	(segment
		(start 98.786141 85.886141)
		(end 100.38 85.886141)
		(width 0.13)
		(layer "In4.Cu")
		(net 192)
	)
	(segment
		(start 136.15 90.895527)
		(end 136.15 89.95)
		(width 0.13)
		(layer "In4.Cu")
		(net 192)
	)
	(segment
		(start 125.525 99.75)
		(end 126.225 100.45)
		(width 0.13)
		(layer "In4.Cu")
		(net 192)
	)
	(segment
		(start 98.09 85.19)
		(end 98.786141 85.886141)
		(width 0.13)
		(layer "In4.Cu")
		(net 192)
	)
	(segment
		(start 114.593859 100.1)
		(end 122.8 100.1)
		(width 0.13)
		(layer "In4.Cu")
		(net 192)
	)
	(segment
		(start 126.225 100.45)
		(end 128.226973 100.45)
		(width 0.13)
		(layer "In4.Cu")
		(net 192)
	)
	(segment
		(start 122.8 100.1)
		(end 123.15 99.75)
		(width 0.13)
		(layer "In4.Cu")
		(net 192)
	)
	(segment
		(start 136.15 89.95)
		(end 134.9 88.7)
		(width 0.13)
		(layer "In4.Cu")
		(net 192)
	)
	(segment
		(start 136.515 91.260527)
		(end 136.15 90.895527)
		(width 0.13)
		(layer "In4.Cu")
		(net 192)
	)
	(segment
		(start 134.9 88.7)
		(end 132.7 88.7)
		(width 0.13)
		(layer "In4.Cu")
		(net 192)
	)
	(segment
		(start 100.38 85.886141)
		(end 114.593859 100.1)
		(width 0.13)
		(layer "In4.Cu")
		(net 192)
	)
	(segment
		(start 123.15 99.75)
		(end 125.525 99.75)
		(width 0.13)
		(layer "In4.Cu")
		(net 192)
	)
	(segment
		(start 135.3 98.6)
		(end 136.515 97.385)
		(width 0.13)
		(layer "In4.Cu")
		(net 192)
	)
	(segment
		(start 128.226973 100.45)
		(end 130.076973 98.6)
		(width 0.13)
		(layer "In4.Cu")
		(net 192)
	)
	(segment
		(start 98.09 83.78)
		(end 98.09 85.19)
		(width 0.13)
		(layer "In4.Cu")
		(net 192)
	)
	(segment
		(start 136.515 97.385)
		(end 136.515 91.260527)
		(width 0.13)
		(layer "In4.Cu")
		(net 192)
	)
	(segment
		(start 123.899999 91.1)
		(end 124.3 90.7)
		(width 0.15)
		(layer "F.Cu")
		(net 193)
	)
	(segment
		(start 98.5 79)
		(end 98.1 79.4)
		(width 0.15)
		(layer "F.Cu")
		(net 193)
	)
	(via
		(at 123.899999 91.1)
		(size 0.45)
		(drill 0.2)
		(layers "F.Cu" "B.Cu")
		(remove_unused_layers yes)
		(keep_end_layers yes)
		(free yes)
		(zone_layer_connections)
		(net 193)
	)
	(via
		(at 113.7 91.7)
		(size 0.45)
		(drill 0.2)
		(layers "F.Cu" "B.Cu")
		(net 193)
	)
	(via
		(at 98.5 79)
		(size 0.45)
		(drill 0.2)
		(layers "F.Cu" "B.Cu")
		(remove_unused_layers yes)
		(keep_end_layers yes)
		(zone_layer_connections)
		(net 193)
	)
	(segment
		(start 100.7408 87.9408)
		(end 100.7408 88.95)
		(width 0.15)
		(layer "B.Cu")
		(net 193)
	)
	(segment
		(start 100.12 81.42)
		(end 100.12 87.32)
		(width 0.15)
		(layer "B.Cu")
		(net 193)
	)
	(segment
		(start 98.5 79)
		(end 98.5 79.38536)
		(width 0.15)
		(layer "B.Cu")
		(net 193)
	)
	(segment
		(start 113.7 90)
		(end 113.7 91.7)
		(width 0.125)
		(layer "B.Cu")
		(net 193)
	)
	(segment
		(start 113.28 89.58)
		(end 113.7 90)
		(width 0.125)
		(layer "B.Cu")
		(net 193)
	)
	(segment
		(start 100.12 87.32)
		(end 100.7408 87.9408)
		(width 0.15)
		(layer "B.Cu")
		(net 193)
	)
	(segment
		(start 98.5 79.38536)
		(end 98.79 79.67536)
		(width 0.15)
		(layer "B.Cu")
		(net 193)
	)
	(segment
		(start 101.3454 89.5546)
		(end 101.3708 89.58)
		(width 0.125)
		(layer "B.Cu")
		(net 193)
	)
	(segment
		(start 101.3708 89.58)
		(end 113.28 89.58)
		(width 0.125)
		(layer "B.Cu")
		(net 193)
	)
	(segment
		(start 98.79 79.67536)
		(end 98.79 80.09)
		(width 0.15)
		(layer "B.Cu")
		(net 193)
	)
	(segment
		(start 98.79 80.09)
		(end 100.12 81.42)
		(width 0.15)
		(layer "B.Cu")
		(net 193)
	)
	(segment
		(start 101.3454 89.5546)
		(end 100.7408 88.95)
		(width 0.15)
		(layer "B.Cu")
		(net 193)
	)
	(segment
		(start 123.899999 91.1)
		(end 123.499999 91.5)
		(width 0.125)
		(layer "In2.Cu")
		(net 193)
	)
	(segment
		(start 113.9 91.5)
		(end 123.499999 91.5)
		(width 0.125)
		(layer "In2.Cu")
		(net 193)
	)
	(segment
		(start 113.9 91.5)
		(end 113.7 91.7)
		(width 0.125)
		(layer "In2.Cu")
		(net 193)
	)
	(segment
		(start 101.84 80.42)
		(end 100.12 80.42)
		(width 0.2)
		(layer "F.Cu")
		(net 194)
	)
	(segment
		(start 132.714022 91.1)
		(end 132.7 91.1)
		(width 0.15)
		(layer "F.Cu")
		(net 194)
	)
	(segment
		(start 132.7 91.1)
		(end 132.3 90.7)
		(width 0.15)
		(layer "F.Cu")
		(net 194)
	)
	(via
		(at 101.84 80.42)
		(size 0.45)
		(drill 0.2)
		(layers "F.Cu" "B.Cu")
		(remove_unused_layers yes)
		(keep_end_layers yes)
		(zone_layer_connections)
		(net 194)
	)
	(via
		(at 132.714022 91.1)
		(size 0.45)
		(drill 0.2)
		(layers "F.Cu" "B.Cu")
		(remove_unused_layers yes)
		(keep_end_layers yes)
		(zone_layer_connections)
		(net 194)
	)
	(segment
		(start 110.99 80.49)
		(end 111.406795 80.49)
		(width 0.13)
		(layer "In4.Cu")
		(net 194)
	)
	(segment
		(start 133 91.5)
		(end 133 91.25)
		(width 0.13)
		(layer "In4.Cu")
		(net 194)
	)
	(segment
		(start 107.59 80.42)
		(end 108.62 79.39)
		(width 0.13)
		(layer "In4.Cu")
		(net 194)
	)
	(segment
		(start 123.9 95.95)
		(end 124.4 96.45)
		(width 0.13)
		(layer "In4.Cu")
		(net 194)
	)
	(segment
		(start 118.55 95.95)
		(end 123.9 95.95)
		(width 0.13)
		(layer "In4.Cu")
		(net 194)
	)
	(segment
		(start 126.294473 96.45)
		(end 126.844473 95.9)
		(width 0.13)
		(layer "In4.Cu")
		(net 194)
	)
	(segment
		(start 111.07 75.66)
		(end 111.73 76.32)
		(width 0.13)
		(layer "In4.Cu")
		(net 194)
	)
	(segment
		(start 110.173205 80.89)
		(end 111.406795 80.89)
		(width 0.13)
		(layer "In4.Cu")
		(net 194)
	)
	(segment
		(start 101.84 80.42)
		(end 107.59 80.42)
		(width 0.13)
		(layer "In4.Cu")
		(net 194)
	)
	(segment
		(start 132.75 94.8)
		(end 132.75 94.15)
		(width 0.13)
		(layer "In4.Cu")
		(net 194)
	)
	(segment
		(start 132.75 94.15)
		(end 133.15 93.75)
		(width 0.13)
		(layer "In4.Cu")
		(net 194)
	)
	(segment
		(start 130.65 95.55)
		(end 132 95.55)
		(width 0.13)
		(layer "In4.Cu")
		(net 194)
	)
	(segment
		(start 132.85 91.1)
		(end 132.714022 91.1)
		(width 0.13)
		(layer "In4.Cu")
		(net 194)
	)
	(segment
		(start 133.15 91.65)
		(end 133 91.5)
		(width 0.13)
		(layer "In4.Cu")
		(net 194)
	)
	(segment
		(start 133 91.25)
		(end 132.85 91.1)
		(width 0.13)
		(layer "In4.Cu")
		(net 194)
	)
	(segment
		(start 111.73 78.823456)
		(end 111.74 78.833456)
		(width 0.13)
		(layer "In4.Cu")
		(net 194)
	)
	(segment
		(start 124.4 96.45)
		(end 126.294473 96.45)
		(width 0.13)
		(layer "In4.Cu")
		(net 194)
	)
	(segment
		(start 108.62 79.39)
		(end 108.62 76.28)
		(width 0.13)
		(layer "In4.Cu")
		(net 194)
	)
	(segment
		(start 109.24 75.66)
		(end 111.07 75.66)
		(width 0.13)
		(layer "In4.Cu")
		(net 194)
	)
	(segment
		(start 130.3 95.9)
		(end 130.65 95.55)
		(width 0.13)
		(layer "In4.Cu")
		(net 194)
	)
	(segment
		(start 110.79 88.19)
		(end 118.55 95.95)
		(width 0.13)
		(layer "In4.Cu")
		(net 194)
	)
	(segment
		(start 111.74 78.833456)
		(end 110.79 79.783456)
		(width 0.13)
		(layer "In4.Cu")
		(net 194)
	)
	(segment
		(start 111.73 76.32)
		(end 111.73 78.823456)
		(width 0.13)
		(layer "In4.Cu")
		(net 194)
	)
	(segment
		(start 133.15 93.75)
		(end 133.15 91.65)
		(width 0.13)
		(layer "In4.Cu")
		(net 194)
	)
	(segment
		(start 126.844473 95.9)
		(end 130.3 95.9)
		(width 0.13)
		(layer "In4.Cu")
		(net 194)
	)
	(segment
		(start 108.62 76.28)
		(end 109.24 75.66)
		(width 0.13)
		(layer "In4.Cu")
		(net 194)
	)
	(segment
		(start 111.406795 81.69)
		(end 110.99 81.69)
		(width 0.13)
		(layer "In4.Cu")
		(net 194)
	)
	(segment
		(start 110.79 79.783456)
		(end 110.79 80.29)
		(width 0.13)
		(layer "In4.Cu")
		(net 194)
	)
	(segment
		(start 132 95.55)
		(end 132.75 94.8)
		(width 0.13)
		(layer "In4.Cu")
		(net 194)
	)
	(segment
		(start 110.79 81.89)
		(end 110.79 88.19)
		(width 0.13)
		(layer "In4.Cu")
		(net 194)
	)
	(segment
		(start 110.173205 81.29)
		(end 111.406795 81.29)
		(width 0.13)
		(layer "In4.Cu")
		(net 194)
	)
	(arc
		(start 111.406795 80.49)
		(mid 111.548216 80.548579)
		(end 111.606795 80.69)
		(width 0.13)
		(layer "In4.Cu")
		(net 194)
	)
	(arc
		(start 111.406795 81.29)
		(mid 111.548216 81.348579)
		(end 111.606795 81.49)
		(width 0.13)
		(layer "In4.Cu")
		(net 194)
	)
	(arc
		(start 109.973205 81.09)
		(mid 110.031784 81.231421)
		(end 110.173205 81.29)
		(width 0.13)
		(layer "In4.Cu")
		(net 194)
	)
	(arc
		(start 111.606795 81.49)
		(mid 111.548216 81.631421)
		(end 111.406795 81.69)
		(width 0.13)
		(layer "In4.Cu")
		(net 194)
	)
	(arc
		(start 110.99 81.69)
		(mid 110.848579 81.748579)
		(end 110.79 81.89)
		(width 0.13)
		(layer "In4.Cu")
		(net 194)
	)
	(arc
		(start 111.606795 80.69)
		(mid 111.548216 80.831421)
		(end 111.406795 80.89)
		(width 0.13)
		(layer "In4.Cu")
		(net 194)
	)
	(arc
		(start 110.173205 80.89)
		(mid 110.031784 80.948579)
		(end 109.973205 81.09)
		(width 0.13)
		(layer "In4.Cu")
		(net 194)
	)
	(arc
		(start 110.79 80.29)
		(mid 110.848579 80.431421)
		(end 110.99 80.49)
		(width 0.13)
		(layer "In4.Cu")
		(net 194)
	)
	(segment
		(start 101.93 77.88)
		(end 99.62 77.88)
		(width 0.2)
		(layer "F.Cu")
		(net 195)
	)
	(segment
		(start 130.3 90.3)
		(end 129.9 90.7)
		(width 0.182)
		(layer "F.Cu")
		(net 195)
	)
	(segment
		(start 99.62 77.88)
		(end 99.1 78.4)
		(width 0.2)
		(layer "F.Cu")
		(net 195)
	)
	(via
		(at 101.93 77.88)
		(size 0.45)
		(drill 0.2)
		(layers "F.Cu" "B.Cu")
		(remove_unused_layers yes)
		(keep_end_layers yes)
		(zone_layer_connections)
		(net 195)
	)
	(via
		(at 130.3 90.3)
		(size 0.45)
		(drill 0.2)
		(layers "F.Cu" "B.Cu")
		(remove_unused_layers yes)
		(keep_end_layers yes)
		(zone_layer_connections)
		(net 195)
	)
	(segment
		(start 112.75 85.875)
		(end 112.75 85.925)
		(width 0.13)
		(layer "In4.Cu")
		(net 195)
	)
	(segment
		(start 112.925 86.1)
		(end 113.65 86.1)
		(width 0.13)
		(layer "In4.Cu")
		(net 195)
	)
	(segment
		(start 112.925 84.9)
		(end 113.65 84.9)
		(width 0.13)
		(layer "In4.Cu")
		(net 195)
	)
	(segment
		(start 113.3 82.9)
		(end 113.65 82.9)
		(width 0.13)
		(layer "In4.Cu")
		(net 195)
	)
	(segment
		(start 113.1 75.13)
		(end 113.1 82.7)
		(width 0.13)
		(layer "In4.Cu")
		(net 195)
	)
	(segment
		(start 108.13 73.56)
		(end 111.53 73.56)
		(width 0.13)
		(layer "In4.Cu")
		(net 195)
	)
	(segment
		(start 101.93 78.43)
		(end 102.1 78.6)
		(width 0.13)
		(layer "In4.Cu")
		(net 195)
	)
	(segment
		(start 107.5 74.19)
		(end 108.13 73.56)
		(width 0.13)
		(layer "In4.Cu")
		(net 195)
	)
	(segment
		(start 129.108235 92.911765)
		(end 129.108235 92.547292)
		(width 0.13)
		(layer "In4.Cu")
		(net 195)
	)
	(segment
		(start 113.1 88.63)
		(end 117.578234 93.108234)
		(width 0.13)
		(layer "In4.Cu")
		(net 195)
	)
	(segment
		(start 112.925 83.7)
		(end 113.65 83.7)
		(width 0.13)
		(layer "In4.Cu")
		(net 195)
	)
	(segment
		(start 129.108235 92.547292)
		(end 129.340527 92.315)
		(width 0.13)
		(layer "In4.Cu")
		(net 195)
	)
	(segment
		(start 112.925 83.3)
		(end 113.65 83.3)
		(width 0.13)
		(layer "In4.Cu")
		(net 195)
	)
	(segment
		(start 102.1 78.6)
		(end 106.9 78.6)
		(width 0.13)
		(layer "In4.Cu")
		(net 195)
	)
	(segment
		(start 112.925 84.1)
		(end 113.65 84.1)
		(width 0.13)
		(layer "In4.Cu")
		(net 195)
	)
	(segment
		(start 101.93 77.88)
		(end 101.93 78.43)
		(width 0.13)
		(layer "In4.Cu")
		(net 195)
	)
	(segment
		(start 129.90851 92.065963)
		(end 129.90851 90.89149)
		(width 0.13)
		(layer "In4.Cu")
		(net 195)
	)
	(segment
		(start 129.90851 90.89149)
		(end 130.3 90.5)
		(width 0.13)
		(layer "In4.Cu")
		(net 195)
	)
	(segment
		(start 129.659473 92.315)
		(end 129.90851 92.065963)
		(width 0.13)
		(layer "In4.Cu")
		(net 195)
	)
	(segment
		(start 112.925 84.5)
		(end 113.65 84.5)
		(width 0.13)
		(layer "In4.Cu")
		(net 195)
	)
	(segment
		(start 111.53 73.56)
		(end 113.1 75.13)
		(width 0.13)
		(layer "In4.Cu")
		(net 195)
	)
	(segment
		(start 129.340527 92.315)
		(end 129.659473 92.315)
		(width 0.13)
		(layer "In4.Cu")
		(net 195)
	)
	(segment
		(start 128.911766 93.108234)
		(end 129.108235 92.911765)
		(width 0.13)
		(layer "In4.Cu")
		(net 195)
	)
	(segment
		(start 113.1 86.7)
		(end 113.1 88.63)
		(width 0.13)
		(layer "In4.Cu")
		(net 195)
	)
	(segment
		(start 112.925 85.3)
		(end 113.65 85.3)
		(width 0.13)
		(layer "In4.Cu")
		(net 195)
	)
	(segment
		(start 113.65 86.5)
		(end 113.3 86.5)
		(width 0.13)
		(layer "In4.Cu")
		(net 195)
	)
	(segment
		(start 106.9 78.6)
		(end 107.5 78)
		(width 0.13)
		(layer "In4.Cu")
		(net 195)
	)
	(segment
		(start 112.75 84.275)
		(end 112.75 84.325)
		(width 0.13)
		(layer "In4.Cu")
		(net 195)
	)
	(segment
		(start 130.3 90.5)
		(end 130.3 90.3)
		(width 0.13)
		(layer "In4.Cu")
		(net 195)
	)
	(segment
		(start 112.75 83.475)
		(end 112.75 83.525)
		(width 0.13)
		(layer "In4.Cu")
		(net 195)
	)
	(segment
		(start 112.925 85.7)
		(end 113.65 85.7)
		(width 0.13)
		(layer "In4.Cu")
		(net 195)
	)
	(segment
		(start 117.578234 93.108234)
		(end 128.911766 93.108234)
		(width 0.13)
		(layer "In4.Cu")
		(net 195)
	)
	(segment
		(start 107.5 78)
		(end 107.5 74.19)
		(width 0.13)
		(layer "In4.Cu")
		(net 195)
	)
	(segment
		(start 112.75 85.075)
		(end 112.75 85.125)
		(width 0.13)
		(layer "In4.Cu")
		(net 195)
	)
	(arc
		(start 112.75 85.125)
		(mid 112.801256 85.248744)
		(end 112.925 85.3)
		(width 0.13)
		(layer "In4.Cu")
		(net 195)
	)
	(arc
		(start 113.85 85.5)
		(mid 113.791421 85.641421)
		(end 113.65 85.7)
		(width 0.13)
		(layer "In4.Cu")
		(net 195)
	)
	(arc
		(start 113.85 86.3)
		(mid 113.791421 86.441421)
		(end 113.65 86.5)
		(width 0.13)
		(layer "In4.Cu")
		(net 195)
	)
	(arc
		(start 113.3 86.5)
		(mid 113.158579 86.558579)
		(end 113.1 86.7)
		(width 0.13)
		(layer "In4.Cu")
		(net 195)
	)
	(arc
		(start 112.925 84.9)
		(mid 112.801256 84.951256)
		(end 112.75 85.075)
		(width 0.13)
		(layer "In4.Cu")
		(net 195)
	)
	(arc
		(start 112.925 84.1)
		(mid 112.801256 84.151256)
		(end 112.75 84.275)
		(width 0.13)
		(layer "In4.Cu")
		(net 195)
	)
	(arc
		(start 112.75 85.925)
		(mid 112.801256 86.048744)
		(end 112.925 86.1)
		(width 0.13)
		(layer "In4.Cu")
		(net 195)
	)
	(arc
		(start 113.65 84.5)
		(mid 113.791421 84.558579)
		(end 113.85 84.7)
		(width 0.13)
		(layer "In4.Cu")
		(net 195)
	)
	(arc
		(start 113.65 82.9)
		(mid 113.791421 82.958579)
		(end 113.85 83.1)
		(width 0.13)
		(layer "In4.Cu")
		(net 195)
	)
	(arc
		(start 112.925 85.7)
		(mid 112.801256 85.751256)
		(end 112.75 85.875)
		(width 0.13)
		(layer "In4.Cu")
		(net 195)
	)
	(arc
		(start 113.65 85.3)
		(mid 113.791421 85.358579)
		(end 113.85 85.5)
		(width 0.13)
		(layer "In4.Cu")
		(net 195)
	)
	(arc
		(start 113.85 83.9)
		(mid 113.791421 84.041421)
		(end 113.65 84.1)
		(width 0.13)
		(layer "In4.Cu")
		(net 195)
	)
	(arc
		(start 113.65 86.1)
		(mid 113.791421 86.158579)
		(end 113.85 86.3)
		(width 0.13)
		(layer "In4.Cu")
		(net 195)
	)
	(arc
		(start 112.75 84.325)
		(mid 112.801256 84.448744)
		(end 112.925 84.5)
		(width 0.13)
		(layer "In4.Cu")
		(net 195)
	)
	(arc
		(start 113.85 84.7)
		(mid 113.791421 84.841421)
		(end 113.65 84.9)
		(width 0.13)
		(layer "In4.Cu")
		(net 195)
	)
	(arc
		(start 113.85 83.1)
		(mid 113.791421 83.241421)
		(end 113.65 83.3)
		(width 0.13)
		(layer "In4.Cu")
		(net 195)
	)
	(arc
		(start 113.65 83.7)
		(mid 113.791421 83.758579)
		(end 113.85 83.9)
		(width 0.13)
		(layer "In4.Cu")
		(net 195)
	)
	(arc
		(start 112.925 83.3)
		(mid 112.801256 83.351256)
		(end 112.75 83.475)
		(width 0.13)
		(layer "In4.Cu")
		(net 195)
	)
	(arc
		(start 113.1 82.7)
		(mid 113.158579 82.841421)
		(end 113.3 82.9)
		(width 0.13)
		(layer "In4.Cu")
		(net 195)
	)
	(arc
		(start 112.75 83.525)
		(mid 112.801256 83.648744)
		(end 112.925 83.7)
		(width 0.13)
		(layer "In4.Cu")
		(net 195)
	)
	(segment
		(start 130.7 88.3)
		(end 131.1 88.7)
		(width 0.2)
		(layer "F.Cu")
		(net 196)
	)
	(segment
		(start 99.611644 80.911644)
		(end 99.1 80.4)
		(width 0.2)
		(layer "F.Cu")
		(net 196)
	)
	(segment
		(start 101.449307 80.911644)
		(end 99.611644 80.911644)
		(width 0.2)
		(layer "F.Cu")
		(net 196)
	)
	(via
		(at 131.1 88.7)
		(size 0.45)
		(drill 0.1)
		(layers "F.Cu" "B.Cu")
		(net 196)
	)
	(via
		(at 101.449307 80.911644)
		(size 0.45)
		(drill 0.2)
		(layers "F.Cu" "B.Cu")
		(remove_unused_layers yes)
		(keep_end_layers yes)
		(zone_layer_connections)
		(net 196)
	)
	(segment
		(start 109.145 93.437842)
		(end 108.756587 93.826254)
		(width 0.13)
		(layer "In2.Cu")
		(net 196)
	)
	(segment
		(start 110.170798 95.240466)
		(end 111.124398 94.286863)
		(width 0.13)
		(layer "In2.Cu")
		(net 196)
	)
	(segment
		(start 109.605113 94.674781)
		(end 110.558713 93.721178)
		(width 0.13)
		(layer "In2.Cu")
		(net 196)
	)
	(segment
		(start 102.56 80.82)
		(end 103.92 82.18)
		(width 0.13)
		(layer "In2.Cu")
		(net 196)
	)
	(segment
		(start 108.756588 94.109097)
		(end 108.756587 94.109097)
		(width 0.13)
		(layer "In2.Cu")
		(net 196)
	)
	(segment
		(start 110.275871 93.438337)
		(end 110.275872 93.438336)
		(width 0.13)
		(layer "In2.Cu")
		(net 196)
	)
	(segment
		(start 111.407243 94.286864)
		(end 111.407242 94.286864)
		(width 0.13)
		(layer "In2.Cu")
		(net 196)
	)
	(segment
		(start 110.275873 93.155494)
		(end 110.275872 93.155494)
		(width 0.13)
		(layer "In2.Cu")
		(net 196)
	)
	(segment
		(start 109.32227 94.674781)
		(end 109.322271 94.674781)
		(width 0.13)
		(layer "In2.Cu")
		(net 196)
	)
	(segment
		(start 103.92 87.93)
		(end 109.145 93.155)
		(width 0.13)
		(layer "In2.Cu")
		(net 196)
	)
	(segment
		(start 132.829473 89.085)
		(end 131.485 89.085)
		(width 0.13)
		(layer "In2.Cu")
		(net 196)
	)
	(segment
		(start 110.170799 95.240465)
		(end 110.170798 95.240466)
		(width 0.13)
		(layer "In2.Cu")
		(net 196)
	)
	(segment
		(start 131.485 89.085)
		(end 131.1 88.7)
		(width 0.13)
		(layer "In2.Cu")
		(net 196)
	)
	(segment
		(start 111.124897 95.134896)
		(end 111.124895 95.134895)
		(width 0.13)
		(layer "In2.Cu")
		(net 196)
	)
	(segment
		(start 103.92 82.18)
		(end 103.92 87.93)
		(width 0.13)
		(layer "In2.Cu")
		(net 196)
	)
	(segment
		(start 109.887955 95.240466)
		(end 109.887956 95.240466)
		(width 0.13)
		(layer "In2.Cu")
		(net 196)
	)
	(segment
		(start 114.85 98.86)
		(end 125.45 98.86)
		(width 0.13)
		(layer "In2.Cu")
		(net 196)
	)
	(segment
		(start 111.407241 94.569707)
		(end 111.407242 94.569706)
		(width 0.13)
		(layer "In2.Cu")
		(net 196)
	)
	(segment
		(start 109.605114 94.67478)
		(end 109.605113 94.674781)
		(width 0.13)
		(layer "In2.Cu")
		(net 196)
	)
	(segment
		(start 110.841556 94.004022)
		(end 110.841557 94.004021)
		(width 0.13)
		(layer "In2.Cu")
		(net 196)
	)
	(segment
		(start 133.21 94.82)
		(end 133.21 89.465527)
		(width 0.13)
		(layer "In2.Cu")
		(net 196)
	)
	(segment
		(start 110.841558 93.721179)
		(end 110.841557 93.721179)
		(width 0.13)
		(layer "In2.Cu")
		(net 196)
	)
	(segment
		(start 111.407242 94.569706)
		(end 111.124896 94.852053)
		(width 0.13)
		(layer "In2.Cu")
		(net 196)
	)
	(segment
		(start 101.449307 80.911644)
		(end 101.540951 80.82)
		(width 0.13)
		(layer "In2.Cu")
		(net 196)
	)
	(segment
		(start 111.124895 95.134895)
		(end 114.85 98.86)
		(width 0.13)
		(layer "In2.Cu")
		(net 196)
	)
	(segment
		(start 110.275872 93.438336)
		(end 109.322271 94.391938)
		(width 0.13)
		(layer "In2.Cu")
		(net 196)
	)
	(segment
		(start 109.144999 93.437843)
		(end 109.145 93.437842)
		(width 0.13)
		(layer "In2.Cu")
		(net 196)
	)
	(segment
		(start 130.104731 95.68)
		(end 132.35 95.68)
		(width 0.13)
		(layer "In2.Cu")
		(net 196)
	)
	(segment
		(start 127.23 97.08)
		(end 128.70473 97.08)
		(width 0.13)
		(layer "In2.Cu")
		(net 196)
	)
	(segment
		(start 110.841557 94.004021)
		(end 109.887956 94.957623)
		(width 0.13)
		(layer "In2.Cu")
		(net 196)
	)
	(segment
		(start 128.70473 97.08)
		(end 130.104731 95.68)
		(width 0.13)
		(layer "In2.Cu")
		(net 196)
	)
	(segment
		(start 132.35 95.68)
		(end 133.21 94.82)
		(width 0.13)
		(layer "In2.Cu")
		(net 196)
	)
	(segment
		(start 125.45 98.86)
		(end 127.23 97.08)
		(width 0.13)
		(layer "In2.Cu")
		(net 196)
	)
	(segment
		(start 101.540951 80.82)
		(end 102.56 80.82)
		(width 0.13)
		(layer "In2.Cu")
		(net 196)
	)
	(segment
		(start 109.03943 94.109096)
		(end 109.039429 94.109097)
		(width 0.13)
		(layer "In2.Cu")
		(net 196)
	)
	(segment
		(start 133.21 89.465527)
		(end 132.829473 89.085)
		(width 0.13)
		(layer "In2.Cu")
		(net 196)
	)
	(segment
		(start 109.039429 94.109097)
		(end 109.993028 93.155493)
		(width 0.13)
		(layer "In2.Cu")
		(net 196)
	)
	(arc
		(start 110.558713 93.721178)
		(mid 110.700136 93.662601)
		(end 110.841558 93.721179)
		(width 0.13)
		(layer "In2.Cu")
		(net 196)
	)
	(arc
		(start 110.275872 93.155494)
		(mid 110.33445 93.296916)
		(end 110.275871 93.438337)
		(width 0.13)
		(layer "In2.Cu")
		(net 196)
	)
	(arc
		(start 111.124896 94.852053)
		(mid 111.066318 94.993475)
		(end 111.124897 95.134896)
		(width 0.13)
		(layer "In2.Cu")
		(net 196)
	)
	(arc
		(start 108.756587 93.826254)
		(mid 108.698009 93.967676)
		(end 108.756588 94.109097)
		(width 0.13)
		(layer "In2.Cu")
		(net 196)
	)
	(arc
		(start 108.756587 94.109097)
		(mid 108.898009 94.167675)
		(end 109.03943 94.109096)
		(width 0.13)
		(layer "In2.Cu")
		(net 196)
	)
	(arc
		(start 109.145 93.155)
		(mid 109.203578 93.296422)
		(end 109.144999 93.437843)
		(width 0.13)
		(layer "In2.Cu")
		(net 196)
	)
	(arc
		(start 109.887956 94.957623)
		(mid 109.829377 95.099044)
		(end 109.887955 95.240466)
		(width 0.13)
		(layer "In2.Cu")
		(net 196)
	)
	(arc
		(start 109.322271 94.391938)
		(mid 109.263692 94.533359)
		(end 109.32227 94.674781)
		(width 0.13)
		(layer "In2.Cu")
		(net 196)
	)
	(arc
		(start 109.887956 95.240466)
		(mid 110.029378 95.299044)
		(end 110.170799 95.240465)
		(width 0.13)
		(layer "In2.Cu")
		(net 196)
	)
	(arc
		(start 110.841557 93.721179)
		(mid 110.900135 93.862601)
		(end 110.841556 94.004022)
		(width 0.13)
		(layer "In2.Cu")
		(net 196)
	)
	(arc
		(start 109.993028 93.155493)
		(mid 110.134451 93.096916)
		(end 110.275873 93.155494)
		(width 0.13)
		(layer "In2.Cu")
		(net 196)
	)
	(arc
		(start 111.407242 94.286864)
		(mid 111.46582 94.428286)
		(end 111.407241 94.569707)
		(width 0.13)
		(layer "In2.Cu")
		(net 196)
	)
	(arc
		(start 109.322271 94.674781)
		(mid 109.463693 94.733359)
		(end 109.605114 94.67478)
		(width 0.13)
		(layer "In2.Cu")
		(net 196)
	)
	(arc
		(start 111.124398 94.286863)
		(mid 111.265821 94.228286)
		(end 111.407243 94.286864)
		(width 0.13)
		(layer "In2.Cu")
		(net 196)
	)
	(segment
		(start 98.1 70.1)
		(end 98.1 73.4)
		(width 0.2)
		(layer "F.Cu")
		(net 197)
	)
	(segment
		(start 98.15 70.05)
		(end 98.1 70.1)
		(width 0.2)
		(layer "F.Cu")
		(net 197)
	)
	(segment
		(start 129.1 88.3)
		(end 128.7 88.7)
		(width 0.15)
		(layer "F.Cu")
		(net 197)
	)
	(via
		(at 128.7 88.7)
		(size 0.45)
		(drill 0.2)
		(layers "F.Cu" "B.Cu")
		(remove_unused_layers yes)
		(keep_end_layers yes)
		(zone_layer_connections)
		(net 197)
	)
	(via
		(at 98.15 70.05)
		(size 0.45)
		(drill 0.2)
		(layers "F.Cu" "B.Cu")
		(remove_unused_layers yes)
		(keep_end_layers yes)
		(zone_layer_connections)
		(net 197)
	)
	(segment
		(start 109.867932 75.68)
		(end 110.992068 75.68)
		(width 0.13)
		(layer "In2.Cu")
		(net 197)
	)
	(segment
		(start 109.867932 74.08)
		(end 110.992068 74.08)
		(width 0.13)
		(layer "In2.Cu")
		(net 197)
	)
	(segment
		(start 109.867932 74.88)
		(end 110.642068 74.88)
		(width 0.13)
		(layer "In2.Cu")
		(net 197)
	)
	(segment
		(start 109.867932 74.48)
		(end 110.992068 74.48)
		(width 0.13)
		(layer "In2.Cu")
		(net 197)
	)
	(segment
		(start 98.15 68.05)
		(end 99.5 66.7)
		(width 0.13)
		(layer "In2.Cu")
		(net 197)
	)
	(segment
		(start 109.867932 75.28)
		(end 110.642068 75.28)
		(width 0.13)
		(layer "In2.Cu")
		(net 197)
	)
	(segment
		(start 110.48 73.28)
		(end 110.992068 73.28)
		(width 0.13)
		(layer "In2.Cu")
		(net 197)
	)
	(segment
		(start 128.3 89.1)
		(end 128.7 88.7)
		(width 0.13)
		(layer "In2.Cu")
		(net 197)
	)
	(segment
		(start 109.867932 73.68)
		(end 110.992068 73.68)
		(width 0.13)
		(layer "In2.Cu")
		(net 197)
	)
	(segment
		(start 110.28 83.623495)
		(end 115.756504 89.1)
		(width 0.13)
		(layer "In2.Cu")
		(net 197)
	)
	(segment
		(start 115.756504 89.1)
		(end 128.3 89.1)
		(width 0.13)
		(layer "In2.Cu")
		(net 197)
	)
	(segment
		(start 110.28 76.28)
		(end 110.28 83.623495)
		(width 0.13)
		(layer "In2.Cu")
		(net 197)
	)
	(segment
		(start 98.15 70.05)
		(end 98.15 68.05)
		(width 0.13)
		(layer "In2.Cu")
		(net 197)
	)
	(segment
		(start 108.5 66.7)
		(end 110.28 68.48)
		(width 0.13)
		(layer "In2.Cu")
		(net 197)
	)
	(segment
		(start 110.28 68.48)
		(end 110.28 73.08)
		(width 0.13)
		(layer "In2.Cu")
		(net 197)
	)
	(segment
		(start 99.5 66.7)
		(end 108.5 66.7)
		(width 0.13)
		(layer "In2.Cu")
		(net 197)
	)
	(segment
		(start 110.992068 76.08)
		(end 110.48 76.08)
		(width 0.13)
		(layer "In2.Cu")
		(net 197)
	)
	(arc
		(start 111.192068 74.28)
		(mid 111.133489 74.421421)
		(end 110.992068 74.48)
		(width 0.13)
		(layer "In2.Cu")
		(net 197)
	)
	(arc
		(start 110.842068 75.08)
		(mid 110.783489 75.221421)
		(end 110.642068 75.28)
		(width 0.13)
		(layer "In2.Cu")
		(net 197)
	)
	(arc
		(start 110.48 76.08)
		(mid 110.338579 76.138579)
		(end 110.28 76.28)
		(width 0.13)
		(layer "In2.Cu")
		(net 197)
	)
	(arc
		(start 109.667932 74.68)
		(mid 109.726511 74.821421)
		(end 109.867932 74.88)
		(width 0.13)
		(layer "In2.Cu")
		(net 197)
	)
	(arc
		(start 111.192068 75.88)
		(mid 111.133489 76.021421)
		(end 110.992068 76.08)
		(width 0.13)
		(layer "In2.Cu")
		(net 197)
	)
	(arc
		(start 110.642068 74.88)
		(mid 110.783489 74.938579)
		(end 110.842068 75.08)
		(width 0.13)
		(layer "In2.Cu")
		(net 197)
	)
	(arc
		(start 111.192068 73.48)
		(mid 111.133489 73.621421)
		(end 110.992068 73.68)
		(width 0.13)
		(layer "In2.Cu")
		(net 197)
	)
	(arc
		(start 109.867932 74.48)
		(mid 109.726511 74.538579)
		(end 109.667932 74.68)
		(width 0.13)
		(layer "In2.Cu")
		(net 197)
	)
	(arc
		(start 110.992068 73.28)
		(mid 111.133489 73.338579)
		(end 111.192068 73.48)
		(width 0.13)
		(layer "In2.Cu")
		(net 197)
	)
	(arc
		(start 109.667932 73.88)
		(mid 109.726511 74.021421)
		(end 109.867932 74.08)
		(width 0.13)
		(layer "In2.Cu")
		(net 197)
	)
	(arc
		(start 110.992068 75.68)
		(mid 111.133489 75.738579)
		(end 111.192068 75.88)
		(width 0.13)
		(layer "In2.Cu")
		(net 197)
	)
	(arc
		(start 109.867932 75.28)
		(mid 109.726511 75.338579)
		(end 109.667932 75.48)
		(width 0.13)
		(layer "In2.Cu")
		(net 197)
	)
	(arc
		(start 109.667932 75.48)
		(mid 109.726511 75.621421)
		(end 109.867932 75.68)
		(width 0.13)
		(layer "In2.Cu")
		(net 197)
	)
	(arc
		(start 109.867932 73.68)
		(mid 109.726511 73.738579)
		(end 109.667932 73.88)
		(width 0.13)
		(layer "In2.Cu")
		(net 197)
	)
	(arc
		(start 110.28 73.08)
		(mid 110.338579 73.221421)
		(end 110.48 73.28)
		(width 0.13)
		(layer "In2.Cu")
		(net 197)
	)
	(arc
		(start 110.992068 74.08)
		(mid 111.133489 74.138579)
		(end 111.192068 74.28)
		(width 0.13)
		(layer "In2.Cu")
		(net 197)
	)
	(segment
		(start 93.134498 80.424498)
		(end 93.510523 80.424498)
		(width 0.15)
		(layer "F.Cu")
		(net 198)
	)
	(via
		(at 93.510523 80.424498)
		(size 0.45)
		(drill 0.2)
		(layers "F.Cu" "B.Cu")
		(remove_unused_layers yes)
		(keep_end_layers yes)
		(zone_layer_connections)
		(net 198)
	)
	(segment
		(start 96.914314 89.5)
		(end 93.74 89.5)
		(width 0.15)
		(layer "B.Cu")
		(net 198)
	)
	(segment
		(start 97.75 89.75)
		(end 97.45 89.45)
		(width 0.15)
		(layer "B.Cu")
		(net 198)
	)
	(segment
		(start 94.735 93.25)
		(end 94.735 92.265)
		(width 0.15)
		(layer "B.Cu")
		(net 198)
	)
	(segment
		(start 93.510523 80.424498)
		(end 93.510523 82.279477)
		(width 0.15)
		(layer "B.Cu")
		(net 198)
	)
	(segment
		(start 93.74 89.5)
		(end 93.19 88.95)
		(width 0.15)
		(layer "B.Cu")
		(net 198)
	)
	(segment
		(start 94.75 92.25)
		(end 96.25 92.25)
		(width 0.15)
		(layer "B.Cu")
		(net 198)
	)
	(segment
		(start 96.25 92.25)
		(end 97.75 90.75)
		(width 0.15)
		(layer "B.Cu")
		(net 198)
	)
	(segment
		(start 97.45 89.45)
		(end 96.964314 89.45)
		(width 0.15)
		(layer "B.Cu")
		(net 198)
	)
	(segment
		(start 93.2 82.59)
		(end 93.2 88.94)
		(width 0.15)
		(layer "B.Cu")
		(net 198)
	)
	(segment
		(start 97.75 90.75)
		(end 97.75 89.75)
		(width 0.15)
		(layer "B.Cu")
		(net 198)
	)
	(segment
		(start 93.510523 82.279477)
		(end 93.2 82.59)
		(width 0.15)
		(layer "B.Cu")
		(net 198)
	)
	(segment
		(start 96.964314 89.45)
		(end 96.914314 89.5)
		(width 0.15)
		(layer "B.Cu")
		(net 198)
	)
	(segment
		(start 122.3 91.1)
		(end 122.7 90.7)
		(width 0.15)
		(layer "F.Cu")
		(net 199)
	)
	(segment
		(start 98.1 80.41)
		(end 98.59 80.9)
		(width 0.15)
		(layer "F.Cu")
		(net 199)
	)
	(via
		(at 122.3 91.1)
		(size 0.45)
		(drill 0.2)
		(layers "F.Cu" "B.Cu")
		(remove_unused_layers yes)
		(keep_end_layers yes)
		(free yes)
		(zone_layer_connections)
		(net 199)
	)
	(via
		(at 98.59 80.9)
		(size 0.45)
		(drill 0.2)
		(layers "F.Cu" "B.Cu")
		(remove_unused_layers yes)
		(keep_end_layers yes)
		(zone_layer_connections)
		(net 199)
	)
	(segment
		(start 99.02 82.83)
		(end 98.59 82.4)
		(width 0.15)
		(layer "B.Cu")
		(net 199)
	)
	(segment
		(start 100.1908 89.9)
		(end 112.7 89.9)
		(width 0.125)
		(layer "B.Cu")
		(net 199)
	)
	(segment
		(start 99.2408 87.7508)
		(end 99.02 87.53)
		(width 0.15)
		(layer "B.Cu")
		(net 199)
	)
	(segment
		(start 113.9 92.2)
		(end 114.2 91.9)
		(width 0.125)
		(layer "B.Cu")
		(net 199)
	)
	(segment
		(start 119.6 89.6)
		(end 120.3 90.3)
		(width 0.125)
		(layer "B.Cu")
		(net 199)
	)
	(segment
		(start 113.2 90.4)
		(end 113.2 91.9)
		(width 0.125)
		(layer "B.Cu")
		(net 199)
	)
	(segment
		(start 99.02 87.53)
		(end 99.02 82.83)
		(width 0.15)
		(layer "B.Cu")
		(net 199)
	)
	(segment
		(start 113.2 91.9)
		(end 113.5 92.2)
		(width 0.125)
		(layer "B.Cu")
		(net 199)
	)
	(segment
		(start 114.2 91.9)
		(end 114.2 89.9)
		(width 0.125)
		(layer "B.Cu")
		(net 199)
	)
	(segment
		(start 114.2 89.9)
		(end 114.5 89.6)
		(width 0.125)
		(layer "B.Cu")
		(net 199)
	)
	(segment
		(start 122.1 91.1)
		(end 122.3 91.1)
		(width 0.125)
		(layer "B.Cu")
		(net 199)
	)
	(segment
		(start 121.3 90.3)
		(end 122.1 91.1)
		(width 0.125)
		(layer "B.Cu")
		(net 199)
	)
	(segment
		(start 114.5 89.6)
		(end 119.6 89.6)
		(width 0.125)
		(layer "B.Cu")
		(net 199)
	)
	(segment
		(start 98.59 82.4)
		(end 98.59 80.9)
		(width 0.15)
		(layer "B.Cu")
		(net 199)
	)
	(segment
		(start 113.5 92.2)
		(end 113.9 92.2)
		(width 0.125)
		(layer "B.Cu")
		(net 199)
	)
	(segment
		(start 99.2408 88.95)
		(end 99.2408 87.7508)
		(width 0.15)
		(layer "B.Cu")
		(net 199)
	)
	(segment
		(start 120.3 90.3)
		(end 121.3 90.3)
		(width 0.125)
		(layer "B.Cu")
		(net 199)
	)
	(segment
		(start 112.7 89.9)
		(end 113.2 90.4)
		(width 0.125)
		(layer "B.Cu")
		(net 199)
	)
	(segment
		(start 99.2408 88.95)
		(end 100.1908 89.9)
		(width 0.125)
		(layer "B.Cu")
		(net 199)
	)
	(segment
		(start 97.182468 80.4)
		(end 97.672468 79.91)
		(width 0.15)
		(layer "F.Cu")
		(net 200)
	)
	(via
		(at 97.672468 79.91)
		(size 0.45)
		(drill 0.2)
		(layers "F.Cu" "B.Cu")
		(remove_unused_layers yes)
		(keep_end_layers yes)
		(zone_layer_connections)
		(net 200)
	)
	(segment
		(start 97.7408 87.7508)
		(end 96.19 86.2)
		(width 0.15)
		(layer "B.Cu")
		(net 200)
	)
	(segment
		(start 94.735 94.25)
		(end 96.25 94.25)
		(width 0.15)
		(layer "B.Cu")
		(net 200)
	)
	(segment
		(start 97.7408 88.95)
		(end 97.7408 87.7508)
		(width 0.15)
		(layer "B.Cu")
		(net 200)
	)
	(segment
		(start 96.19 82.8)
		(end 96.19 86.2)
		(width 0.15)
		(layer "B.Cu")
		(net 200)
	)
	(segment
		(start 96.25 94.25)
		(end 98.5 92)
		(width 0.15)
		(layer "B.Cu")
		(net 200)
	)
	(segment
		(start 98.5 92)
		(end 98.5 89.7092)
		(width 0.15)
		(layer "B.Cu")
		(net 200)
	)
	(segment
		(start 94.735 94.25)
		(end 94.735 95.25)
		(width 0.15)
		(layer "B.Cu")
		(net 200)
	)
	(segment
		(start 97.672468 81.317532)
		(end 96.19 82.8)
		(width 0.15)
		(layer "B.Cu")
		(net 200)
	)
	(segment
		(start 98.5 89.7092)
		(end 97.7408 88.95)
		(width 0.15)
		(layer "B.Cu")
		(net 200)
	)
	(segment
		(start 97.672468 79.91)
		(end 97.672468 81.317532)
		(width 0.15)
		(layer "B.Cu")
		(net 200)
	)
	(segment
		(start 104.47 84.69)
		(end 100.68 88.48)
		(width 0.15)
		(layer "F.Cu")
		(net 201)
	)
	(segment
		(start 120.3 89.9)
		(end 119.7 89.9)
		(width 0.15)
		(layer "F.Cu")
		(net 201)
	)
	(segment
		(start 97.69 88)
		(end 97.69 86.53)
		(width 0.15)
		(layer "F.Cu")
		(net 201)
	)
	(segment
		(start 97.1 79.384068)
		(end 97.601295 78.882773)
		(width 0.15)
		(layer "F.Cu")
		(net 201)
	)
	(segment
		(start 119.7 89.9)
		(end 114.49 84.69)
		(width 0.15)
		(layer "F.Cu")
		(net 201)
	)
	(segment
		(start 114.49 84.69)
		(end 104.47 84.69)
		(width 0.15)
		(layer "F.Cu")
		(net 201)
	)
	(segment
		(start 98.17 88.48)
		(end 97.69 88)
		(width 0.15)
		(layer "F.Cu")
		(net 201)
	)
	(segment
		(start 100.68 88.48)
		(end 98.17 88.48)
		(width 0.15)
		(layer "F.Cu")
		(net 201)
	)
	(via
		(at 97.601295 78.882773)
		(size 0.45)
		(drill 0.2)
		(layers "F.Cu" "B.Cu")
		(remove_unused_layers yes)
		(keep_end_layers yes)
		(zone_layer_connections)
		(net 201)
	)
	(via
		(at 97.69 86.53)
		(size 0.45)
		(drill 0.2)
		(layers "F.Cu" "B.Cu")
		(remove_unused_layers yes)
		(keep_end_layers yes)
		(zone_layer_connections)
		(net 201)
	)
	(segment
		(start 97.69 86.53)
		(end 98.13 86.53)
		(width 0.15)
		(layer "B.Cu")
		(net 201)
	)
	(segment
		(start 98.072468 83.107532)
		(end 97.69 83.49)
		(width 0.15)
		(layer "B.Cu")
		(net 201)
	)
	(segment
		(start 98.4908 88.2)
		(end 98.19 87.8992)
		(width 0.15)
		(layer "B.Cu")
		(net 201)
	)
	(segment
		(start 98.13 86.53)
		(end 98.19 86.47)
		(width 0.15)
		(layer "B.Cu")
		(net 201)
	)
	(segment
		(start 97.601295 78.882773)
		(end 97.69 78.971478)
		(width 0.15)
		(layer "B.Cu")
		(net 201)
	)
	(segment
		(start 98.072468 79.664936)
		(end 98.072468 83.107532)
		(width 0.15)
		(layer "B.Cu")
		(net 201)
	)
	(segment
		(start 97.69 79.282468)
		(end 98.072468 79.664936)
		(width 0.15)
		(layer "B.Cu")
		(net 201)
	)
	(segment
		(start 97.69 83.49)
		(end 97.69 84.25)
		(width 0.15)
		(layer "B.Cu")
		(net 201)
	)
	(segment
		(start 98.19 87.8992)
		(end 98.19 86.47)
		(width 0.15)
		(layer "B.Cu")
		(net 201)
	)
	(segment
		(start 98.19 84.75)
		(end 98.19 86.47)
		(width 0.15)
		(layer "B.Cu")
		(net 201)
	)
	(segment
		(start 97.69 84.25)
		(end 98.19 84.75)
		(width 0.15)
		(layer "B.Cu")
		(net 201)
	)
	(segment
		(start 97.69 78.971478)
		(end 97.69 79.282468)
		(width 0.15)
		(layer "B.Cu")
		(net 201)
	)
	(segment
		(start 101.448898 78.420523)
		(end 100.120523 78.420523)
		(width 0.2)
		(layer "F.Cu")
		(net 202)
	)
	(segment
		(start 130.7 89.1)
		(end 131.1 89.5)
		(width 0.182)
		(layer "F.Cu")
		(net 202)
	)
	(via
		(at 101.448898 78.420523)
		(size 0.45)
		(drill 0.2)
		(layers "F.Cu" "B.Cu")
		(remove_unused_layers yes)
		(keep_end_layers yes)
		(zone_layer_connections)
		(net 202)
	)
	(via
		(at 131.1 89.5)
		(size 0.45)
		(drill 0.2)
		(layers "F.Cu" "B.Cu")
		(remove_unused_layers yes)
		(keep_end_layers yes)
		(zone_layer_connections)
		(net 202)
	)
	(segment
		(start 108.397798 89.987984)
		(end 108.397798 89.987985)
		(width 0.13)
		(layer "In2.Cu")
		(net 202)
	)
	(segment
		(start 125.32 97.48)
		(end 125.13 97.67)
		(width 0.13)
		(layer "In2.Cu")
		(net 202)
	)
	(segment
		(start 129.915 95.36)
		(end 129.515 95.76)
		(width 0.13)
		(layer "In2.Cu")
		(net 202)
	)
	(segment
		(start 107.840829 91.393485)
		(end 107.840827 91.393484)
		(width 0.13)
		(layer "In2.Cu")
		(net 202)
	)
	(segment
		(start 103.1 78.7)
		(end 101.728375 78.7)
		(width 0.13)
		(layer "In2.Cu")
		(net 202)
	)
	(segment
		(start 124.85 98.4)
		(end 115.97 98.4)
		(width 0.13)
		(layer "In2.Cu")
		(net 202)
	)
	(segment
		(start 115.97 98.4)
		(end 108.685 91.115)
		(width 0.13)
		(layer "In2.Cu")
		(net 202)
	)
	(segment
		(start 106.700734 88.290921)
		(end 105.860919 89.130732)
		(width 0.13)
		(layer "In2.Cu")
		(net 202)
	)
	(segment
		(start 131.91 94.71)
		(end 130.145527 94.71)
		(width 0.13)
		(layer "In2.Cu")
		(net 202)
	)
	(segment
		(start 107.266422 88.856609)
		(end 106.426607 89.69642)
		(width 0.13)
		(layer "In2.Cu")
		(net 202)
	)
	(segment
		(start 104.82 80.42)
		(end 103.1 78.7)
		(width 0.13)
		(layer "In2.Cu")
		(net 202)
	)
	(segment
		(start 125.13 98.12)
		(end 124.85 98.4)
		(width 0.13)
		(layer "In2.Cu")
		(net 202)
	)
	(segment
		(start 108.260733 90.690734)
		(end 108.260735 90.690735)
		(width 0.13)
		(layer "In2.Cu")
		(net 202)
	)
	(segment
		(start 132.035 89.885)
		(end 132.31 90.16)
		(width 0.13)
		(layer "In2.Cu")
		(net 202)
	)
	(segment
		(start 105.578076 88.847889)
		(end 105.856562 88.569404)
		(width 0.13)
		(layer "In2.Cu")
		(net 202)
	)
	(segment
		(start 131.1 89.5)
		(end 131.485 89.885)
		(width 0.13)
		(layer "In2.Cu")
		(net 202)
	)
	(segment
		(start 105.578076 89.130733)
		(end 105.578077 89.130733)
		(width 0.13)
		(layer "In2.Cu")
		(net 202)
	)
	(segment
		(start 106.709452 89.979266)
		(end 106.709452 89.979265)
		(width 0.13)
		(layer "In2.Cu")
		(net 202)
	)
	(segment
		(start 104.82 87.25)
		(end 104.82 80.42)
		(width 0.13)
		(layer "In2.Cu")
		(net 202)
	)
	(segment
		(start 129.515 95.76)
		(end 129.115 95.76)
		(width 0.13)
		(layer "In2.Cu")
		(net 202)
	)
	(segment
		(start 107.266422 88.856608)
		(end 107.266422 88.856609)
		(width 0.13)
		(layer "In2.Cu")
		(net 202)
	)
	(segment
		(start 107.27514 90.827797)
		(end 107.275141 90.827797)
		(width 0.13)
		(layer "In2.Cu")
		(net 202)
	)
	(segment
		(start 105.578076 88.84789)
		(end 105.578076 88.847889)
		(width 0.13)
		(layer "In2.Cu")
		(net 202)
	)
	(segment
		(start 106.709452 89.979265)
		(end 107.549265 89.139452)
		(width 0.13)
		(layer "In2.Cu")
		(net 202)
	)
	(segment
		(start 106.700734 88.29092)
		(end 106.700734 88.290921)
		(width 0.13)
		(layer "In2.Cu")
		(net 202)
	)
	(segment
		(start 126.37 97.48)
		(end 125.32 97.48)
		(width 0.13)
		(layer "In2.Cu")
		(net 202)
	)
	(segment
		(start 107.840828 91.110642)
		(end 108.260733 90.690734)
		(width 0.13)
		(layer "In2.Cu")
		(net 202)
	)
	(segment
		(start 105.856562 88.286562)
		(end 105.856561 88.28656)
		(width 0.13)
		(layer "In2.Cu")
		(net 202)
	)
	(segment
		(start 108.397798 89.987985)
		(end 107.557983 90.827796)
		(width 0.13)
		(layer "In2.Cu")
		(net 202)
	)
	(segment
		(start 106.983578 88.290921)
		(end 106.983577 88.290921)
		(width 0.13)
		(layer "In2.Cu")
		(net 202)
	)
	(segment
		(start 107.83211 89.422297)
		(end 106.992295 90.262108)
		(width 0.13)
		(layer "In2.Cu")
		(net 202)
	)
	(segment
		(start 132.31 90.16)
		(end 132.31 94.31)
		(width 0.13)
		(layer "In2.Cu")
		(net 202)
	)
	(segment
		(start 108.260735 90.690735)
		(end 108.680641 90.270828)
		(width 0.13)
		(layer "In2.Cu")
		(net 202)
	)
	(segment
		(start 106.143764 89.413578)
		(end 106.143764 89.413577)
		(width 0.13)
		(layer "In2.Cu")
		(net 202)
	)
	(segment
		(start 132.31 94.31)
		(end 131.91 94.71)
		(width 0.13)
		(layer "In2.Cu")
		(net 202)
	)
	(segment
		(start 128.15 96.725)
		(end 127.125 96.725)
		(width 0.13)
		(layer "In2.Cu")
		(net 202)
	)
	(segment
		(start 125.13 97.67)
		(end 125.13 98.12)
		(width 0.13)
		(layer "In2.Cu")
		(net 202)
	)
	(segment
		(start 108.402156 91.114999)
		(end 108.123671 91.393485)
		(width 0.13)
		(layer "In2.Cu")
		(net 202)
	)
	(segment
		(start 107.83211 89.422296)
		(end 107.83211 89.422297)
		(width 0.13)
		(layer "In2.Cu")
		(net 202)
	)
	(segment
		(start 107.549266 88.856609)
		(end 107.549265 88.856609)
		(width 0.13)
		(layer "In2.Cu")
		(net 202)
	)
	(segment
		(start 108.402157 91.114999)
		(end 108.402156 91.114999)
		(width 0.13)
		(layer "In2.Cu")
		(net 202)
	)
	(segment
		(start 101.728375 78.7)
		(end 101.448898 78.420523)
		(width 0.13)
		(layer "In2.Cu")
		(net 202)
	)
	(segment
		(start 105.856561 88.28656)
		(end 104.82 87.25)
		(width 0.13)
		(layer "In2.Cu")
		(net 202)
	)
	(segment
		(start 107.27514 90.544954)
		(end 107.27514 90.544953)
		(width 0.13)
		(layer "In2.Cu")
		(net 202)
	)
	(segment
		(start 108.114954 89.422297)
		(end 108.114953 89.422297)
		(width 0.13)
		(layer "In2.Cu")
		(net 202)
	)
	(segment
		(start 106.709452 90.262109)
		(end 106.709453 90.262109)
		(width 0.13)
		(layer "In2.Cu")
		(net 202)
	)
	(segment
		(start 107.840826 91.110641)
		(end 107.840828 91.110642)
		(width 0.13)
		(layer "In2.Cu")
		(net 202)
	)
	(segment
		(start 108.680642 89.987985)
		(end 108.680641 89.987985)
		(width 0.13)
		(layer "In2.Cu")
		(net 202)
	)
	(segment
		(start 129.115 95.76)
		(end 128.15 96.725)
		(width 0.13)
		(layer "In2.Cu")
		(net 202)
	)
	(segment
		(start 127.125 96.725)
		(end 126.37 97.48)
		(width 0.13)
		(layer "In2.Cu")
		(net 202)
	)
	(segment
		(start 106.143764 89.696421)
		(end 106.143765 89.696421)
		(width 0.13)
		(layer "In2.Cu")
		(net 202)
	)
	(segment
		(start 131.485 89.885)
		(end 132.035 89.885)
		(width 0.13)
		(layer "In2.Cu")
		(net 202)
	)
	(segment
		(start 129.915 94.940527)
		(end 129.915 95.36)
		(width 0.13)
		(layer "In2.Cu")
		(net 202)
	)
	(segment
		(start 107.27514 90.544953)
		(end 108.114953 89.70514)
		(width 0.13)
		(layer "In2.Cu")
		(net 202)
	)
	(segment
		(start 130.145527 94.71)
		(end 129.915 94.940527)
		(width 0.13)
		(layer "In2.Cu")
		(net 202)
	)
	(segment
		(start 106.143764 89.413577)
		(end 106.983577 88.573764)
		(width 0.13)
		(layer "In2.Cu")
		(net 202)
	)
	(arc
		(start 105.856562 88.569404)
		(mid 105.915139 88.427982)
		(end 105.856562 88.286562)
		(width 0.13)
		(layer "In2.Cu")
		(net 202)
	)
	(arc
		(start 106.992295 90.262108)
		(mid 106.850874 90.320687)
		(end 106.709452 90.262109)
		(width 0.13)
		(layer "In2.Cu")
		(net 202)
	)
	(arc
		(start 108.680641 90.270828)
		(mid 108.73922 90.129407)
		(end 108.680642 89.987985)
		(width 0.13)
		(layer "In2.Cu")
		(net 202)
	)
	(arc
		(start 108.680641 89.987985)
		(mid 108.53922 89.929406)
		(end 108.397798 89.987984)
		(width 0.13)
		(layer "In2.Cu")
		(net 202)
	)
	(arc
		(start 107.549265 88.856609)
		(mid 107.407844 88.79803)
		(end 107.266422 88.856608)
		(width 0.13)
		(layer "In2.Cu")
		(net 202)
	)
	(arc
		(start 108.685 91.115)
		(mid 108.543579 91.056421)
		(end 108.402157 91.114999)
		(width 0.13)
		(layer "In2.Cu")
		(net 202)
	)
	(arc
		(start 106.709453 90.262109)
		(mid 106.650874 90.120688)
		(end 106.709452 89.979266)
		(width 0.13)
		(layer "In2.Cu")
		(net 202)
	)
	(arc
		(start 105.578077 89.130733)
		(mid 105.519498 88.989312)
		(end 105.578076 88.84789)
		(width 0.13)
		(layer "In2.Cu")
		(net 202)
	)
	(arc
		(start 107.840827 91.393484)
		(mid 107.782248 91.252063)
		(end 107.840826 91.110641)
		(width 0.13)
		(layer "In2.Cu")
		(net 202)
	)
	(arc
		(start 108.114953 89.70514)
		(mid 108.173532 89.563719)
		(end 108.114954 89.422297)
		(width 0.13)
		(layer "In2.Cu")
		(net 202)
	)
	(arc
		(start 107.557983 90.827796)
		(mid 107.416562 90.886375)
		(end 107.27514 90.827797)
		(width 0.13)
		(layer "In2.Cu")
		(net 202)
	)
	(arc
		(start 106.983577 88.573764)
		(mid 107.042156 88.432343)
		(end 106.983578 88.290921)
		(width 0.13)
		(layer "In2.Cu")
		(net 202)
	)
	(arc
		(start 105.860919 89.130732)
		(mid 105.719498 89.189311)
		(end 105.578076 89.130733)
		(width 0.13)
		(layer "In2.Cu")
		(net 202)
	)
	(arc
		(start 107.275141 90.827797)
		(mid 107.216562 90.686376)
		(end 107.27514 90.544954)
		(width 0.13)
		(layer "In2.Cu")
		(net 202)
	)
	(arc
		(start 106.426607 89.69642)
		(mid 106.285186 89.754999)
		(end 106.143764 89.696421)
		(width 0.13)
		(layer "In2.Cu")
		(net 202)
	)
	(arc
		(start 107.549265 89.139452)
		(mid 107.607844 88.998031)
		(end 107.549266 88.856609)
		(width 0.13)
		(layer "In2.Cu")
		(net 202)
	)
	(arc
		(start 108.123671 91.393485)
		(mid 107.982249 91.452062)
		(end 107.840829 91.393485)
		(width 0.13)
		(layer "In2.Cu")
		(net 202)
	)
	(arc
		(start 106.983577 88.290921)
		(mid 106.842156 88.232342)
		(end 106.700734 88.29092)
		(width 0.13)
		(layer "In2.Cu")
		(net 202)
	)
	(arc
		(start 108.114953 89.422297)
		(mid 107.973532 89.363718)
		(end 107.83211 89.422296)
		(width 0.13)
		(layer "In2.Cu")
		(net 202)
	)
	(arc
		(start 106.143765 89.696421)
		(mid 106.085186 89.555)
		(end 106.143764 89.413578)
		(width 0.13)
		(layer "In2.Cu")
		(net 202)
	)
	(segment
		(start 129.1 90.7)
		(end 129.5 91.1)
		(width 0.182)
		(layer "F.Cu")
		(net 203)
	)
	(segment
		(start 101.8 76.902467)
		(end 99.597533 76.902467)
		(width 0.2)
		(layer "F.Cu")
		(net 203)
	)
	(segment
		(start 99.597533 76.902467)
		(end 99.1 77.4)
		(width 0.2)
		(layer "F.Cu")
		(net 203)
	)
	(via
		(at 129.5 91.1)
		(size 0.45)
		(drill 0.2)
		(layers "F.Cu" "B.Cu")
		(remove_unused_layers yes)
		(keep_end_layers yes)
		(zone_layer_connections)
		(net 203)
	)
	(via
		(at 101.8 76.902467)
		(size 0.45)
		(drill 0.2)
		(layers "F.Cu" "B.Cu")
		(remove_unused_layers yes)
		(keep_end_layers yes)
		(zone_layer_connections)
		(net 203)
	)
	(segment
		(start 107.9 71.5)
		(end 112.5 71.5)
		(width 0.13)
		(layer "In4.Cu")
		(net 203)
	)
	(segment
		(start 103.8 77.4)
		(end 105.6 77.4)
		(width 0.13)
		(layer "In4.Cu")
		(net 203)
	)
	(segment
		(start 103.302467 76.902467)
		(end 103.8 77.4)
		(width 0.13)
		(layer "In4.Cu")
		(net 203)
	)
	(segment
		(start 114.73712 88.777088)
		(end 115.837086 87.677119)
		(width 0.13)
		(layer "In4.Cu")
		(net 203)
	)
	(segment
		(start 116.685615 88.525647)
		(end 116.277053 88.93421)
		(width 0.13)
		(layer "In4.Cu")
		(net 203)
	)
	(segment
		(start 129.5 91.355527)
		(end 129.5 91.1)
		(width 0.13)
		(layer "In4.Cu")
		(net 203)
	)
	(segment
		(start 106.7 72.7)
		(end 107.9 71.5)
		(width 0.13)
		(layer "In4.Cu")
		(net 203)
	)
	(segment
		(start 118.935027 90.78)
		(end 120.845027 92.69)
		(width 0.13)
		(layer "In4.Cu")
		(net 203)
	)
	(segment
		(start 122.054973 92.69)
		(end 122.459973 92.285)
		(width 0.13)
		(layer "In4.Cu")
		(net 203)
	)
	(segment
		(start 128.859473 92.285)
		(end 129.115 92.029473)
		(width 0.13)
		(layer "In4.Cu")
		(net 203)
	)
	(segment
		(start 116.11993 87.959962)
		(end 115.019963 89.05993)
		(width 0.13)
		(layer "In4.Cu")
		(net 203)
	)
	(segment
		(start 112.5 71.5)
		(end 114.1 73.1)
		(width 0.13)
		(layer "In4.Cu")
		(net 203)
	)
	(segment
		(start 129.115 91.740527)
		(end 129.5 91.355527)
		(width 0.13)
		(layer "In4.Cu")
		(net 203)
	)
	(segment
		(start 120.845027 92.69)
		(end 122.054973 92.69)
		(width 0.13)
		(layer "In4.Cu")
		(net 203)
	)
	(segment
		(start 115.302805 89.342773)
		(end 116.402771 88.242804)
		(width 0.13)
		(layer "In4.Cu")
		(net 203)
	)
	(segment
		(start 115.554248 87.111439)
		(end 115.554247 87.111438)
		(width 0.13)
		(layer "In4.Cu")
		(net 203)
	)
	(segment
		(start 106.7 76.3)
		(end 106.7 72.7)
		(width 0.13)
		(layer "In4.Cu")
		(net 203)
	)
	(segment
		(start 115.302806 89.342772)
		(end 115.302805 89.342773)
		(width 0.13)
		(layer "In4.Cu")
		(net 203)
	)
	(segment
		(start 114.1 87.04)
		(end 114.58 87.52)
		(width 0.13)
		(layer "In4.Cu")
		(net 203)
	)
	(segment
		(start 114.862843 87.519999)
		(end 114.862842 87.52)
		(width 0.13)
		(layer "In4.Cu")
		(net 203)
	)
	(segment
		(start 114.1 73.1)
		(end 114.1 87.04)
		(width 0.13)
		(layer "In4.Cu")
		(net 203)
	)
	(segment
		(start 116.11993 87.677121)
		(end 116.11993 87.67712)
		(width 0.13)
		(layer "In4.Cu")
		(net 203)
	)
	(segment
		(start 116.119929 87.959963)
		(end 116.11993 87.959962)
		(width 0.13)
		(layer "In4.Cu")
		(net 203)
	)
	(segment
		(start 116.277053 89.217052)
		(end 117.84 90.78)
		(width 0.13)
		(layer "In4.Cu")
		(net 203)
	)
	(segment
		(start 115.019963 89.342772)
		(end 115.019963 89.342773)
		(width 0.13)
		(layer "In4.Cu")
		(net 203)
	)
	(segment
		(start 114.454278 88.777087)
		(end 114.454278 88.777088)
		(width 0.13)
		(layer "In4.Cu")
		(net 203)
	)
	(segment
		(start 129.115 92.029473)
		(end 129.115 91.740527)
		(width 0.13)
		(layer "In4.Cu")
		(net 203)
	)
	(segment
		(start 101.8 76.902467)
		(end 103.302467 76.902467)
		(width 0.13)
		(layer "In4.Cu")
		(net 203)
	)
	(segment
		(start 116.685614 88.525648)
		(end 116.685615 88.525647)
		(width 0.13)
		(layer "In4.Cu")
		(net 203)
	)
	(segment
		(start 114.862842 87.52)
		(end 115.271405 87.111438)
		(width 0.13)
		(layer "In4.Cu")
		(net 203)
	)
	(segment
		(start 116.685615 88.242806)
		(end 116.685615 88.242805)
		(width 0.13)
		(layer "In4.Cu")
		(net 203)
	)
	(segment
		(start 117.84 90.78)
		(end 118.935027 90.78)
		(width 0.13)
		(layer "In4.Cu")
		(net 203)
	)
	(segment
		(start 115.554246 87.394281)
		(end 115.554247 87.39428)
		(width 0.13)
		(layer "In4.Cu")
		(net 203)
	)
	(segment
		(start 114.737121 88.777087)
		(end 114.73712 88.777088)
		(width 0.13)
		(layer "In4.Cu")
		(net 203)
	)
	(segment
		(start 105.6 77.4)
		(end 106.7 76.3)
		(width 0.13)
		(layer "In4.Cu")
		(net 203)
	)
	(segment
		(start 115.554247 87.39428)
		(end 114.454278 88.494245)
		(width 0.13)
		(layer "In4.Cu")
		(net 203)
	)
	(segment
		(start 116.277054 89.217053)
		(end 116.277053 89.217052)
		(width 0.13)
		(layer "In4.Cu")
		(net 203)
	)
	(segment
		(start 122.459973 92.285)
		(end 128.859473 92.285)
		(width 0.13)
		(layer "In4.Cu")
		(net 203)
	)
	(arc
		(start 116.685615 88.242805)
		(mid 116.744193 88.384227)
		(end 116.685614 88.525648)
		(width 0.13)
		(layer "In4.Cu")
		(net 203)
	)
	(arc
		(start 114.454278 88.494245)
		(mid 114.3957 88.635666)
		(end 114.454278 88.777087)
		(width 0.13)
		(layer "In4.Cu")
		(net 203)
	)
	(arc
		(start 115.019963 89.342773)
		(mid 115.161385 89.401351)
		(end 115.302806 89.342772)
		(width 0.13)
		(layer "In4.Cu")
		(net 203)
	)
	(arc
		(start 116.277053 88.93421)
		(mid 116.218475 89.075632)
		(end 116.277054 89.217053)
		(width 0.13)
		(layer "In4.Cu")
		(net 203)
	)
	(arc
		(start 116.11993 87.67712)
		(mid 116.178508 87.818542)
		(end 116.119929 87.959963)
		(width 0.13)
		(layer "In4.Cu")
		(net 203)
	)
	(arc
		(start 114.58 87.52)
		(mid 114.721422 87.578578)
		(end 114.862843 87.519999)
		(width 0.13)
		(layer "In4.Cu")
		(net 203)
	)
	(arc
		(start 115.837086 87.677119)
		(mid 115.978508 87.618542)
		(end 116.11993 87.677121)
		(width 0.13)
		(layer "In4.Cu")
		(net 203)
	)
	(arc
		(start 116.402771 88.242804)
		(mid 116.544193 88.184227)
		(end 116.685615 88.242806)
		(width 0.13)
		(layer "In4.Cu")
		(net 203)
	)
	(arc
		(start 114.454278 88.777088)
		(mid 114.5957 88.835666)
		(end 114.737121 88.777087)
		(width 0.13)
		(layer "In4.Cu")
		(net 203)
	)
	(arc
		(start 115.271405 87.111438)
		(mid 115.412827 87.05286)
		(end 115.554248 87.111439)
		(width 0.13)
		(layer "In4.Cu")
		(net 203)
	)
	(arc
		(start 115.554247 87.111438)
		(mid 115.612825 87.25286)
		(end 115.554246 87.394281)
		(width 0.13)
		(layer "In4.Cu")
		(net 203)
	)
	(arc
		(start 115.019963 89.05993)
		(mid 114.961385 89.201351)
		(end 115.019963 89.342772)
		(width 0.13)
		(layer "In4.Cu")
		(net 203)
	)
	(segment
		(start 128.3 89.9)
		(end 127.89 89.49)
		(width 0.2)
		(layer "F.Cu")
		(net 204)
	)
	(segment
		(start 97.59 74.89)
		(end 97.59 71.74)
		(width 0.2)
		(layer "F.Cu")
		(net 204)
	)
	(segment
		(start 97.59 71.74)
		(end 97.63 71.7)
		(width 0.2)
		(layer "F.Cu")
		(net 204)
	)
	(segment
		(start 98.1 75.4)
		(end 97.59 74.89)
		(width 0.2)
		(layer "F.Cu")
		(net 204)
	)
	(via
		(at 127.89 89.49)
		(size 0.45)
		(drill 0.1)
		(layers "F.Cu" "B.Cu")
		(net 204)
	)
	(via
		(at 97.63 71.7)
		(size 0.45)
		(drill 0.2)
		(layers "F.Cu" "B.Cu")
		(remove_unused_layers yes)
		(keep_end_layers yes)
		(zone_layer_connections)
		(net 204)
	)
	(segment
		(start 110.694757 85.353769)
		(end 110.694758 85.353768)
		(width 0.13)
		(layer "In2.Cu")
		(net 204)
	)
	(segment
		(start 110.077843 85.404999)
		(end 110.077842 85.405)
		(width 0.13)
		(layer "In2.Cu")
		(net 204)
	)
	(segment
		(start 97.63 71.7)
		(end 97.63 71.47)
		(width 0.13)
		(layer "In2.Cu")
		(net 204)
	)
	(segment
		(start 100 67.8)
		(end 108.4 67.8)
		(width 0.13)
		(layer "In2.Cu")
		(net 204)
	)
	(segment
		(start 111.492052 87.102052)
		(end 114.305 89.915)
		(width 0.13)
		(layer "In2.Cu")
		(net 204)
	)
	(segment
		(start 109.31 68.71)
		(end 109.31 84.92)
		(width 0.13)
		(layer "In2.Cu")
		(net 204)
	)
	(segment
		(start 109.31 84.92)
		(end 109.795 85.405)
		(width 0.13)
		(layer "In2.Cu")
		(net 204)
	)
	(segment
		(start 110.769072 86.976506)
		(end 110.769071 86.976507)
		(width 0.13)
		(layer "In2.Cu")
		(net 204)
	)
	(segment
		(start 111.260442 85.636609)
		(end 111.260441 85.636609)
		(width 0.13)
		(layer "In2.Cu")
		(net 204)
	)
	(segment
		(start 110.694759 85.070928)
		(end 110.694758 85.070926)
		(width 0.13)
		(layer "In2.Cu")
		(net 204)
	)
	(segment
		(start 114.305 89.915)
		(end 127.585 89.915)
		(width 0.13)
		(layer "In2.Cu")
		(net 204)
	)
	(segment
		(start 111.826126 86.485136)
		(end 111.492053 86.81921)
		(width 0.13)
		(layer "In2.Cu")
		(net 204)
	)
	(segment
		(start 127.89 89.61)
		(end 127.89 89.49)
		(width 0.13)
		(layer "In2.Cu")
		(net 204)
	)
	(segment
		(start 111.260441 85.919451)
		(end 110.486229 86.693664)
		(width 0.13)
		(layer "In2.Cu")
		(net 204)
	)
	(segment
		(start 110.077842 85.405)
		(end 110.411916 85.070927)
		(width 0.13)
		(layer "In2.Cu")
		(net 204)
	)
	(segment
		(start 110.203387 86.410821)
		(end 110.203386 86.410822)
		(width 0.13)
		(layer "In2.Cu")
		(net 204)
	)
	(segment
		(start 111.26044 85.919452)
		(end 111.260441 85.919451)
		(width 0.13)
		(layer "In2.Cu")
		(net 204)
	)
	(segment
		(start 110.219262 85.829262)
		(end 109.920544 86.127979)
		(width 0.13)
		(layer "In2.Cu")
		(net 204)
	)
	(segment
		(start 108.4 67.8)
		(end 109.31 68.71)
		(width 0.13)
		(layer "In2.Cu")
		(net 204)
	)
	(segment
		(start 99.3 69.8)
		(end 99.3 68.5)
		(width 0.13)
		(layer "In2.Cu")
		(net 204)
	)
	(segment
		(start 99.3 68.5)
		(end 100 67.8)
		(width 0.13)
		(layer "In2.Cu")
		(net 204)
	)
	(segment
		(start 110.486228 86.976507)
		(end 110.486229 86.976507)
		(width 0.13)
		(layer "In2.Cu")
		(net 204)
	)
	(segment
		(start 110.219264 85.829263)
		(end 110.219262 85.829262)
		(width 0.13)
		(layer "In2.Cu")
		(net 204)
	)
	(segment
		(start 111.826125 86.485137)
		(end 111.826126 86.485136)
		(width 0.13)
		(layer "In2.Cu")
		(net 204)
	)
	(segment
		(start 111.492054 87.102053)
		(end 111.492052 87.102052)
		(width 0.13)
		(layer "In2.Cu")
		(net 204)
	)
	(segment
		(start 111.826127 86.202294)
		(end 111.826126 86.202294)
		(width 0.13)
		(layer "In2.Cu")
		(net 204)
	)
	(segment
		(start 110.694758 85.353768)
		(end 110.219264 85.829263)
		(width 0.13)
		(layer "In2.Cu")
		(net 204)
	)
	(segment
		(start 109.920543 86.410822)
		(end 109.920544 86.410822)
		(width 0.13)
		(layer "In2.Cu")
		(net 204)
	)
	(segment
		(start 97.63 71.47)
		(end 99.3 69.8)
		(width 0.13)
		(layer "In2.Cu")
		(net 204)
	)
	(segment
		(start 110.769071 86.976507)
		(end 111.543282 86.202293)
		(width 0.13)
		(layer "In2.Cu")
		(net 204)
	)
	(segment
		(start 127.585 89.915)
		(end 127.89 89.61)
		(width 0.13)
		(layer "In2.Cu")
		(net 204)
	)
	(segment
		(start 110.203386 86.410822)
		(end 110.977597 85.636608)
		(width 0.13)
		(layer "In2.Cu")
		(net 204)
	)
	(arc
		(start 109.920544 86.127979)
		(mid 109.861965 86.2694)
		(end 109.920543 86.410822)
		(width 0.13)
		(layer "In2.Cu")
		(net 204)
	)
	(arc
		(start 110.694758 85.070926)
		(mid 110.753336 85.212348)
		(end 110.694757 85.353769)
		(width 0.13)
		(layer "In2.Cu")
		(net 204)
	)
	(arc
		(start 109.795 85.405)
		(mid 109.936422 85.463578)
		(end 110.077843 85.404999)
		(width 0.13)
		(layer "In2.Cu")
		(net 204)
	)
	(arc
		(start 110.977597 85.636608)
		(mid 111.11902 85.578031)
		(end 111.260442 85.636609)
		(width 0.13)
		(layer "In2.Cu")
		(net 204)
	)
	(arc
		(start 109.920544 86.410822)
		(mid 110.061966 86.4694)
		(end 110.203387 86.410821)
		(width 0.13)
		(layer "In2.Cu")
		(net 204)
	)
	(arc
		(start 111.492053 86.81921)
		(mid 111.433475 86.960632)
		(end 111.492054 87.102053)
		(width 0.13)
		(layer "In2.Cu")
		(net 204)
	)
	(arc
		(start 111.260441 85.636609)
		(mid 111.319019 85.778031)
		(end 111.26044 85.919452)
		(width 0.13)
		(layer "In2.Cu")
		(net 204)
	)
	(arc
		(start 111.826126 86.202294)
		(mid 111.884704 86.343716)
		(end 111.826125 86.485137)
		(width 0.13)
		(layer "In2.Cu")
		(net 204)
	)
	(arc
		(start 110.411916 85.070927)
		(mid 110.553338 85.012349)
		(end 110.694759 85.070928)
		(width 0.13)
		(layer "In2.Cu")
		(net 204)
	)
	(arc
		(start 110.486229 86.976507)
		(mid 110.627651 87.035085)
		(end 110.769072 86.976506)
		(width 0.13)
		(layer "In2.Cu")
		(net 204)
	)
	(arc
		(start 110.486229 86.693664)
		(mid 110.42765 86.835085)
		(end 110.486228 86.976507)
		(width 0.13)
		(layer "In2.Cu")
		(net 204)
	)
	(arc
		(start 111.543282 86.202293)
		(mid 111.684705 86.143716)
		(end 111.826127 86.202294)
		(width 0.13)
		(layer "In2.Cu")
		(net 204)
	)
	(segment
		(start 131.5 90.7)
		(end 131.9 91.1)
		(width 0.2)
		(layer "F.Cu")
		(net 205)
	)
	(segment
		(start 100.1 77.4)
		(end 101.49 77.4)
		(width 0.2)
		(layer "F.Cu")
		(net 205)
	)
	(via
		(at 131.9 91.1)
		(size 0.45)
		(drill 0.1)
		(layers "F.Cu" "B.Cu")
		(net 205)
	)
	(via
		(at 101.49 77.4)
		(size 0.45)
		(drill 0.2)
		(layers "F.Cu" "B.Cu")
		(remove_unused_layers yes)
		(keep_end_layers yes)
		(zone_layer_connections)
		(net 205)
	)
	(segment
		(start 112.637842 93.245)
		(end 112.756249 93.126594)
		(width 0.13)
		(layer "In2.Cu")
		(net 205)
	)
	(segment
		(start 131.485 91.515)
		(end 131.9 91.1)
		(width 0.13)
		(layer "In2.Cu")
		(net 205)
	)
	(segment
		(start 129.36 94.69)
		(end 129.672634 94.69)
		(width 0.13)
		(layer "In2.Cu")
		(net 205)
	)
	(segment
		(start 129.672634 94.69)
		(end 131.485 92.877634)
		(width 0.13)
		(layer "In2.Cu")
		(net 205)
	)
	(segment
		(start 118.77751 97.92249)
		(end 118.77751 96.72249)
		(width 0.13)
		(layer "In2.Cu")
		(net 205)
	)
	(segment
		(start 113.604777 93.692278)
		(end 113.604776 93.692278)
		(width 0.13)
		(layer "In2.Cu")
		(net 205)
	)
	(segment
		(start 105.62 79.42)
		(end 105.62 86.51)
		(width 0.13)
		(layer "In2.Cu")
		(net 205)
	)
	(segment
		(start 123.84751 97.52249)
		(end 124.855 96.515)
		(width 0.13)
		(layer "In2.Cu")
		(net 205)
	)
	(segment
		(start 117.17751 97.32249)
		(end 117.17751 96.72249)
		(width 0.13)
		(layer "In2.Cu")
		(net 205)
	)
	(segment
		(start 126.98 96.495)
		(end 127.849473 96.495)
		(width 0.13)
		(layer "In2.Cu")
		(net 205)
	)
	(segment
		(start 101.49 77.4)
		(end 101.905697 77.4)
		(width 0.13)
		(layer "In2.Cu")
		(net 205)
	)
	(segment
		(start 119.57751 97.92249)
		(end 119.57751 96.72249)
		(width 0.13)
		(layer "In2.Cu")
		(net 205)
	)
	(segment
		(start 131.485 92.877634)
		(end 131.485 91.515)
		(width 0.13)
		(layer "In2.Cu")
		(net 205)
	)
	(segment
		(start 113.039091 93.126594)
		(end 113.039091 93.126593)
		(width 0.13)
		(layer "In2.Cu")
		(net 205)
	)
	(segment
		(start 105.62 86.51)
		(end 112.355 93.245)
		(width 0.13)
		(layer "In2.Cu")
		(net 205)
	)
	(segment
		(start 102.197261 77.108436)
		(end 103.314624 77.108436)
		(width 0.13)
		(layer "In2.Cu")
		(net 205)
	)
	(segment
		(start 120.17751 97.52249)
		(end 123.84751 97.52249)
		(width 0.13)
		(layer "In2.Cu")
		(net 205)
	)
	(segment
		(start 126.96 96.515)
		(end 126.98 96.495)
		(width 0.13)
		(layer "In2.Cu")
		(net 205)
	)
	(segment
		(start 117.97751 97.92249)
		(end 117.97751 96.72249)
		(width 0.13)
		(layer "In2.Cu")
		(net 205)
	)
	(segment
		(start 112.637843 93.244999)
		(end 112.637842 93.245)
		(width 0.13)
		(layer "In2.Cu")
		(net 205)
	)
	(segment
		(start 113.03909 93.409436)
		(end 113.039091 93.409435)
		(width 0.13)
		(layer "In2.Cu")
		(net 205)
	)
	(segment
		(start 112.625502 94.38871)
		(end 112.625501 94.388711)
		(width 0.13)
		(layer "In2.Cu")
		(net 205)
	)
	(segment
		(start 119.97751 96.72249)
		(end 119.97751 97.32249)
		(width 0.13)
		(layer "In2.Cu")
		(net 205)
	)
	(segment
		(start 116.63249 97.52249)
		(end 116.97751 97.52249)
		(width 0.13)
		(layer "In2.Cu")
		(net 205)
	)
	(segment
		(start 114.170461 94.540805)
		(end 114.052055 94.659212)
		(width 0.13)
		(layer "In2.Cu")
		(net 205)
	)
	(segment
		(start 113.191186 94.954396)
		(end 113.887617 94.257962)
		(width 0.13)
		(layer "In2.Cu")
		(net 205)
	)
	(segment
		(start 117.57751 96.72249)
		(end 117.57751 97.92249)
		(width 0.13)
		(layer "In2.Cu")
		(net 205)
	)
	(segment
		(start 113.039091 93.409435)
		(end 112.342659 94.105868)
		(width 0.13)
		(layer "In2.Cu")
		(net 205)
	)
	(segment
		(start 118.37751 96.72249)
		(end 118.37751 97.92249)
		(width 0.13)
		(layer "In2.Cu")
		(net 205)
	)
	(segment
		(start 129.085 95.259473)
		(end 129.085 94.965)
		(width 0.13)
		(layer "In2.Cu")
		(net 205)
	)
	(segment
		(start 112.625501 94.388711)
		(end 113.321932 93.692277)
		(width 0.13)
		(layer "In2.Cu")
		(net 205)
	)
	(segment
		(start 114.170462 94.257963)
		(end 114.170461 94.257963)
		(width 0.13)
		(layer "In2.Cu")
		(net 205)
	)
	(segment
		(start 103.8 77.6)
		(end 105.62 79.42)
		(width 0.13)
		(layer "In2.Cu")
		(net 205)
	)
	(segment
		(start 101.905697 77.4)
		(end 102.197261 77.108436)
		(width 0.13)
		(layer "In2.Cu")
		(net 205)
	)
	(segment
		(start 112.908344 94.954395)
		(end 112.908344 94.954396)
		(width 0.13)
		(layer "In2.Cu")
		(net 205)
	)
	(segment
		(start 114.052054 94.942054)
		(end 116.63249 97.52249)
		(width 0.13)
		(layer "In2.Cu")
		(net 205)
	)
	(segment
		(start 113.604776 93.97512)
		(end 112.908344 94.671553)
		(width 0.13)
		(layer "In2.Cu")
		(net 205)
	)
	(segment
		(start 103.314624 77.108436)
		(end 103.8 77.593812)
		(width 0.13)
		(layer "In2.Cu")
		(net 205)
	)
	(segment
		(start 119.17751 96.72249)
		(end 119.17751 97.92249)
		(width 0.13)
		(layer "In2.Cu")
		(net 205)
	)
	(segment
		(start 127.849473 96.495)
		(end 129.085 95.259473)
		(width 0.13)
		(layer "In2.Cu")
		(net 205)
	)
	(segment
		(start 112.342659 94.38871)
		(end 112.342659 94.388711)
		(width 0.13)
		(layer "In2.Cu")
		(net 205)
	)
	(segment
		(start 113.191187 94.954395)
		(end 113.191186 94.954396)
		(width 0.13)
		(layer "In2.Cu")
		(net 205)
	)
	(segment
		(start 114.052055 94.942054)
		(end 114.052054 94.942054)
		(width 0.13)
		(layer "In2.Cu")
		(net 205)
	)
	(segment
		(start 103.8 77.593812)
		(end 103.8 77.6)
		(width 0.13)
		(layer "In2.Cu")
		(net 205)
	)
	(segment
		(start 129.085 94.965)
		(end 129.36 94.69)
		(width 0.13)
		(layer "In2.Cu")
		(net 205)
	)
	(segment
		(start 113.604775 93.975121)
		(end 113.604776 93.97512)
		(width 0.13)
		(layer "In2.Cu")
		(net 205)
	)
	(segment
		(start 114.17046 94.540806)
		(end 114.170461 94.540805)
		(width 0.13)
		(layer "In2.Cu")
		(net 205)
	)
	(segment
		(start 124.855 96.515)
		(end 126.96 96.515)
		(width 0.13)
		(layer "In2.Cu")
		(net 205)
	)
	(arc
		(start 119.17751 97.92249)
		(mid 119.236089 98.063911)
		(end 119.37751 98.12249)
		(width 0.13)
		(layer "In2.Cu")
		(net 205)
	)
	(arc
		(start 117.57751 97.92249)
		(mid 117.636089 98.063911)
		(end 117.77751 98.12249)
		(width 0.13)
		(layer "In2.Cu")
		(net 205)
	)
	(arc
		(start 114.170461 94.257963)
		(mid 114.229039 94.399385)
		(end 114.17046 94.540806)
		(width 0.13)
		(layer "In2.Cu")
		(net 205)
	)
	(arc
		(start 118.77751 96.72249)
		(mid 118.836089 96.581069)
		(end 118.97751 96.52249)
		(width 0.13)
		(layer "In2.Cu")
		(net 205)
	)
	(arc
		(start 113.321932 93.692277)
		(mid 113.463355 93.6337)
		(end 113.604777 93.692278)
		(width 0.13)
		(layer "In2.Cu")
		(net 205)
	)
	(arc
		(start 119.37751 98.12249)
		(mid 119.518931 98.063911)
		(end 119.57751 97.92249)
		(width 0.13)
		(layer "In2.Cu")
		(net 205)
	)
	(arc
		(start 112.342659 94.388711)
		(mid 112.484081 94.447289)
		(end 112.625502 94.38871)
		(width 0.13)
		(layer "In2.Cu")
		(net 205)
	)
	(arc
		(start 112.756249 93.126594)
		(mid 112.897669 93.068015)
		(end 113.039091 93.126594)
		(width 0.13)
		(layer "In2.Cu")
		(net 205)
	)
	(arc
		(start 118.17751 96.52249)
		(mid 118.318931 96.581069)
		(end 118.37751 96.72249)
		(width 0.13)
		(layer "In2.Cu")
		(net 205)
	)
	(arc
		(start 114.052055 94.659212)
		(mid 113.993476 94.800632)
		(end 114.052055 94.942054)
		(width 0.13)
		(layer "In2.Cu")
		(net 205)
	)
	(arc
		(start 119.57751 96.72249)
		(mid 119.636089 96.581069)
		(end 119.77751 96.52249)
		(width 0.13)
		(layer "In2.Cu")
		(net 205)
	)
	(arc
		(start 118.57751 98.12249)
		(mid 118.718931 98.063911)
		(end 118.77751 97.92249)
		(width 0.13)
		(layer "In2.Cu")
		(net 205)
	)
	(arc
		(start 117.17751 96.72249)
		(mid 117.236089 96.581069)
		(end 117.37751 96.52249)
		(width 0.13)
		(layer "In2.Cu")
		(net 205)
	)
	(arc
		(start 118.37751 97.92249)
		(mid 118.436089 98.063911)
		(end 118.57751 98.12249)
		(width 0.13)
		(layer "In2.Cu")
		(net 205)
	)
	(arc
		(start 117.77751 98.12249)
		(mid 117.918931 98.063911)
		(end 117.97751 97.92249)
		(width 0.13)
		(layer "In2.Cu")
		(net 205)
	)
	(arc
		(start 112.342659 94.105868)
		(mid 112.284081 94.247289)
		(end 112.342659 94.38871)
		(width 0.13)
		(layer "In2.Cu")
		(net 205)
	)
	(arc
		(start 113.604776 93.692278)
		(mid 113.663354 93.8337)
		(end 113.604775 93.975121)
		(width 0.13)
		(layer "In2.Cu")
		(net 205)
	)
	(arc
		(start 113.887617 94.257962)
		(mid 114.02904 94.199385)
		(end 114.170462 94.257963)
		(width 0.13)
		(layer "In2.Cu")
		(net 205)
	)
	(arc
		(start 112.908344 94.671553)
		(mid 112.849766 94.812974)
		(end 112.908344 94.954395)
		(width 0.13)
		(layer "In2.Cu")
		(net 205)
	)
	(arc
		(start 113.039091 93.126593)
		(mid 113.097669 93.268015)
		(end 113.03909 93.409436)
		(width 0.13)
		(layer "In2.Cu")
		(net 205)
	)
	(arc
		(start 117.37751 96.52249)
		(mid 117.518931 96.581069)
		(end 117.57751 96.72249)
		(width 0.13)
		(layer "In2.Cu")
		(net 205)
	)
	(arc
		(start 119.97751 97.32249)
		(mid 120.036089 97.463911)
		(end 120.17751 97.52249)
		(width 0.13)
		(layer "In2.Cu")
		(net 205)
	)
	(arc
		(start 116.97751 97.52249)
		(mid 117.118931 97.463911)
		(end 117.17751 97.32249)
		(width 0.13)
		(layer "In2.Cu")
		(net 205)
	)
	(arc
		(start 117.97751 96.72249)
		(mid 118.036089 96.581069)
		(end 118.17751 96.52249)
		(width 0.13)
		(layer "In2.Cu")
		(net 205)
	)
	(arc
		(start 112.355 93.245)
		(mid 112.496422 93.303578)
		(end 112.637843 93.244999)
		(width 0.13)
		(layer "In2.Cu")
		(net 205)
	)
	(arc
		(start 119.77751 96.52249)
		(mid 119.918931 96.581069)
		(end 119.97751 96.72249)
		(width 0.13)
		(layer "In2.Cu")
		(net 205)
	)
	(arc
		(start 112.908344 94.954396)
		(mid 113.049766 95.012974)
		(end 113.191187 94.954395)
		(width 0.13)
		(layer "In2.Cu")
		(net 205)
	)
	(arc
		(start 118.97751 96.52249)
		(mid 119.118931 96.581069)
		(end 119.17751 96.72249)
		(width 0.13)
		(layer "In2.Cu")
		(net 205)
	)
	(segment
		(start 101.23 74.91)
		(end 101.3 74.84)
		(width 0.2)
		(layer "F.Cu")
		(net 206)
	)
	(segment
		(start 99.59 74.91)
		(end 101.23 74.91)
		(width 0.2)
		(layer "F.Cu")
		(net 206)
	)
	(segment
		(start 99.1 75.4)
		(end 99.59 74.91)
		(width 0.2)
		(layer "F.Cu")
		(net 206)
	)
	(segment
		(start 129.1 93.9)
		(end 129.5 94.3)
		(width 0.2)
		(layer "F.Cu")
		(net 206)
	)
	(via
		(at 129.5 94.3)
		(size 0.45)
		(drill 0.1)
		(layers "F.Cu" "B.Cu")
		(net 206)
	)
	(via
		(at 101.3 74.84)
		(size 0.45)
		(drill 0.2)
		(layers "F.Cu" "B.Cu")
		(remove_unused_layers yes)
		(keep_end_layers yes)
		(zone_layer_connections)
		(net 206)
	)
	(segment
		(start 128.285 95.44)
		(end 128.285 94.89)
		(width 0.13)
		(layer "In2.Cu")
		(net 206)
	)
	(segment
		(start 105.644686 73.11)
		(end 106.875314 73.11)
		(width 0.13)
		(layer "In2.Cu")
		(net 206)
	)
	(segment
		(start 105.644686 71.91)
		(end 106.875314 71.91)
		(width 0.13)
		(layer "In2.Cu")
		(net 206)
	)
	(segment
		(start 124.535 96.285)
		(end 126.815 96.285)
		(width 0.13)
		(layer "In2.Cu")
		(net 206)
	)
	(segment
		(start 129.3 94.3)
		(end 129.5 94.3)
		(width 0.13)
		(layer "In2.Cu")
		(net 206)
	)
	(segment
		(start 105.644686 73.51)
		(end 106.875314 73.51)
		(width 0.13)
		(layer "In2.Cu")
		(net 206)
	)
	(segment
		(start 127.475 96.25)
		(end 128.285 95.44)
		(width 0.13)
		(layer "In2.Cu")
		(net 206)
	)
	(segment
		(start 126.815 96.285)
		(end 126.85 96.25)
		(width 0.13)
		(layer "In2.Cu")
		(net 206)
	)
	(segment
		(start 105.644686 72.31)
		(end 106.875314 72.31)
		(width 0.13)
		(layer "In2.Cu")
		(net 206)
	)
	(segment
		(start 105.644686 73.91)
		(end 106.21 73.91)
		(width 0.13)
		(layer "In2.Cu")
		(net 206)
	)
	(segment
		(start 102.17 74.64)
		(end 102.73 74.64)
		(width 0.13)
		(layer "In2.Cu")
		(net 206)
	)
	(segment
		(start 106.41 70.56)
		(end 106.41 71.31)
		(width 0.13)
		(layer "In2.Cu")
		(net 206)
	)
	(segment
		(start 102.93 74.84)
		(end 103.66 74.84)
		(width 0.13)
		(layer "In2.Cu")
		(net 206)
	)
	(segment
		(start 116.6 96.275)
		(end 124.525 96.275)
		(width 0.13)
		(layer "In2.Cu")
		(net 206)
	)
	(segment
		(start 113.894499 93.5645)
		(end 113.894499 93.569499)
		(width 0.13)
		(layer "In2.Cu")
		(net 206)
	)
	(segment
		(start 106.41 86.08)
		(end 113.894499 93.5645)
		(width 0.13)
		(layer "In2.Cu")
		(net 206)
	)
	(segment
		(start 129.075 94.525)
		(end 129.3 94.3)
		(width 0.13)
		(layer "In2.Cu")
		(net 206)
	)
	(segment
		(start 126.85 96.25)
		(end 127.475 96.25)
		(width 0.13)
		(layer "In2.Cu")
		(net 206)
	)
	(segment
		(start 101.97 74.84)
		(end 102.17 74.64)
		(width 0.13)
		(layer "In2.Cu")
		(net 206)
	)
	(segment
		(start 104.4 74.1)
		(end 104.4 70.6)
		(width 0.13)
		(layer "In2.Cu")
		(net 206)
	)
	(segment
		(start 102.73 74.64)
		(end 102.93 74.84)
		(width 0.13)
		(layer "In2.Cu")
		(net 206)
	)
	(segment
		(start 101.3 74.84)
		(end 101.97 74.84)
		(width 0.13)
		(layer "In2.Cu")
		(net 206)
	)
	(segment
		(start 103.66 74.84)
		(end 104.4 74.1)
		(width 0.13)
		(layer "In2.Cu")
		(net 206)
	)
	(segment
		(start 105.644686 72.71)
		(end 106.875314 72.71)
		(width 0.13)
		(layer "In2.Cu")
		(net 206)
	)
	(segment
		(start 128.65 94.525)
		(end 129.075 94.525)
		(width 0.13)
		(layer "In2.Cu")
		(net 206)
	)
	(segment
		(start 128.285 94.89)
		(end 128.65 94.525)
		(width 0.13)
		(layer "In2.Cu")
		(net 206)
	)
	(segment
		(start 104.4 70.6)
		(end 104.8 70.2)
		(width 0.13)
		(layer "In2.Cu")
		(net 206)
	)
	(segment
		(start 124.525 96.275)
		(end 124.535 96.285)
		(width 0.13)
		(layer "In2.Cu")
		(net 206)
	)
	(segment
		(start 113.894499 93.569499)
		(end 116.6 96.275)
		(width 0.13)
		(layer "In2.Cu")
		(net 206)
	)
	(segment
		(start 106.05 70.2)
		(end 106.41 70.56)
		(width 0.13)
		(layer "In2.Cu")
		(net 206)
	)
	(segment
		(start 106.41 74.11)
		(end 106.41 86.08)
		(width 0.13)
		(layer "In2.Cu")
		(net 206)
	)
	(segment
		(start 104.8 70.2)
		(end 106.05 70.2)
		(width 0.13)
		(layer "In2.Cu")
		(net 206)
	)
	(segment
		(start 106.61 71.51)
		(end 106.875314 71.51)
		(width 0.13)
		(layer "In2.Cu")
		(net 206)
	)
	(arc
		(start 105.644686 71.91)
		(mid 105.503265 71.968579)
		(end 105.444686 72.11)
		(width 0.13)
		(layer "In2.Cu")
		(net 206)
	)
	(arc
		(start 105.444686 72.11)
		(mid 105.503265 72.251421)
		(end 105.644686 72.31)
		(width 0.13)
		(layer "In2.Cu")
		(net 206)
	)
	(arc
		(start 107.075314 73.31)
		(mid 107.016735 73.451421)
		(end 106.875314 73.51)
		(width 0.13)
		(layer "In2.Cu")
		(net 206)
	)
	(arc
		(start 107.075314 71.71)
		(mid 107.016735 71.851421)
		(end 106.875314 71.91)
		(width 0.13)
		(layer "In2.Cu")
		(net 206)
	)
	(arc
		(start 105.444686 72.91)
		(mid 105.503265 73.051421)
		(end 105.644686 73.11)
		(width 0.13)
		(layer "In2.Cu")
		(net 206)
	)
	(arc
		(start 106.21 73.91)
		(mid 106.351421 73.968579)
		(end 106.41 74.11)
		(width 0.13)
		(layer "In2.Cu")
		(net 206)
	)
	(arc
		(start 106.875314 71.51)
		(mid 107.016735 71.568579)
		(end 107.075314 71.71)
		(width 0.13)
		(layer "In2.Cu")
		(net 206)
	)
	(arc
		(start 105.444686 73.71)
		(mid 105.503265 73.851421)
		(end 105.644686 73.91)
		(width 0.13)
		(layer "In2.Cu")
		(net 206)
	)
	(arc
		(start 106.875314 73.11)
		(mid 107.016735 73.168579)
		(end 107.075314 73.31)
		(width 0.13)
		(layer "In2.Cu")
		(net 206)
	)
	(arc
		(start 105.644686 72.71)
		(mid 105.503265 72.768579)
		(end 105.444686 72.91)
		(width 0.13)
		(layer "In2.Cu")
		(net 206)
	)
	(arc
		(start 106.875314 72.31)
		(mid 107.016735 72.368579)
		(end 107.075314 72.51)
		(width 0.13)
		(layer "In2.Cu")
		(net 206)
	)
	(arc
		(start 107.075314 72.51)
		(mid 107.016735 72.651421)
		(end 106.875314 72.71)
		(width 0.13)
		(layer "In2.Cu")
		(net 206)
	)
	(arc
		(start 105.644686 73.51)
		(mid 105.503265 73.568579)
		(end 105.444686 73.71)
		(width 0.13)
		(layer "In2.Cu")
		(net 206)
	)
	(arc
		(start 106.41 71.31)
		(mid 106.468579 71.451421)
		(end 106.61 71.51)
		(width 0.13)
		(layer "In2.Cu")
		(net 206)
	)
	(segment
		(start 129.5 89.5)
		(end 129.51 89.5)
		(width 0.2)
		(layer "F.Cu")
		(net 207)
	)
	(segment
		(start 101.86 75.4)
		(end 101.87 75.41)
		(width 0.2)
		(layer "F.Cu")
		(net 207)
	)
	(segment
		(start 129.1 89.1)
		(end 129.5 89.5)
		(width 0.2)
		(layer "F.Cu")
		(net 207)
	)
	(segment
		(start 100.1 75.4)
		(end 101.86 75.4)
		(width 0.2)
		(layer "F.Cu")
		(net 207)
	)
	(via
		(at 101.87 75.41)
		(size 0.45)
		(drill 0.2)
		(layers "F.Cu" "B.Cu")
		(remove_unused_layers yes)
		(keep_end_layers yes)
		(zone_layer_connections)
		(net 207)
	)
	(via
		(at 129.51 89.5)
		(size 0.45)
		(drill 0.1)
		(layers "F.Cu" "B.Cu")
		(net 207)
	)
	(segment
		(start 117.397132 86.45266)
		(end 117.397131 86.452659)
		(width 0.13)
		(layer "In4.Cu")
		(net 207)
	)
	(segment
		(start 116.335022 84.403506)
		(end 115.347977 85.390547)
		(width 0.13)
		(layer "In4.Cu")
		(net 207)
	)
	(segment
		(start 115.700079 84.472764)
		(end 116.05218 84.120664)
		(width 0.13)
		(layer "In4.Cu")
		(net 207)
	)
	(segment
		(start 128.851544 90.7)
		(end 129.115 90.436544)
		(width 0.13)
		(layer "In4.Cu")
		(net 207)
	)
	(segment
		(start 116.196504 86.239075)
		(end 117.183546 85.25203)
		(width 0.13)
		(layer "In4.Cu")
		(net 207)
	)
	(segment
		(start 116.196505 86.239074)
		(end 116.196504 86.239075)
		(width 0.13)
		(layer "In4.Cu")
		(net 207)
	)
	(segment
		(start 129.115 90.075)
		(end 129.51 89.68)
		(width 0.13)
		(layer "In4.Cu")
		(net 207)
	)
	(segment
		(start 102.235527 75.41)
		(end 102.240527 75.415)
		(width 0.13)
		(layer "In4.Cu")
		(net 207)
	)
	(segment
		(start 105.3 74.9)
		(end 105.3 72.3)
		(width 0.13)
		(layer "In4.Cu")
		(net 207)
	)
	(segment
		(start 105.3 72.3)
		(end 107.57 70.03)
		(width 0.13)
		(layer "In4.Cu")
		(net 207)
	)
	(segment
		(start 127.7 90.7)
		(end 128.851544 90.7)
		(width 0.13)
		(layer "In4.Cu")
		(net 207)
	)
	(segment
		(start 120.315 89.935)
		(end 121.091765 90.711765)
		(width 0.13)
		(layer "In4.Cu")
		(net 207)
	)
	(segment
		(start 115.01 84.065527)
		(end 115.417237 84.472764)
		(width 0.13)
		(layer "In4.Cu")
		(net 207)
	)
	(segment
		(start 116.900705 84.969188)
		(end 115.913662 85.956232)
		(width 0.13)
		(layer "In4.Cu")
		(net 207)
	)
	(segment
		(start 116.76219 86.804759)
		(end 116.762189 86.80476)
		(width 0.13)
		(layer "In4.Cu")
		(net 207)
	)
	(segment
		(start 102.240527 75.415)
		(end 104.785 75.415)
		(width 0.13)
		(layer "In4.Cu")
		(net 207)
	)
	(segment
		(start 121.317291 91.485)
		(end 127.231188 91.485)
		(width 0.13)
		(layer "In4.Cu")
		(net 207)
	)
	(segment
		(start 115.347977 85.673389)
		(end 115.347977 85.67339)
		(width 0.13)
		(layer "In4.Cu")
		(net 207)
	)
	(segment
		(start 127.5 90.9)
		(end 127.7 90.7)
		(width 0.13)
		(layer "In4.Cu")
		(net 207)
	)
	(segment
		(start 115.630819 85.67339)
		(end 116.617861 84.686345)
		(width 0.13)
		(layer "In4.Cu")
		(net 207)
	)
	(segment
		(start 116.479347 86.804759)
		(end 116.479347 86.80476)
		(width 0.13)
		(layer "In4.Cu")
		(net 207)
	)
	(segment
		(start 127.231188 91.485)
		(end 127.5 91.216188)
		(width 0.13)
		(layer "In4.Cu")
		(net 207)
	)
	(segment
		(start 127.5 91.216188)
		(end 127.5 90.9)
		(width 0.13)
		(layer "In4.Cu")
		(net 207)
	)
	(segment
		(start 116.900705 84.686347)
		(end 116.900705 84.686346)
		(width 0.13)
		(layer "In4.Cu")
		(net 207)
	)
	(segment
		(start 121.091765 90.711765)
		(end 121.091765 91.259474)
		(width 0.13)
		(layer "In4.Cu")
		(net 207)
	)
	(segment
		(start 115.63082 85.673389)
		(end 115.630819 85.67339)
		(width 0.13)
		(layer "In4.Cu")
		(net 207)
	)
	(segment
		(start 117.397131 86.452659)
		(end 120.315 89.370527)
		(width 0.13)
		(layer "In4.Cu")
		(net 207)
	)
	(segment
		(start 116.335023 84.120665)
		(end 116.335022 84.120664)
		(width 0.13)
		(layer "In4.Cu")
		(net 207)
	)
	(segment
		(start 116.762189 86.80476)
		(end 117.114289 86.452659)
		(width 0.13)
		(layer "In4.Cu")
		(net 207)
	)
	(segment
		(start 117.46639 85.534873)
		(end 116.479347 86.521917)
		(width 0.13)
		(layer "In4.Cu")
		(net 207)
	)
	(segment
		(start 115.01 71.31)
		(end 115.01 84.065527)
		(width 0.13)
		(layer "In4.Cu")
		(net 207)
	)
	(segment
		(start 116.335021 84.403507)
		(end 116.335022 84.403506)
		(width 0.13)
		(layer "In4.Cu")
		(net 207)
	)
	(segment
		(start 104.785 75.415)
		(end 105.3 74.9)
		(width 0.13)
		(layer "In4.Cu")
		(net 207)
	)
	(segment
		(start 121.091765 91.259474)
		(end 121.317291 91.485)
		(width 0.13)
		(layer "In4.Cu")
		(net 207)
	)
	(segment
		(start 116.900704 84.969189)
		(end 116.900705 84.969188)
		(width 0.13)
		(layer "In4.Cu")
		(net 207)
	)
	(segment
		(start 120.315 89.370527)
		(end 120.315 89.935)
		(width 0.13)
		(layer "In4.Cu")
		(net 207)
	)
	(segment
		(start 129.115 90.436544)
		(end 129.115 90.075)
		(width 0.13)
		(layer "In4.Cu")
		(net 207)
	)
	(segment
		(start 115.913662 86.239074)
		(end 115.913662 86.239075)
		(width 0.13)
		(layer "In4.Cu")
		(net 207)
	)
	(segment
		(start 117.46639 85.252032)
		(end 117.46639 85.252031)
		(width 0.13)
		(layer "In4.Cu")
		(net 207)
	)
	(segment
		(start 115.70008 84.472763)
		(end 115.700079 84.472764)
		(width 0.13)
		(layer "In4.Cu")
		(net 207)
	)
	(segment
		(start 129.51 89.68)
		(end 129.51 89.5)
		(width 0.13)
		(layer "In4.Cu")
		(net 207)
	)
	(segment
		(start 101.87 75.41)
		(end 102.235527 75.41)
		(width 0.13)
		(layer "In4.Cu")
		(net 207)
	)
	(segment
		(start 113.73 70.03)
		(end 115.01 71.31)
		(width 0.13)
		(layer "In4.Cu")
		(net 207)
	)
	(segment
		(start 107.57 70.03)
		(end 113.73 70.03)
		(width 0.13)
		(layer "In4.Cu")
		(net 207)
	)
	(segment
		(start 117.466389 85.534874)
		(end 117.46639 85.534873)
		(width 0.13)
		(layer "In4.Cu")
		(net 207)
	)
	(arc
		(start 117.183546 85.25203)
		(mid 117.324968 85.193453)
		(end 117.46639 85.252032)
		(width 0.13)
		(layer "In4.Cu")
		(net 207)
	)
	(arc
		(start 117.114289 86.452659)
		(mid 117.255711 86.394081)
		(end 117.397132 86.45266)
		(width 0.13)
		(layer "In4.Cu")
		(net 207)
	)
	(arc
		(start 117.46639 85.252031)
		(mid 117.524968 85.393453)
		(end 117.466389 85.534874)
		(width 0.13)
		(layer "In4.Cu")
		(net 207)
	)
	(arc
		(start 116.479347 86.80476)
		(mid 116.620769 86.863338)
		(end 116.76219 86.804759)
		(width 0.13)
		(layer "In4.Cu")
		(net 207)
	)
	(arc
		(start 116.617861 84.686345)
		(mid 116.759283 84.627768)
		(end 116.900705 84.686347)
		(width 0.13)
		(layer "In4.Cu")
		(net 207)
	)
	(arc
		(start 116.479347 86.521917)
		(mid 116.420769 86.663338)
		(end 116.479347 86.804759)
		(width 0.13)
		(layer "In4.Cu")
		(net 207)
	)
	(arc
		(start 116.05218 84.120664)
		(mid 116.193602 84.062086)
		(end 116.335023 84.120665)
		(width 0.13)
		(layer "In4.Cu")
		(net 207)
	)
	(arc
		(start 116.335022 84.120664)
		(mid 116.3936 84.262086)
		(end 116.335021 84.403507)
		(width 0.13)
		(layer "In4.Cu")
		(net 207)
	)
	(arc
		(start 116.900705 84.686346)
		(mid 116.959283 84.827768)
		(end 116.900704 84.969189)
		(width 0.13)
		(layer "In4.Cu")
		(net 207)
	)
	(arc
		(start 115.913662 86.239075)
		(mid 116.055084 86.297653)
		(end 116.196505 86.239074)
		(width 0.13)
		(layer "In4.Cu")
		(net 207)
	)
	(arc
		(start 115.347977 85.67339)
		(mid 115.489399 85.731968)
		(end 115.63082 85.673389)
		(width 0.13)
		(layer "In4.Cu")
		(net 207)
	)
	(arc
		(start 115.417237 84.472764)
		(mid 115.558659 84.531342)
		(end 115.70008 84.472763)
		(width 0.13)
		(layer "In4.Cu")
		(net 207)
	)
	(arc
		(start 115.347977 85.390547)
		(mid 115.289399 85.531968)
		(end 115.347977 85.673389)
		(width 0.13)
		(layer "In4.Cu")
		(net 207)
	)
	(arc
		(start 115.913662 85.956232)
		(mid 115.855084 86.097653)
		(end 115.913662 86.239074)
		(width 0.13)
		(layer "In4.Cu")
		(net 207)
	)
	(segment
		(start 98.59 75.91)
		(end 98.1 76.4)
		(width 0.15)
		(layer "F.Cu")
		(net 208)
	)
	(segment
		(start 123.899999 89.523234)
		(end 123.899999 89.500001)
		(width 0.15)
		(layer "F.Cu")
		(net 208)
	)
	(segment
		(start 98.59 75.9)
		(end 98.59 75.91)
		(width 0.15)
		(layer "F.Cu")
		(net 208)
	)
	(segment
		(start 123.899999 89.500001)
		(end 124.3 89.1)
		(width 0.15)
		(layer "F.Cu")
		(net 208)
	)
	(via
		(at 123.899999 89.523234)
		(size 0.45)
		(drill 0.2)
		(layers "F.Cu" "B.Cu")
		(remove_unused_layers yes)
		(keep_end_layers yes)
		(free yes)
		(zone_layer_connections)
		(net 208)
	)
	(via
		(at 98.59 75.9)
		(size 0.45)
		(drill 0.2)
		(layers "F.Cu" "B.Cu")
		(remove_unused_layers yes)
		(keep_end_layers yes)
		(zone_layer_connections)
		(net 208)
	)
	(segment
		(start 123.475 89.098235)
		(end 123.475 88.525982)
		(width 0.1)
		(layer "B.Cu")
		(net 208)
	)
	(segment
		(start 122.1 88.3)
		(end 115.4 88.3)
		(width 0.125)
		(layer "B.Cu")
		(net 208)
	)
	(segment
		(start 101.3 87.2)
		(end 102.2 87.2)
		(width 0.15)
		(layer "B.Cu")
		(net 208)
	)
	(segment
		(start 102.2408 88.95)
		(end 102.2408 87.3408)
		(width 0.125)
		(layer "B.Cu")
		(net 208)
	)
	(segment
		(start 98.59 75.9)
		(end 98.59 76.1)
		(width 0.15)
		(layer "B.Cu")
		(net 208)
	)
	(segment
		(start 102.5 87.2)
		(end 102.2 87.2)
		(width 0.125)
		(layer "B.Cu")
		(net 208)
	)
	(segment
		(start 99.69 78.2)
		(end 99.69 79.22)
		(width 0.15)
		(layer "B.Cu")
		(net 208)
	)
	(segment
		(start 98.59 76.1)
		(end 99.19 76.7)
		(width 0.15)
		(layer "B.Cu")
		(net 208)
	)
	(segment
		(start 102.5 87.2)
		(end 102.3816 87.2)
		(width 0.125)
		(layer "B.Cu")
		(net 208)
	)
	(segment
		(start 100.8 86.7)
		(end 101.3 87.2)
		(width 0.15)
		(layer "B.Cu")
		(net 208)
	)
	(segment
		(start 123.249018 88.3)
		(end 122.1 88.3)
		(width 0.1)
		(layer "B.Cu")
		(net 208)
	)
	(segment
		(start 115.4 88.3)
		(end 114.3 87.2)
		(width 0.125)
		(layer "B.Cu")
		(net 208)
	)
	(segment
		(start 102.2 87.2)
		(end 102.1 87.2)
		(width 0.125)
		(layer "B.Cu")
		(net 208)
	)
	(segment
		(start 99.69 79.22)
		(end 100.8 80.33)
		(width 0.15)
		(layer "B.Cu")
		(net 208)
	)
	(segment
		(start 100.8 80.33)
		(end 100.8 86.7)
		(width 0.15)
		(layer "B.Cu")
		(net 208)
	)
	(segment
		(start 114.3 87.2)
		(end 102.5 87.2)
		(width 0.125)
		(layer "B.Cu")
		(net 208)
	)
	(segment
		(start 99.19 77.7)
		(end 99.69 78.2)
		(width 0.15)
		(layer "B.Cu")
		(net 208)
	)
	(segment
		(start 102.3816 87.2)
		(end 102.2408 87.3408)
		(width 0.125)
		(layer "B.Cu")
		(net 208)
	)
	(segment
		(start 123.475 88.525982)
		(end 123.249018 88.3)
		(width 0.1)
		(layer "B.Cu")
		(net 208)
	)
	(segment
		(start 99.19 76.7)
		(end 99.19 77.7)
		(width 0.15)
		(layer "B.Cu")
		(net 208)
	)
	(segment
		(start 102.2408 87.3408)
		(end 102.1 87.2)
		(width 0.125)
		(layer "B.Cu")
		(net 208)
	)
	(segment
		(start 123.899999 89.523234)
		(end 123.475 89.098235)
		(width 0.1)
		(layer "B.Cu")
		(net 208)
	)
	(segment
		(start 103.6 87.6)
		(end 103.1 87.1)
		(width 0.15)
		(layer "F.Cu")
		(net 209)
	)
	(segment
		(start 123.099499 89.489297)
		(end 123.110703 89.489297)
		(width 0.15)
		(layer "F.Cu")
		(net 209)
	)
	(segment
		(start 123.110703 89.489297)
		(end 123.5 89.1)
		(width 0.15)
		(layer "F.Cu")
		(net 209)
	)
	(segment
		(start 93.09 79.4)
		(end 92.69 79)
		(width 0.15)
		(layer "F.Cu")
		(net 209)
	)
	(segment
		(start 103.6 88.05)
		(end 103.6 87.6)
		(width 0.15)
		(layer "F.Cu")
		(net 209)
	)
	(segment
		(start 100.6 89.25)
		(end 97.73 89.25)
		(width 0.15)
		(layer "F.Cu")
		(net 209)
	)
	(segment
		(start 97.73 89.25)
		(end 97.13 89.85)
		(width 0.15)
		(layer "F.Cu")
		(net 209)
	)
	(segment
		(start 103.43 88.22)
		(end 103.6 88.05)
		(width 0.15)
		(layer "F.Cu")
		(net 209)
	)
	(segment
		(start 102.75 87.1)
		(end 100.6 89.25)
		(width 0.15)
		(layer "F.Cu")
		(net 209)
	)
	(segment
		(start 103.1 87.1)
		(end 102.75 87.1)
		(width 0.15)
		(layer "F.Cu")
		(net 209)
	)
	(via
		(at 97.13 89.85)
		(size 0.45)
		(drill 0.2)
		(layers "F.Cu" "B.Cu")
		(remove_unused_layers yes)
		(keep_end_layers yes)
		(zone_layer_connections)
		(net 209)
	)
	(via
		(at 103.43 88.22)
		(size 0.45)
		(drill 0.2)
		(layers "F.Cu" "B.Cu")
		(net 209)
	)
	(via
		(at 92.69 79)
		(size 0.45)
		(drill 0.2)
		(layers "F.Cu" "B.Cu")
		(remove_unused_layers yes)
		(keep_end_layers yes)
		(zone_layer_connections)
		(net 209)
	)
	(via
		(at 123.099499 89.489297)
		(size 0.45)
		(drill 0.2)
		(layers "F.Cu" "B.Cu")
		(remove_unused_layers yes)
		(keep_end_layers yes)
		(free yes)
		(zone_layer_connections)
		(net 209)
	)
	(segment
		(start 114.94 88.6)
		(end 113.92 87.58)
		(width 0.125)
		(layer "B.Cu")
		(net 209)
	)
	(segment
		(start 92.69 82.5)
		(end 93.09 82.1)
		(width 0.15)
		(layer "B.Cu")
		(net 209)
	)
	(segment
		(start 104.07 87.58)
		(end 103.43 88.22)
		(width 0.15)
		(layer "B.Cu")
		(net 209)
	)
	(segment
		(start 92.69 79.424314)
		(end 92.69 79)
		(width 0.15)
		(layer "B.Cu")
		(net 209)
	)
	(segment
		(start 92.44 88.2)
		(end 92.44 85.7)
		(width 0.15)
		(layer "B.Cu")
		(net 209)
	)
	(segment
		(start 92.44 85.7)
		(end 92.69 85.45)
		(width 0.15)
		(layer "B.Cu")
		(net 209)
	)
	(segment
		(start 93.2 89.85)
		(end 92.43 89.08)
		(width 0.15)
		(layer "B.Cu")
		(net 209)
	)
	(segment
		(start 104.07 87.58)
		(end 113.92 87.58)
		(width 0.15)
		(layer "B.Cu")
		(net 209)
	)
	(segment
		(start 93.09 82.1)
		(end 93.09 79.824314)
		(width 0.15)
		(layer "B.Cu")
		(net 209)
	)
	(segment
		(start 123.099499 89.299499)
		(end 122.4 88.6)
		(width 0.125)
		(layer "B.Cu")
		(net 209)
	)
	(segment
		(start 92.43 89.08)
		(end 92.43 88.21)
		(width 0.15)
		(layer "B.Cu")
		(net 209)
	)
	(segment
		(start 93.09 79.824314)
		(end 92.69 79.424314)
		(width 0.15)
		(layer "B.Cu")
		(net 209)
	)
	(segment
		(start 92.69 85.45)
		(end 92.69 82.5)
		(width 0.15)
		(layer "B.Cu")
		(net 209)
	)
	(segment
		(start 123.099499 89.489297)
		(end 123.099499 89.299499)
		(width 0.125)
		(layer "B.Cu")
		(net 209)
	)
	(segment
		(start 122.4 88.6)
		(end 114.94 88.6)
		(width 0.125)
		(layer "B.Cu")
		(net 209)
	)
	(segment
		(start 97.13 89.85)
		(end 93.2 89.85)
		(width 0.15)
		(layer "B.Cu")
		(net 209)
	)
	(segment
		(start 101.87 74.4)
		(end 100.1 74.4)
		(width 0.2)
		(layer "F.Cu")
		(net 210)
	)
	(segment
		(start 128.7 90.3)
		(end 129.1 89.9)
		(width 0.182)
		(layer "F.Cu")
		(net 210)
	)
	(via
		(at 128.7 90.3)
		(size 0.45)
		(drill 0.2)
		(layers "F.Cu" "B.Cu")
		(remove_unused_layers yes)
		(keep_end_layers yes)
		(zone_layer_connections)
		(net 210)
	)
	(via
		(at 101.87 74.4)
		(size 0.45)
		(drill 0.2)
		(layers "F.Cu" "B.Cu")
		(remove_unused_layers yes)
		(keep_end_layers yes)
		(zone_layer_connections)
		(net 210)
	)
	(segment
		(start 121.085 89.735)
		(end 122.065 90.715)
		(width 0.13)
		(layer "In4.Cu")
		(net 210)
	)
	(segment
		(start 116.535 78.615)
		(end 116.96 79.04)
		(width 0.13)
		(layer "In4.Cu")
		(net 210)
	)
	(segment
		(start 118.657053 80.737054)
		(end 118.657052 80.737053)
		(width 0.13)
		(layer "In4.Cu")
		(net 210)
	)
	(segment
		(start 116.535 70.335)
		(end 116.535 78.615)
		(width 0.13)
		(layer "In4.Cu")
		(net 210)
	)
	(segment
		(start 118.23279 80.31279)
		(end 117.75686 80.788719)
		(width 0.13)
		(layer "In4.Cu")
		(net 210)
	)
	(segment
		(start 103.3 74.4)
		(end 103.488643 74.211361)
		(width 0.13)
		(layer "In4.Cu")
		(net 210)
	)
	(segment
		(start 116.837623 80.010903)
		(end 117.930901 78.91762)
		(width 0.13)
		(layer "In4.Cu")
		(net 210)
	)
	(segment
		(start 118.213744 79.200465)
		(end 118.213745 79.200464)
		(width 0.13)
		(layer "In4.Cu")
		(net 210)
	)
	(segment
		(start 116.55478 80.010903)
		(end 116.554781 80.010903)
		(width 0.13)
		(layer "In4.Cu")
		(net 210)
	)
	(segment
		(start 102 71.87)
		(end 102.47 71.4)
		(width 0.13)
		(layer "In4.Cu")
		(net 210)
	)
	(segment
		(start 102.47 71.4)
		(end 104.3 71.4)
		(width 0.13)
		(layer "In4.Cu")
		(net 210)
	)
	(segment
		(start 103.488643 74.211361)
		(end 103.488643 74.211357)
		(width 0.13)
		(layer "In4.Cu")
		(net 210)
	)
	(segment
		(start 116.837624 80.010902)
		(end 116.837623 80.010903)
		(width 0.13)
		(layer "In4.Cu")
		(net 210)
	)
	(segment
		(start 118.213746 78.917623)
		(end 118.213745 78.917622)
		(width 0.13)
		(layer "In4.Cu")
		(net 210)
	)
	(segment
		(start 117.403307 80.576586)
		(end 117.403306 80.576587)
		(width 0.13)
		(layer "In4.Cu")
		(net 210)
	)
	(segment
		(start 103.9 73.1)
		(end 103.5 72.7)
		(width 0.13)
		(layer "In4.Cu")
		(net 210)
	)
	(segment
		(start 122.065 90.715)
		(end 126.485 90.715)
		(width 0.13)
		(layer "In4.Cu")
		(net 210)
	)
	(segment
		(start 102 72.3)
		(end 102 71.87)
		(width 0.13)
		(layer "In4.Cu")
		(net 210)
	)
	(segment
		(start 103.488643 74.211357)
		(end 103.9 73.8)
		(width 0.13)
		(layer "In4.Cu")
		(net 210)
	)
	(segment
		(start 117.667103 79.747103)
		(end 117.667105 79.747105)
		(width 0.13)
		(layer "In4.Cu")
		(net 210)
	)
	(segment
		(start 118.657052 80.737053)
		(end 120.285 82.365)
		(width 0.13)
		(layer "In4.Cu")
		(net 210)
	)
	(segment
		(start 117.667105 79.747105)
		(end 117.120464 80.293745)
		(width 0.13)
		(layer "In4.Cu")
		(net 210)
	)
	(segment
		(start 117.120465 80.576588)
		(end 117.120464 80.576587)
		(width 0.13)
		(layer "In4.Cu")
		(net 210)
	)
	(segment
		(start 117.403306 80.576587)
		(end 118.496586 79.483305)
		(width 0.13)
		(layer "In4.Cu")
		(net 210)
	)
	(segment
		(start 118.039703 81.071561)
		(end 118.039702 81.071562)
		(width 0.13)
		(layer "In4.Cu")
		(net 210)
	)
	(segment
		(start 120.285 88.305)
		(end 121.085 89.105)
		(width 0.13)
		(layer "In4.Cu")
		(net 210)
	)
	(segment
		(start 117.75686 81.071561)
		(end 117.75686 81.071562)
		(width 0.13)
		(layer "In4.Cu")
		(net 210)
	)
	(segment
		(start 118.213745 79.200464)
		(end 117.667103 79.747103)
		(width 0.13)
		(layer "In4.Cu")
		(net 210)
	)
	(segment
		(start 126.485 90.715)
		(end 126.9 90.3)
		(width 0.13)
		(layer "In4.Cu")
		(net 210)
	)
	(segment
		(start 121.085 89.105)
		(end 121.085 89.735)
		(width 0.13)
		(layer "In4.Cu")
		(net 210)
	)
	(segment
		(start 118.779431 79.483308)
		(end 118.77943 79.483307)
		(width 0.13)
		(layer "In4.Cu")
		(net 210)
	)
	(segment
		(start 118.779429 79.76615)
		(end 118.77943 79.766149)
		(width 0.13)
		(layer "In4.Cu")
		(net 210)
	)
	(segment
		(start 114.9 68.7)
		(end 116.535 70.335)
		(width 0.13)
		(layer "In4.Cu")
		(net 210)
	)
	(segment
		(start 102.4 72.7)
		(end 102 72.3)
		(width 0.13)
		(layer "In4.Cu")
		(net 210)
	)
	(segment
		(start 118.039702 81.071562)
		(end 118.37421 80.737053)
		(width 0.13)
		(layer "In4.Cu")
		(net 210)
	)
	(segment
		(start 103.5 72.7)
		(end 102.4 72.7)
		(width 0.13)
		(layer "In4.Cu")
		(net 210)
	)
	(segment
		(start 120.285 82.365)
		(end 120.285 88.305)
		(width 0.13)
		(layer "In4.Cu")
		(net 210)
	)
	(segment
		(start 126.9 90.3)
		(end 128.7 90.3)
		(width 0.13)
		(layer "In4.Cu")
		(net 210)
	)
	(segment
		(start 116.959999 79.322843)
		(end 116.96 79.322842)
		(width 0.13)
		(layer "In4.Cu")
		(net 210)
	)
	(segment
		(start 104.3 71.4)
		(end 107 68.7)
		(width 0.13)
		(layer "In4.Cu")
		(net 210)
	)
	(segment
		(start 118.232788 80.312788)
		(end 118.23279 80.31279)
		(width 0.13)
		(layer "In4.Cu")
		(net 210)
	)
	(segment
		(start 116.96 79.322842)
		(end 116.554781 79.72806)
		(width 0.13)
		(layer "In4.Cu")
		(net 210)
	)
	(segment
		(start 107 68.7)
		(end 114.9 68.7)
		(width 0.13)
		(layer "In4.Cu")
		(net 210)
	)
	(segment
		(start 118.77943 79.766149)
		(end 118.232788 80.312788)
		(width 0.13)
		(layer "In4.Cu")
		(net 210)
	)
	(segment
		(start 103.9 73.8)
		(end 103.9 73.1)
		(width 0.13)
		(layer "In4.Cu")
		(net 210)
	)
	(segment
		(start 101.87 74.4)
		(end 103.3 74.4)
		(width 0.13)
		(layer "In4.Cu")
		(net 210)
	)
	(arc
		(start 117.120464 80.576587)
		(mid 117.261886 80.635165)
		(end 117.403307 80.576586)
		(width 0.13)
		(layer "In4.Cu")
		(net 210)
	)
	(arc
		(start 118.213745 78.917622)
		(mid 118.272323 79.059044)
		(end 118.213744 79.200465)
		(width 0.13)
		(layer "In4.Cu")
		(net 210)
	)
	(arc
		(start 117.75686 80.788719)
		(mid 117.698282 80.93014)
		(end 117.75686 81.071561)
		(width 0.13)
		(layer "In4.Cu")
		(net 210)
	)
	(arc
		(start 116.554781 79.72806)
		(mid 116.496202 79.869481)
		(end 116.55478 80.010903)
		(width 0.13)
		(layer "In4.Cu")
		(net 210)
	)
	(arc
		(start 116.554781 80.010903)
		(mid 116.696203 80.069481)
		(end 116.837624 80.010902)
		(width 0.13)
		(layer "In4.Cu")
		(net 210)
	)
	(arc
		(start 118.37421 80.737053)
		(mid 118.515632 80.678475)
		(end 118.657053 80.737054)
		(width 0.13)
		(layer "In4.Cu")
		(net 210)
	)
	(arc
		(start 117.75686 81.071562)
		(mid 117.898282 81.13014)
		(end 118.039703 81.071561)
		(width 0.13)
		(layer "In4.Cu")
		(net 210)
	)
	(arc
		(start 117.930901 78.91762)
		(mid 118.072325 78.859044)
		(end 118.213746 78.917623)
		(width 0.13)
		(layer "In4.Cu")
		(net 210)
	)
	(arc
		(start 118.496586 79.483305)
		(mid 118.63801 79.424729)
		(end 118.779431 79.483308)
		(width 0.13)
		(layer "In4.Cu")
		(net 210)
	)
	(arc
		(start 116.96 79.04)
		(mid 117.018578 79.181422)
		(end 116.959999 79.322843)
		(width 0.13)
		(layer "In4.Cu")
		(net 210)
	)
	(arc
		(start 118.77943 79.483307)
		(mid 118.838008 79.624729)
		(end 118.779429 79.76615)
		(width 0.13)
		(layer "In4.Cu")
		(net 210)
	)
	(arc
		(start 117.120464 80.293745)
		(mid 117.061886 80.435167)
		(end 117.120465 80.576588)
		(width 0.13)
		(layer "In4.Cu")
		(net 210)
	)
	(segment
		(start 129.9 88.3)
		(end 130.3 88.7)
		(width 0.182)
		(layer "F.Cu")
		(net 211)
	)
	(segment
		(start 99.62 73.88)
		(end 99.1 74.4)
		(width 0.2)
		(layer "F.Cu")
		(net 211)
	)
	(segment
		(start 99.62 72.34)
		(end 99.62 73.88)
		(width 0.2)
		(layer "F.Cu")
		(net 211)
	)
	(segment
		(start 99.83 72.13)
		(end 99.62 72.34)
		(width 0.2)
		(layer "F.Cu")
		(net 211)
	)
	(via
		(at 130.3 88.7)
		(size 0.45)
		(drill 0.2)
		(layers "F.Cu" "B.Cu")
		(remove_unused_layers yes)
		(keep_end_layers yes)
		(zone_layer_connections)
		(net 211)
	)
	(via
		(at 99.83 72.13)
		(size 0.45)
		(drill 0.2)
		(layers "F.Cu" "B.Cu")
		(remove_unused_layers yes)
		(keep_end_layers yes)
		(zone_layer_connections)
		(net 211)
	)
	(segment
		(start 124.059421 89.88)
		(end 128.93 89.88)
		(width 0.13)
		(layer "In4.Cu")
		(net 211)
	)
	(segment
		(start 121.915 88.859473)
		(end 121.915 89.659473)
		(width 0.13)
		(layer "In4.Cu")
		(net 211)
	)
	(segment
		(start 115.75 67.75)
		(end 117.6 69.6)
		(width 0.13)
		(layer "In4.Cu")
		(net 211)
	)
	(segment
		(start 121.105858 79.591195)
		(end 121.105857 79.591194)
		(width 0.13)
		(layer "In4.Cu")
		(net 211)
	)
	(segment
		(start 121.115 88.059473)
		(end 121.915 88.859473)
		(width 0.13)
		(layer "In4.Cu")
		(net 211)
	)
	(segment
		(start 120.874209 80.954209)
		(end 120.874209 80.95421)
		(width 0.13)
		(layer "In4.Cu")
		(net 211)
	)
	(segment
		(start 124.051187 89.888234)
		(end 124.059421 89.88)
		(width 0.13)
		(layer "In4.Cu")
		(net 211)
	)
	(segment
		(start 129.09 89.72)
		(end 129.09 89.32)
		(width 0.13)
		(layer "In4.Cu")
		(net 211)
	)
	(segment
		(start 128.93 89.88)
		(end 129.09 89.72)
		(width 0.13)
		(layer "In4.Cu")
		(net 211)
	)
	(segment
		(start 120.540174 79.025511)
		(end 120.540173 79.025511)
		(width 0.13)
		(layer "In4.Cu")
		(net 211)
	)
	(segment
		(start 129.89 89.11)
		(end 130.3 88.7)
		(width 0.13)
		(layer "In4.Cu")
		(net 211)
	)
	(segment
		(start 119.742843 79.539999)
		(end 119.742842 79.54)
		(width 0.13)
		(layer "In4.Cu")
		(net 211)
	)
	(segment
		(start 121.115 81.195)
		(end 121.115 88.059473)
		(width 0.13)
		(layer "In4.Cu")
		(net 211)
	)
	(segment
		(start 129.3 89.11)
		(end 129.89 89.11)
		(width 0.13)
		(layer "In4.Cu")
		(net 211)
	)
	(segment
		(start 119.884262 79.964262)
		(end 119.228351 80.620172)
		(width 0.13)
		(layer "In4.Cu")
		(net 211)
	)
	(segment
		(start 100.3 72.13)
		(end 104.68 67.75)
		(width 0.13)
		(layer "In4.Cu")
		(net 211)
	)
	(segment
		(start 120.874209 80.95421)
		(end 121.115 81.195)
		(width 0.13)
		(layer "In4.Cu")
		(net 211)
	)
	(segment
		(start 119.511193 80.903014)
		(end 120.823013 79.591192)
		(width 0.13)
		(layer "In4.Cu")
		(net 211)
	)
	(segment
		(start 121.105856 79.874037)
		(end 121.105857 79.874036)
		(width 0.13)
		(layer "In4.Cu")
		(net 211)
	)
	(segment
		(start 120.076878 81.468699)
		(end 120.591366 80.95421)
		(width 0.13)
		(layer "In4.Cu")
		(net 211)
	)
	(segment
		(start 122.143761 89.888234)
		(end 124.051187 89.888234)
		(width 0.13)
		(layer "In4.Cu")
		(net 211)
	)
	(segment
		(start 120.449945 80.529945)
		(end 120.449947 80.529947)
		(width 0.13)
		(layer "In4.Cu")
		(net 211)
	)
	(segment
		(start 117.6 77.68)
		(end 119.46 79.54)
		(width 0.13)
		(layer "In4.Cu")
		(net 211)
	)
	(segment
		(start 104.68 67.75)
		(end 115.75 67.75)
		(width 0.13)
		(layer "In4.Cu")
		(net 211)
	)
	(segment
		(start 119.742842 79.54)
		(end 120.257331 79.025512)
		(width 0.13)
		(layer "In4.Cu")
		(net 211)
	)
	(segment
		(start 119.794037 81.4687)
		(end 119.794036 81.468699)
		(width 0.13)
		(layer "In4.Cu")
		(net 211)
	)
	(segment
		(start 129.09 89.32)
		(end 129.3 89.11)
		(width 0.13)
		(layer "In4.Cu")
		(net 211)
	)
	(segment
		(start 121.105857 79.874036)
		(end 120.449945 80.529945)
		(width 0.13)
		(layer "In4.Cu")
		(net 211)
	)
	(segment
		(start 121.915 89.659473)
		(end 122.143761 89.888234)
		(width 0.13)
		(layer "In4.Cu")
		(net 211)
	)
	(segment
		(start 99.83 72.13)
		(end 100.3 72.13)
		(width 0.13)
		(layer "In4.Cu")
		(net 211)
	)
	(segment
		(start 120.449947 80.529947)
		(end 119.794036 81.185857)
		(width 0.13)
		(layer "In4.Cu")
		(net 211)
	)
	(segment
		(start 120.540172 79.308354)
		(end 120.540173 79.308353)
		(width 0.13)
		(layer "In4.Cu")
		(net 211)
	)
	(segment
		(start 117.6 69.6)
		(end 117.6 77.68)
		(width 0.13)
		(layer "In4.Cu")
		(net 211)
	)
	(segment
		(start 120.076879 81.468698)
		(end 120.076878 81.468699)
		(width 0.13)
		(layer "In4.Cu")
		(net 211)
	)
	(segment
		(start 119.884263 79.964264)
		(end 119.884262 79.964262)
		(width 0.13)
		(layer "In4.Cu")
		(net 211)
	)
	(segment
		(start 120.540173 79.308353)
		(end 119.884263 79.964264)
		(width 0.13)
		(layer "In4.Cu")
		(net 211)
	)
	(segment
		(start 119.228352 80.903015)
		(end 119.228351 80.903014)
		(width 0.13)
		(layer "In4.Cu")
		(net 211)
	)
	(segment
		(start 119.511194 80.903013)
		(end 119.511193 80.903014)
		(width 0.13)
		(layer "In4.Cu")
		(net 211)
	)
	(arc
		(start 119.228351 80.903014)
		(mid 119.369773 80.961592)
		(end 119.511194 80.903013)
		(width 0.13)
		(layer "In4.Cu")
		(net 211)
	)
	(arc
		(start 120.823013 79.591192)
		(mid 120.964437 79.532616)
		(end 121.105858 79.591195)
		(width 0.13)
		(layer "In4.Cu")
		(net 211)
	)
	(arc
		(start 120.257331 79.025512)
		(mid 120.398752 78.966933)
		(end 120.540174 79.025511)
		(width 0.13)
		(layer "In4.Cu")
		(net 211)
	)
	(arc
		(start 119.228351 80.620172)
		(mid 119.169773 80.761594)
		(end 119.228352 80.903015)
		(width 0.13)
		(layer "In4.Cu")
		(net 211)
	)
	(arc
		(start 121.105857 79.591194)
		(mid 121.164435 79.732616)
		(end 121.105856 79.874037)
		(width 0.13)
		(layer "In4.Cu")
		(net 211)
	)
	(arc
		(start 119.794036 81.185857)
		(mid 119.735458 81.327279)
		(end 119.794037 81.4687)
		(width 0.13)
		(layer "In4.Cu")
		(net 211)
	)
	(arc
		(start 119.46 79.54)
		(mid 119.601422 79.598578)
		(end 119.742843 79.539999)
		(width 0.13)
		(layer "In4.Cu")
		(net 211)
	)
	(arc
		(start 119.794036 81.468699)
		(mid 119.935458 81.527277)
		(end 120.076879 81.468698)
		(width 0.13)
		(layer "In4.Cu")
		(net 211)
	)
	(arc
		(start 120.540173 79.025511)
		(mid 120.598751 79.166933)
		(end 120.540172 79.308354)
		(width 0.13)
		(layer "In4.Cu")
		(net 211)
	)
	(arc
		(start 120.591366 80.95421)
		(mid 120.732787 80.895631)
		(end 120.874209 80.954209)
		(width 0.13)
		(layer "In4.Cu")
		(net 211)
	)
	(segment
		(start 95.24 72.12)
		(end 94.65 72.71)
		(width 0.15)
		(layer "F.Cu")
		(net 212)
	)
	(segment
		(start 95.370051 68.592173)
		(end 95.24 68.722224)
		(width 0.15)
		(layer "F.Cu")
		(net 212)
	)
	(segment
		(start 95.24 68.722224)
		(end 95.24 72.12)
		(width 0.15)
		(layer "F.Cu")
		(net 212)
	)
	(segment
		(start 95.822224 68.14)
		(end 96.75 68.14)
		(width 0.15)
		(layer "F.Cu")
		(net 212)
	)
	(segment
		(start 95.370051 68.592173)
		(end 95.822224 68.14)
		(width 0.15)
		(layer "F.Cu")
		(net 212)
	)
	(segment
		(start 94.65 73.63)
		(end 95.1 74.08)
		(width 0.15)
		(layer "F.Cu")
		(net 212)
	)
	(segment
		(start 131.9 87.1)
		(end 131.5 87.5)
		(width 0.15)
		(layer "F.Cu")
		(net 212)
	)
	(segment
		(start 97.44 68.83)
		(end 98.3692 68.83)
		(width 0.15)
		(layer "F.Cu")
		(net 212)
	)
	(segment
		(start 96.75 68.14)
		(end 97.44 68.83)
		(width 0.15)
		(layer "F.Cu")
		(net 212)
	)
	(segment
		(start 95.1 74.08)
		(end 95.1 74.4)
		(width 0.15)
		(layer "F.Cu")
		(net 212)
	)
	(segment
		(start 98.3692 68.83)
		(end 99 68.1992)
		(width 0.15)
		(layer "F.Cu")
		(net 212)
	)
	(segment
		(start 94.65 72.71)
		(end 94.65 73.63)
		(width 0.15)
		(layer "F.Cu")
		(net 212)
	)
	(via
		(at 93.36 67.9)
		(size 0.45)
		(drill 0.2)
		(layers "F.Cu" "B.Cu")
		(remove_unused_layers yes)
		(keep_end_layers yes)
		(zone_layer_connections)
		(net 212)
	)
	(via
		(at 131.9 87.1)
		(size 0.45)
		(drill 0.2)
		(layers "F.Cu" "B.Cu")
		(remove_unused_layers yes)
		(keep_end_layers yes)
		(zone_layer_connections)
		(net 212)
	)
	(via
		(at 95.370051 68.592173)
		(size 0.45)
		(drill 0.2)
		(layers "F.Cu" "B.Cu")
		(remove_unused_layers yes)
		(keep_end_layers yes)
		(zone_layer_connections)
		(net 212)
	)
	(segment
		(start 94.052173 68.592173)
		(end 93.36 67.9)
		(width 0.15)
		(layer "B.Cu")
		(net 212)
	)
	(segment
		(start 95.370051 68.592173)
		(end 94.052173 68.592173)
		(width 0.15)
		(layer "B.Cu")
		(net 212)
	)
	(segment
		(start 103.38 99.08)
		(end 92.4 88.1)
		(width 0.13)
		(layer "In2.Cu")
		(net 212)
	)
	(segment
		(start 92.4 88.1)
		(end 92.4 83.1)
		(width 0.13)
		(layer "In2.Cu")
		(net 212)
	)
	(segment
		(start 126 102.1)
		(end 125.6 102.1)
		(width 0.125)
		(layer "In2.Cu")
		(net 212)
	)
	(segment
		(start 115.4 102.1)
		(end 109.6 102.1)
		(width 0.13)
		(layer "In2.Cu")
		(net 212)
	)
	(segment
		(start 127.985 100.915)
		(end 127.363615 100.915)
		(width 0.13)
		(layer "In2.Cu")
		(net 212)
	)
	(segment
		(start 135.03 86.64)
		(end 135.5 87.11)
		(width 0.13)
		(layer "In2.Cu")
		(net 212)
	)
	(segment
		(start 136.08 92.568615)
		(end 136.08 97.01)
		(width 0.13)
		(layer "In2.Cu")
		(net 212)
	)
	(segment
		(start 135.135 91.165)
		(end 135.135 91.623615)
		(width 0.13)
		(layer "In2.Cu")
		(net 212)
	)
	(segment
		(start 109.6 102.1)
		(end 106.58 99.08)
		(width 0.13)
		(layer "In2.Cu")
		(net 212)
	)
	(segment
		(start 135.5 87.11)
		(end 135.5 90.8)
		(width 0.13)
		(layer "In2.Cu")
		(net 212)
	)
	(segment
		(start 129.7 99.2)
		(end 127.985 100.915)
		(width 0.13)
		(layer "In2.Cu")
		(net 212)
	)
	(segment
		(start 125.1 101.6)
		(end 115.9 101.6)
		(width 0.125)
		(layer "In2.Cu")
		(net 212)
	)
	(segment
		(start 135.135 91.623615)
		(end 136.08 92.568615)
		(width 0.13)
		(layer "In2.Cu")
		(net 212)
	)
	(segment
		(start 131.9 87.1)
		(end 132.36 86.64)
		(width 0.13)
		(layer "In2.Cu")
		(net 212)
	)
	(segment
		(start 136.08 97.01)
		(end 135.075 98.015)
		(width 0.13)
		(layer "In2.Cu")
		(net 212)
	)
	(segment
		(start 125.6 102.1)
		(end 125.1 101.6)
		(width 0.125)
		(layer "In2.Cu")
		(net 212)
	)
	(segment
		(start 130.885 98.015)
		(end 132.285 98.015)
		(width 0.125)
		(layer "In2.Cu")
		(net 212)
	)
	(segment
		(start 93.1 68.16)
		(end 93.36 67.9)
		(width 0.13)
		(layer "In2.Cu")
		(net 212)
	)
	(segment
		(start 129.7 99.2)
		(end 130.885 98.015)
		(width 0.125)
		(layer "In2.Cu")
		(net 212)
	)
	(segment
		(start 127.363615 100.915)
		(end 126.178615 102.1)
		(width 0.13)
		(layer "In2.Cu")
		(net 212)
	)
	(segment
		(start 132.36 86.64)
		(end 135.03 86.64)
		(width 0.13)
		(layer "In2.Cu")
		(net 212)
	)
	(segment
		(start 106.58 99.08)
		(end 103.38 99.08)
		(width 0.13)
		(layer "In2.Cu")
		(net 212)
	)
	(segment
		(start 115.9 101.6)
		(end 115.4 102.1)
		(width 0.125)
		(layer "In2.Cu")
		(net 212)
	)
	(segment
		(start 135.5 90.8)
		(end 135.135 91.165)
		(width 0.13)
		(layer "In2.Cu")
		(net 212)
	)
	(segment
		(start 135.075 98.015)
		(end 132.285 98.015)
		(width 0.13)
		(layer "In2.Cu")
		(net 212)
	)
	(segment
		(start 92.4 83.1)
		(end 93.1 82.4)
		(width 0.13)
		(layer "In2.Cu")
		(net 212)
	)
	(segment
		(start 126.178615 102.1)
		(end 126 102.1)
		(width 0.13)
		(layer "In2.Cu")
		(net 212)
	)
	(segment
		(start 93.1 82.4)
		(end 93.1 68.16)
		(width 0.13)
		(layer "In2.Cu")
		(net 212)
	)
	(segment
		(start 98.6 73.9)
		(end 98.1 74.4)
		(width 0.2)
		(layer "F.Cu")
		(net 213)
	)
	(segment
		(start 99.31 71.32)
		(end 98.6 72.03)
		(width 0.2)
		(layer "F.Cu")
		(net 213)
	)
	(segment
		(start 129.9 89.1)
		(end 129.5 88.7)
		(width 0.182)
		(layer "F.Cu")
		(net 213)
	)
	(segment
		(start 98.6 72.03)
		(end 98.6 73.9)
		(width 0.2)
		(layer "F.Cu")
		(net 213)
	)
	(via
		(at 99.31 71.32)
		(size 0.45)
		(drill 0.2)
		(layers "F.Cu" "B.Cu")
		(remove_unused_layers yes)
		(keep_end_layers yes)
		(zone_layer_connections)
		(net 213)
	)
	(via
		(at 129.5 88.7)
		(size 0.45)
		(drill 0.2)
		(layers "F.Cu" "B.Cu")
		(remove_unused_layers yes)
		(keep_end_layers yes)
		(zone_layer_connections)
		(net 213)
	)
	(segment
		(start 120.272051 78.122051)
		(end 120.272053 78.122052)
		(width 0.13)
		(layer "In4.Cu")
		(net 213)
	)
	(segment
		(start 119.017505 78.245232)
		(end 119.017504 78.245231)
		(width 0.13)
		(layer "In4.Cu")
		(net 213)
	)
	(segment
		(start 120.112388 76.867505)
		(end 120.112389 76.867504)
		(width 0.13)
		(layer "In4.Cu")
		(net 213)
	)
	(segment
		(start 118.999263 76.849264)
		(end 118.999262 76.849262)
		(width 0.13)
		(layer "In4.Cu")
		(net 213)
	)
	(segment
		(start 120.678073 77.43319)
		(end 120.678074 77.433189)
		(width 0.13)
		(layer "In4.Cu")
		(net 213)
	)
	(segment
		(start 120.11239 76.584663)
		(end 120.112389 76.584662)
		(width 0.13)
		(layer "In4.Cu")
		(net 213)
	)
	(segment
		(start 119.546704 76.301822)
		(end 119.546705 76.301821)
		(width 0.13)
		(layer "In4.Cu")
		(net 213)
	)
	(segment
		(start 121.9 88.044473)
		(end 122.955527 89.1)
		(width 0.13)
		(layer "In4.Cu")
		(net 213)
	)
	(segment
		(start 119.564945 77.414945)
		(end 119.564947 77.414947)
		(width 0.13)
		(layer "In4.Cu")
		(net 213)
	)
	(segment
		(start 120.678074 77.433189)
		(end 120.272052 77.839208)
		(width 0.13)
		(layer "In4.Cu")
		(net 213)
	)
	(segment
		(start 103.97 66.66)
		(end 116.16 66.66)
		(width 0.13)
		(layer "In4.Cu")
		(net 213)
	)
	(segment
		(start 119.546706 76.018979)
		(end 119.546705 76.018979)
		(width 0.13)
		(layer "In4.Cu")
		(net 213)
	)
	(segment
		(start 118.45182 77.679547)
		(end 118.451819 77.679546)
		(width 0.13)
		(layer "In4.Cu")
		(net 213)
	)
	(segment
		(start 118.857842 76.425)
		(end 119.263863 76.01898)
		(width 0.13)
		(layer "In4.Cu")
		(net 213)
	)
	(segment
		(start 99.31 71.32)
		(end 103.97 66.66)
		(width 0.13)
		(layer "In4.Cu")
		(net 213)
	)
	(segment
		(start 118.734661 77.679546)
		(end 119.829545 76.58466)
		(width 0.13)
		(layer "In4.Cu")
		(net 213)
	)
	(segment
		(start 118.47 68.97)
		(end 118.47 76.32)
		(width 0.13)
		(layer "In4.Cu")
		(net 213)
	)
	(segment
		(start 122.955527 89.1)
		(end 128.844473 89.1)
		(width 0.13)
		(layer "In4.Cu")
		(net 213)
	)
	(segment
		(start 119.564947 77.414947)
		(end 119.017504 77.962389)
		(width 0.13)
		(layer "In4.Cu")
		(net 213)
	)
	(segment
		(start 119.546705 76.301821)
		(end 118.999263 76.849264)
		(width 0.13)
		(layer "In4.Cu")
		(net 213)
	)
	(segment
		(start 121.9 79.75)
		(end 121.9 88.044473)
		(width 0.13)
		(layer "In4.Cu")
		(net 213)
	)
	(segment
		(start 118.999262 76.849262)
		(end 118.451819 77.396704)
		(width 0.13)
		(layer "In4.Cu")
		(net 213)
	)
	(segment
		(start 116.16 66.66)
		(end 118.47 68.97)
		(width 0.13)
		(layer "In4.Cu")
		(net 213)
	)
	(segment
		(start 120.112389 76.867504)
		(end 119.564945 77.414945)
		(width 0.13)
		(layer "In4.Cu")
		(net 213)
	)
	(segment
		(start 128.844473 89.1)
		(end 129.244473 88.7)
		(width 0.13)
		(layer "In4.Cu")
		(net 213)
	)
	(segment
		(start 129.244473 88.7)
		(end 129.5 88.7)
		(width 0.13)
		(layer "In4.Cu")
		(net 213)
	)
	(segment
		(start 119.300347 78.24523)
		(end 119.300346 78.245231)
		(width 0.13)
		(layer "In4.Cu")
		(net 213)
	)
	(segment
		(start 120.272053 78.122052)
		(end 121.9 79.75)
		(width 0.13)
		(layer "In4.Cu")
		(net 213)
	)
	(segment
		(start 118.857843 76.424999)
		(end 118.857842 76.425)
		(width 0.13)
		(layer "In4.Cu")
		(net 213)
	)
	(segment
		(start 119.300346 78.245231)
		(end 120.39523 77.150345)
		(width 0.13)
		(layer "In4.Cu")
		(net 213)
	)
	(segment
		(start 118.734662 77.679545)
		(end 118.734661 77.679546)
		(width 0.13)
		(layer "In4.Cu")
		(net 213)
	)
	(segment
		(start 120.678075 77.150348)
		(end 120.678074 77.150347)
		(width 0.13)
		(layer "In4.Cu")
		(net 213)
	)
	(segment
		(start 118.47 76.32)
		(end 118.575 76.425)
		(width 0.13)
		(layer "In4.Cu")
		(net 213)
	)
	(arc
		(start 119.546705 76.018979)
		(mid 119.605283 76.160401)
		(end 119.546704 76.301822)
		(width 0.13)
		(layer "In4.Cu")
		(net 213)
	)
	(arc
		(start 119.017504 77.962389)
		(mid 118.958926 78.103811)
		(end 119.017505 78.245232)
		(width 0.13)
		(layer "In4.Cu")
		(net 213)
	)
	(arc
		(start 119.017504 78.245231)
		(mid 119.158926 78.303809)
		(end 119.300347 78.24523)
		(width 0.13)
		(layer "In4.Cu")
		(net 213)
	)
	(arc
		(start 120.39523 77.150345)
		(mid 120.536654 77.091769)
		(end 120.678075 77.150348)
		(width 0.13)
		(layer "In4.Cu")
		(net 213)
	)
	(arc
		(start 120.112389 76.584662)
		(mid 120.170967 76.726084)
		(end 120.112388 76.867505)
		(width 0.13)
		(layer "In4.Cu")
		(net 213)
	)
	(arc
		(start 118.451819 77.396704)
		(mid 118.393241 77.538126)
		(end 118.45182 77.679547)
		(width 0.13)
		(layer "In4.Cu")
		(net 213)
	)
	(arc
		(start 118.451819 77.679546)
		(mid 118.593241 77.738124)
		(end 118.734662 77.679545)
		(width 0.13)
		(layer "In4.Cu")
		(net 213)
	)
	(arc
		(start 120.678074 77.150347)
		(mid 120.736652 77.291769)
		(end 120.678073 77.43319)
		(width 0.13)
		(layer "In4.Cu")
		(net 213)
	)
	(arc
		(start 120.272052 77.839208)
		(mid 120.213473 77.980629)
		(end 120.272051 78.122051)
		(width 0.13)
		(layer "In4.Cu")
		(net 213)
	)
	(arc
		(start 119.263863 76.01898)
		(mid 119.405284 75.960401)
		(end 119.546706 76.018979)
		(width 0.13)
		(layer "In4.Cu")
		(net 213)
	)
	(arc
		(start 119.829545 76.58466)
		(mid 119.970969 76.526084)
		(end 120.11239 76.584663)
		(width 0.13)
		(layer "In4.Cu")
		(net 213)
	)
	(arc
		(start 118.575 76.425)
		(mid 118.716422 76.483578)
		(end 118.857843 76.424999)
		(width 0.13)
		(layer "In4.Cu")
		(net 213)
	)
	(segment
		(start 96.61 68.48)
		(end 97.52 69.39)
		(width 0.15)
		(layer "F.Cu")
		(net 214)
	)
	(segment
		(start 95.57 72.93)
		(end 95.1 73.4)
		(width 0.15)
		(layer "F.Cu")
		(net 214)
	)
	(segment
		(start 96.047204 68.48)
		(end 96.61 68.48)
		(width 0.15)
		(layer "F.Cu")
		(net 214)
	)
	(segment
		(start 131.5 86.7)
		(end 131.9 86.3)
		(width 0.15)
		(layer "F.Cu")
		(net 214)
	)
	(segment
		(start 95.57 68.957204)
		(end 95.57 72.93)
		(width 0.15)
		(layer "F.Cu")
		(net 214)
	)
	(segment
		(start 95.963852 68.563352)
		(end 95.57 68.957204)
		(width 0.15)
		(layer "F.Cu")
		(net 214)
	)
	(segment
		(start 97.52 69.39)
		(end 99.1108 69.39)
		(width 0.15)
		(layer "F.Cu")
		(net 214)
	)
	(segment
		(start 95.963852 68.563352)
		(end 96.047204 68.48)
		(width 0.15)
		(layer "F.Cu")
		(net 214)
	)
	(via
		(at 131.9 86.3)
		(size 0.45)
		(drill 0.2)
		(layers "F.Cu" "B.Cu")
		(remove_unused_layers yes)
		(keep_end_layers yes)
		(zone_layer_connections)
		(net 214)
	)
	(via
		(at 95.963852 68.563352)
		(size 0.45)
		(drill 0.2)
		(layers "F.Cu" "B.Cu")
		(remove_unused_layers yes)
		(keep_end_layers yes)
		(zone_layer_connections)
		(net 214)
	)
	(via
		(at 92.404868 68.378178)
		(size 0.45)
		(drill 0.2)
		(layers "F.Cu" "B.Cu")
		(remove_unused_layers yes)
		(keep_end_layers yes)
		(zone_layer_connections)
		(net 214)
	)
	(segment
		(start 95.55 68.977204)
		(end 95.963852 68.563352)
		(width 0.15)
		(layer "B.Cu")
		(net 214)
	)
	(segment
		(start 95.55 69.21)
		(end 95.55 68.977204)
		(width 0.15)
		(layer "B.Cu")
		(net 214)
	)
	(segment
		(start 92.404868 68.378178)
		(end 93.23669 69.21)
		(width 0.15)
		(layer "B.Cu")
		(net 214)
	)
	(segment
		(start 93.23669 69.21)
		(end 95.55 69.21)
		(width 0.15)
		(layer "B.Cu")
		(net 214)
	)
	(segment
		(start 92.404868 68.378178)
		(end 92.1 68.683046)
		(width 0.13)
		(layer "In2.Cu")
		(net 214)
	)
	(segment
		(start 136.85 91.581385)
		(end 136.21 90.941385)
		(width 0.13)
		(layer "In2.Cu")
		(net 214)
	)
	(segment
		(start 135.55 86.3)
		(end 131.9 86.3)
		(width 0.13)
		(layer "In2.Cu")
		(net 214)
	)
	(segment
		(start 116.3 102.2)
		(end 115.85 102.65)
		(width 0.125)
		(layer "In2.Cu")
		(net 214)
	)
	(segment
		(start 92 72.9)
		(end 92 88.4)
		(width 0.13)
		(layer "In2.Cu")
		(net 214)
	)
	(segment
		(start 132.06 98.4)
		(end 135.86 98.4)
		(width 0.13)
		(layer "In2.Cu")
		(net 214)
	)
	(segment
		(start 136.21 90.941385)
		(end 136.21 89.64)
		(width 0.13)
		(layer "In2.Cu")
		(net 214)
	)
	(segment
		(start 115.495 103.005)
		(end 115.85 102.65)
		(width 0.13)
		(layer "In2.Cu")
		(net 214)
	)
	(segment
		(start 92.1 72)
		(end 91.8 72.3)
		(width 0.13)
		(layer "In2.Cu")
		(net 214)
	)
	(segment
		(start 92.1 68.683046)
		(end 92.1 72)
		(width 0.13)
		(layer "In2.Cu")
		(net 214)
	)
	(segment
		(start 126.2 102.5)
		(end 125.4 102.5)
		(width 0.125)
		(layer "In2.Cu")
		(net 214)
	)
	(segment
		(start 136.85 97.41)
		(end 136.85 91.581385)
		(width 0.13)
		(layer "In2.Cu")
		(net 214)
	)
	(segment
		(start 109.905 103.005)
		(end 115.495 103.005)
		(width 0.13)
		(layer "In2.Cu")
		(net 214)
	)
	(segment
		(start 126.2 102.5)
		(end 127.005 102.5)
		(width 0.13)
		(layer "In2.Cu")
		(net 214)
	)
	(segment
		(start 103.61 100.01)
		(end 106.91 100.01)
		(width 0.13)
		(layer "In2.Cu")
		(net 214)
	)
	(segment
		(start 106.91 100.01)
		(end 109.905 103.005)
		(width 0.13)
		(layer "In2.Cu")
		(net 214)
	)
	(segment
		(start 125.1 102.2)
		(end 116.3 102.2)
		(width 0.125)
		(layer "In2.Cu")
		(net 214)
	)
	(segment
		(start 136.21 89.64)
		(end 135.994798 89.424798)
		(width 0.13)
		(layer "In2.Cu")
		(net 214)
	)
	(segment
		(start 135.86 98.4)
		(end 136.85 97.41)
		(width 0.13)
		(layer "In2.Cu")
		(net 214)
	)
	(segment
		(start 135.994798 86.744798)
		(end 135.55 86.3)
		(width 0.13)
		(layer "In2.Cu")
		(net 214)
	)
	(segment
		(start 125.4 102.5)
		(end 125.1 102.2)
		(width 0.125)
		(layer "In2.Cu")
		(net 214)
	)
	(segment
		(start 131.105 98.4)
		(end 130.4025 99.1025)
		(width 0.125)
		(layer "In2.Cu")
		(net 214)
	)
	(segment
		(start 127.005 102.5)
		(end 130.4025 99.1025)
		(width 0.13)
		(layer "In2.Cu")
		(net 214)
	)
	(segment
		(start 91.8 72.7)
		(end 92 72.9)
		(width 0.13)
		(layer "In2.Cu")
		(net 214)
	)
	(segment
		(start 132.06 98.4)
		(end 131.105 98.4)
		(width 0.125)
		(layer "In2.Cu")
		(net 214)
	)
	(segment
		(start 135.994798 89.424798)
		(end 135.994798 86.744798)
		(width 0.13)
		(layer "In2.Cu")
		(net 214)
	)
	(segment
		(start 92 88.4)
		(end 103.61 100.01)
		(width 0.13)
		(layer "In2.Cu")
		(net 214)
	)
	(segment
		(start 91.8 72.3)
		(end 91.8 72.7)
		(width 0.13)
		(layer "In2.Cu")
		(net 214)
	)
	(segment
		(start 128.707742 93.498424)
		(end 128.698424 93.498424)
		(width 0.15)
		(layer "F.Cu")
		(net 215)
	)
	(segment
		(start 101.64 73.4)
		(end 100.1 73.4)
		(width 0.2)
		(layer "F.Cu")
		(net 215)
	)
	(segment
		(start 128.698424 93.498424)
		(end 128.3 93.1)
		(width 0.15)
		(layer "F.Cu")
		(net 215)
	)
	(via
		(at 101.64 73.4)
		(size 0.45)
		(drill 0.2)
		(layers "F.Cu" "B.Cu")
		(remove_unused_layers yes)
		(keep_end_layers yes)
		(zone_layer_connections)
		(net 215)
	)
	(via
		(at 128.707742 93.498424)
		(size 0.45)
		(drill 0.2)
		(layers "F.Cu" "B.Cu")
		(net 215)
	)
	(segment
		(start 106.842476 83.44)
		(end 108.137524 83.44)
		(width 0.13)
		(layer "In2.Cu")
		(net 215)
	)
	(segment
		(start 106.842476 85.04)
		(end 108.137524 85.04)
		(width 0.13)
		(layer "In2.Cu")
		(net 215)
	)
	(segment
		(start 126.444473 95.5)
		(end 127.244473 94.7)
		(width 0.13)
		(layer "In2.Cu")
		(net 215)
	)
	(segment
		(start 107.34 86.04)
		(end 116.8 95.5)
		(width 0.13)
		(layer "In2.Cu")
		(net 215)
	)
	(segment
		(start 106.842476 83.84)
		(end 108.137524 83.84)
		(width 0.13)
		(layer "In2.Cu")
		(net 215)
	)
	(segment
		(start 106.842476 83.04)
		(end 108.137524 83.04)
		(width 0.13)
		(layer "In2.Cu")
		(net 215)
	)
	(segment
		(start 106.842476 84.64)
		(end 108.137524 84.64)
		(width 0.13)
		(layer "In2.Cu")
		(net 215)
	)
	(segment
		(start 108.137524 85.44)
		(end 107.54 85.44)
		(width 0.13)
		(layer "In2.Cu")
		(net 215)
	)
	(segment
		(start 127.244473 94.7)
		(end 128.050386 94.7)
		(width 0.13)
		(layer "In2.Cu")
		(net 215)
	)
	(segment
		(start 107.34 70.56)
		(end 107.34 82.44)
		(width 0.13)
		(layer "In2.Cu")
		(net 215)
	)
	(segment
		(start 106.842476 84.24)
		(end 108.137524 84.24)
		(width 0.13)
		(layer "In2.Cu")
		(net 215)
	)
	(segment
		(start 106.38 69.6)
		(end 107.34 70.56)
		(width 0.13)
		(layer "In2.Cu")
		(net 215)
	)
	(segment
		(start 107.34 85.64)
		(end 107.34 86.04)
		(width 0.13)
		(layer "In2.Cu")
		(net 215)
	)
	(segment
		(start 128.050386 94.7)
		(end 128.707742 94.042644)
		(width 0.13)
		(layer "In2.Cu")
		(net 215)
	)
	(segment
		(start 102.81 69.6)
		(end 106.38 69.6)
		(width 0.13)
		(layer "In2.Cu")
		(net 215)
	)
	(segment
		(start 107.54 82.64)
		(end 108.137524 82.64)
		(width 0.13)
		(layer "In2.Cu")
		(net 215)
	)
	(segment
		(start 101.64 73.4)
		(end 101.64 70.77)
		(width 0.13)
		(layer "In2.Cu")
		(net 215)
	)
	(segment
		(start 101.64 70.77)
		(end 102.81 69.6)
		(width 0.13)
		(layer "In2.Cu")
		(net 215)
	)
	(segment
		(start 116.8 95.5)
		(end 126.444473 95.5)
		(width 0.13)
		(layer "In2.Cu")
		(net 215)
	)
	(segment
		(start 128.707742 94.042644)
		(end 128.707742 93.498424)
		(width 0.13)
		(layer "In2.Cu")
		(net 215)
	)
	(arc
		(start 106.842476 83.04)
		(mid 106.701055 83.098579)
		(end 106.642476 83.24)
		(width 0.13)
		(layer "In2.Cu")
		(net 215)
	)
	(arc
		(start 108.137524 85.04)
		(mid 108.278945 85.098579)
		(end 108.337524 85.24)
		(width 0.13)
		(layer "In2.Cu")
		(net 215)
	)
	(arc
		(start 108.137524 84.24)
		(mid 108.278945 84.298579)
		(end 108.337524 84.44)
		(width 0.13)
		(layer "In2.Cu")
		(net 215)
	)
	(arc
		(start 106.842476 83.84)
		(mid 106.701055 83.898579)
		(end 106.642476 84.04)
		(width 0.13)
		(layer "In2.Cu")
		(net 215)
	)
	(arc
		(start 107.54 85.44)
		(mid 107.398579 85.498579)
		(end 107.34 85.64)
		(width 0.13)
		(layer "In2.Cu")
		(net 215)
	)
	(arc
		(start 108.137524 82.64)
		(mid 108.278945 82.698579)
		(end 108.337524 82.84)
		(width 0.13)
		(layer "In2.Cu")
		(net 215)
	)
	(arc
		(start 108.137524 83.44)
		(mid 108.278945 83.498579)
		(end 108.337524 83.64)
		(width 0.13)
		(layer "In2.Cu")
		(net 215)
	)
	(arc
		(start 106.642476 84.84)
		(mid 106.701055 84.981421)
		(end 106.842476 85.04)
		(width 0.13)
		(layer "In2.Cu")
		(net 215)
	)
	(arc
		(start 106.642476 83.24)
		(mid 106.701055 83.381421)
		(end 106.842476 83.44)
		(width 0.13)
		(layer "In2.Cu")
		(net 215)
	)
	(arc
		(start 107.34 82.44)
		(mid 107.398579 82.581421)
		(end 107.54 82.64)
		(width 0.13)
		(layer "In2.Cu")
		(net 215)
	)
	(arc
		(start 108.337524 84.44)
		(mid 108.278945 84.581421)
		(end 108.137524 84.64)
		(width 0.13)
		(layer "In2.Cu")
		(net 215)
	)
	(arc
		(start 106.642476 84.04)
		(mid 106.701055 84.181421)
		(end 106.842476 84.24)
		(width 0.13)
		(layer "In2.Cu")
		(net 215)
	)
	(arc
		(start 108.337524 83.64)
		(mid 108.278945 83.781421)
		(end 108.137524 83.84)
		(width 0.13)
		(layer "In2.Cu")
		(net 215)
	)
	(arc
		(start 106.842476 84.64)
		(mid 106.701055 84.698579)
		(end 106.642476 84.84)
		(width 0.13)
		(layer "In2.Cu")
		(net 215)
	)
	(arc
		(start 108.337524 85.24)
		(mid 108.278945 85.381421)
		(end 108.137524 85.44)
		(width 0.13)
		(layer "In2.Cu")
		(net 215)
	)
	(arc
		(start 108.337524 82.84)
		(mid 108.278945 82.981421)
		(end 108.137524 83.04)
		(width 0.13)
		(layer "In2.Cu")
		(net 215)
	)
	(segment
		(start 128.3 89.1)
		(end 128.7 89.5)
		(width 0.182)
		(layer "F.Cu")
		(net 216)
	)
	(segment
		(start 99.11 72.58)
		(end 99.11 73.39)
		(width 0.182)
		(layer "F.Cu")
		(net 216)
	)
	(via
		(at 99.11 72.58)
		(size 0.45)
		(drill 0.2)
		(layers "F.Cu" "B.Cu")
		(remove_unused_layers yes)
		(keep_end_layers yes)
		(zone_layer_connections)
		(net 216)
	)
	(via
		(at 128.7 89.5)
		(size 0.45)
		(drill 0.2)
		(layers "F.Cu" "B.Cu")
		(remove_unused_layers yes)
		(keep_end_layers yes)
		(zone_layer_connections)
		(net 216)
	)
	(segment
		(start 108.8 78.7)
		(end 108.835164 78.7)
		(width 0.13)
		(layer "In2.Cu")
		(net 216)
	)
	(segment
		(start 107.814836 81.1)
		(end 108.835164 81.1)
		(width 0.13)
		(layer "In2.Cu")
		(net 216)
	)
	(segment
		(start 102.3 68.5)
		(end 106.4 68.5)
		(width 0.13)
		(layer "In2.Cu")
		(net 216)
	)
	(segment
		(start 100.22 72.58)
		(end 100.45 72.35)
		(width 0.13)
		(layer "In2.Cu")
		(net 216)
	)
	(segment
		(start 106.4 68.5)
		(end 108.125 70.225)
		(width 0.13)
		(layer "In2.Cu")
		(net 216)
	)
	(segment
		(start 107.814836 81.9)
		(end 108.835164 81.9)
		(width 0.13)
		(layer "In2.Cu")
		(net 216)
	)
	(segment
		(start 107.814836 79.5)
		(end 108.835164 79.5)
		(width 0.13)
		(layer "In2.Cu")
		(net 216)
	)
	(segment
		(start 107.814836 79.9)
		(end 108.835164 79.9)
		(width 0.13)
		(layer "In2.Cu")
		(net 216)
	)
	(segment
		(start 107.814836 80.7)
		(end 108.835164 80.7)
		(width 0.13)
		(layer "In2.Cu")
		(net 216)
	)
	(segment
		(start 108.125 70.225)
		(end 108.125 76.325)
		(width 0.13)
		(layer "In2.Cu")
		(net 216)
	)
	(segment
		(start 100.45 70.35)
		(end 102.3 68.5)
		(width 0.13)
		(layer "In2.Cu")
		(net 216)
	)
	(segment
		(start 113.708234 90.708234)
		(end 126.436239 90.708234)
		(width 0.13)
		(layer "In2.Cu")
		(net 216)
	)
	(segment
		(start 108.6 85.6)
		(end 113.708234 90.708234)
		(width 0.13)
		(layer "In2.Cu")
		(net 216)
	)
	(segment
		(start 107.814836 80.3)
		(end 108.835164 80.3)
		(width 0.13)
		(layer "In2.Cu")
		(net 216)
	)
	(segment
		(start 99.11 72.58)
		(end 100.22 72.58)
		(width 0.13)
		(layer "In2.Cu")
		(net 216)
	)
	(segment
		(start 107.814836 81.5)
		(end 108.835164 81.5)
		(width 0.13)
		(layer "In2.Cu")
		(net 216)
	)
	(segment
		(start 108.835164 79.1)
		(end 108.8 79.1)
		(width 0.13)
		(layer "In2.Cu")
		(net 216)
	)
	(segment
		(start 127.9 90.3)
		(end 128.7 89.5)
		(width 0.13)
		(layer "In2.Cu")
		(net 216)
	)
	(segment
		(start 126.436239 90.708234)
		(end 126.844473 90.3)
		(width 0.13)
		(layer "In2.Cu")
		(net 216)
	)
	(segment
		(start 108.835164 82.3)
		(end 108.8 82.3)
		(width 0.13)
		(layer "In2.Cu")
		(net 216)
	)
	(segment
		(start 108.8 79.1)
		(end 107.814836 79.1)
		(width 0.13)
		(layer "In2.Cu")
		(net 216)
	)
	(segment
		(start 100.45 72.35)
		(end 100.45 70.35)
		(width 0.13)
		(layer "In2.Cu")
		(net 216)
	)
	(segment
		(start 108.125 76.325)
		(end 108.6 76.8)
		(width 0.13)
		(layer "In2.Cu")
		(net 216)
	)
	(segment
		(start 108.6 82.5)
		(end 108.6 85.6)
		(width 0.13)
		(layer "In2.Cu")
		(net 216)
	)
	(segment
		(start 108.6 76.8)
		(end 108.6 78.5)
		(width 0.13)
		(layer "In2.Cu")
		(net 216)
	)
	(segment
		(start 126.844473 90.3)
		(end 127.9 90.3)
		(width 0.13)
		(layer "In2.Cu")
		(net 216)
	)
	(arc
		(start 107.614836 80.1)
		(mid 107.673415 80.241421)
		(end 107.814836 80.3)
		(width 0.13)
		(layer "In2.Cu")
		(net 216)
	)
	(arc
		(start 109.035164 82.1)
		(mid 108.976585 82.241421)
		(end 108.835164 82.3)
		(width 0.13)
		(layer "In2.Cu")
		(net 216)
	)
	(arc
		(start 108.835164 78.7)
		(mid 108.976585 78.758579)
		(end 109.035164 78.9)
		(width 0.13)
		(layer "In2.Cu")
		(net 216)
	)
	(arc
		(start 108.8 82.3)
		(mid 108.658579 82.358579)
		(end 108.6 82.5)
		(width 0.13)
		(layer "In2.Cu")
		(net 216)
	)
	(arc
		(start 107.814836 79.1)
		(mid 107.673415 79.158579)
		(end 107.614836 79.3)
		(width 0.13)
		(layer "In2.Cu")
		(net 216)
	)
	(arc
		(start 107.814836 79.9)
		(mid 107.673415 79.958579)
		(end 107.614836 80.1)
		(width 0.13)
		(layer "In2.Cu")
		(net 216)
	)
	(arc
		(start 108.835164 81.9)
		(mid 108.976585 81.958579)
		(end 109.035164 82.1)
		(width 0.13)
		(layer "In2.Cu")
		(net 216)
	)
	(arc
		(start 108.6 78.5)
		(mid 108.658579 78.641421)
		(end 108.8 78.7)
		(width 0.13)
		(layer "In2.Cu")
		(net 216)
	)
	(arc
		(start 108.835164 80.3)
		(mid 108.976585 80.358579)
		(end 109.035164 80.5)
		(width 0.13)
		(layer "In2.Cu")
		(net 216)
	)
	(arc
		(start 108.835164 79.5)
		(mid 108.976585 79.558579)
		(end 109.035164 79.7)
		(width 0.13)
		(layer "In2.Cu")
		(net 216)
	)
	(arc
		(start 107.614836 79.3)
		(mid 107.673415 79.441421)
		(end 107.814836 79.5)
		(width 0.13)
		(layer "In2.Cu")
		(net 216)
	)
	(arc
		(start 107.814836 81.5)
		(mid 107.673415 81.558579)
		(end 107.614836 81.7)
		(width 0.13)
		(layer "In2.Cu")
		(net 216)
	)
	(arc
		(start 109.035164 81.3)
		(mid 108.976585 81.441421)
		(end 108.835164 81.5)
		(width 0.13)
		(layer "In2.Cu")
		(net 216)
	)
	(arc
		(start 109.035164 78.9)
		(mid 108.976585 79.041421)
		(end 108.835164 79.1)
		(width 0.13)
		(layer "In2.Cu")
		(net 216)
	)
	(arc
		(start 107.614836 80.9)
		(mid 107.673415 81.041421)
		(end 107.814836 81.1)
		(width 0.13)
		(layer "In2.Cu")
		(net 216)
	)
	(arc
		(start 109.035164 79.7)
		(mid 108.976585 79.841421)
		(end 108.835164 79.9)
		(width 0.13)
		(layer "In2.Cu")
		(net 216)
	)
	(arc
		(start 107.814836 80.7)
		(mid 107.673415 80.758579)
		(end 107.614836 80.9)
		(width 0.13)
		(layer "In2.Cu")
		(net 216)
	)
	(arc
		(start 107.614836 81.7)
		(mid 107.673415 81.841421)
		(end 107.814836 81.9)
		(width 0.13)
		(layer "In2.Cu")
		(net 216)
	)
	(arc
		(start 109.035164 80.5)
		(mid 108.976585 80.641421)
		(end 108.835164 80.7)
		(width 0.13)
		(layer "In2.Cu")
		(net 216)
	)
	(arc
		(start 108.835164 81.1)
		(mid 108.976585 81.158579)
		(end 109.035164 81.3)
		(width 0.13)
		(layer "In2.Cu")
		(net 216)
	)
	(segment
		(start 98.305686 69.64)
		(end 98.915686 70.25)
		(width 0.15)
		(layer "F.Cu")
		(net 217)
	)
	(segment
		(start 97.097095 69.64)
		(end 98.305686 69.64)
		(width 0.15)
		(layer "F.Cu")
		(net 217)
	)
	(segment
		(start 96.542715 69.1995)
		(end 96.656595 69.1995)
		(width 0.15)
		(layer "F.Cu")
		(net 217)
	)
	(segment
		(start 98.915686 70.25)
		(end 99.4492 70.25)
		(width 0.15)
		(layer "F.Cu")
		(net 217)
	)
	(segment
		(start 130.7 87.5)
		(end 131.1 87.9)
		(width 0.15)
		(layer "F.Cu")
		(net 217)
	)
	(segment
		(start 96.542715 69.1995)
		(end 96.22 69.522215)
		(width 0.15)
		(layer "F.Cu")
		(net 217)
	)
	(segment
		(start 96.656595 69.1995)
		(end 97.097095 69.64)
		(width 0.15)
		(layer "F.Cu")
		(net 217)
	)
	(segment
		(start 96.22 69.522215)
		(end 96.22 73.28)
		(width 0.15)
		(layer "F.Cu")
		(net 217)
	)
	(segment
		(start 99.4492 70.25)
		(end 100.25 69.4492)
		(width 0.15)
		(layer "F.Cu")
		(net 217)
	)
	(via
		(at 96.542715 69.1995)
		(size 0.45)
		(drill 0.2)
		(layers "F.Cu" "B.Cu")
		(remove_unused_layers yes)
		(keep_end_layers yes)
		(zone_layer_connections)
		(net 217)
	)
	(via
		(at 131.1 87.9)
		(size 0.45)
		(drill 0.2)
		(layers "F.Cu" "B.Cu")
		(remove_unused_layers yes)
		(keep_end_layers yes)
		(zone_layer_connections)
		(net 217)
	)
	(segment
		(start 96.1 82.4)
		(end 93.6 84.9)
		(width 0.13)
		(layer "In2.Cu")
		(net 217)
	)
	(segment
		(start 106.25 96.3)
		(end 109.85 99.9)
		(width 0.13)
		(layer "In2.Cu")
		(net 217)
	)
	(segment
		(start 127.55 97.71)
		(end 128.4 97.71)
		(width 0.13)
		(layer "In2.Cu")
		(net 217)
	)
	(segment
		(start 125.96 99.3)
		(end 127.55 97.71)
		(width 0.13)
		(layer "In2.Cu")
		(net 217)
	)
	(segment
		(start 109.85 99.9)
		(end 121.69 99.9)
		(width 0.13)
		(layer "In2.Cu")
		(net 217)
	)
	(segment
		(start 102.86 96.3)
		(end 106.25 96.3)
		(width 0.13)
		(layer "In2.Cu")
		(net 217)
	)
	(segment
		(start 128.4 97.71)
		(end 130.2 95.91)
		(width 0.13)
		(layer "In2.Cu")
		(net 217)
	)
	(segment
		(start 133.685 88.315)
		(end 131.515 88.315)
		(width 0.13)
		(layer "In2.Cu")
		(net 217)
	)
	(segment
		(start 134.25 88.88)
		(end 133.685 88.315)
		(width 0.13)
		(layer "In2.Cu")
		(net 217)
	)
	(segment
		(start 130.2 95.91)
		(end 132.92 95.91)
		(width 0.13)
		(layer "In2.Cu")
		(net 217)
	)
	(segment
		(start 93.6 87.04)
		(end 102.86 96.3)
		(width 0.13)
		(layer "In2.Cu")
		(net 217)
	)
	(segment
		(start 131.515 88.315)
		(end 131.1 87.9)
		(width 0.13)
		(layer "In2.Cu")
		(net 217)
	)
	(segment
		(start 134.25 89.76)
		(end 134.25 88.88)
		(width 0.13)
		(layer "In2.Cu")
		(net 217)
	)
	(segment
		(start 93.6 84.9)
		(end 93.6 87.04)
		(width 0.13)
		(layer "In2.Cu")
		(net 217)
	)
	(segment
		(start 133.61 90.4)
		(end 134.25 89.76)
		(width 0.13)
		(layer "In2.Cu")
		(net 217)
	)
	(segment
		(start 133.61 95.22)
		(end 133.61 90.4)
		(width 0.13)
		(layer "In2.Cu")
		(net 217)
	)
	(segment
		(start 96.1 69.642215)
		(end 96.1 82.4)
		(width 0.13)
		(layer "In2.Cu")
		(net 217)
	)
	(segment
		(start 132.92 95.91)
		(end 133.61 95.22)
		(width 0.13)
		(layer "In2.Cu")
		(net 217)
	)
	(segment
		(start 96.542715 69.1995)
		(end 96.1 69.642215)
		(width 0.13)
		(layer "In2.Cu")
		(net 217)
	)
	(segment
		(start 122.29 99.3)
		(end 125.96 99.3)
		(width 0.13)
		(layer "In2.Cu")
		(net 217)
	)
	(segment
		(start 121.69 99.9)
		(end 122.29 99.3)
		(width 0.13)
		(layer "In2.Cu")
		(net 217)
	)
	(segment
		(start 94.41 67.26)
		(end 95.215 68.065)
		(width 0.15)
		(layer "F.Cu")
		(net 218)
	)
	(segment
		(start 99.6508 67.6)
		(end 100.25 68.1992)
		(width 0.15)
		(layer "F.Cu")
		(net 218)
	)
	(segment
		(start 96.845686 67.6)
		(end 99.6508 67.6)
		(width 0.15)
		(layer "F.Cu")
		(net 218)
	)
	(segment
		(start 132.7 87.9)
		(end 132.3 87.5)
		(width 0.182)
		(layer "F.Cu")
		(net 218)
	)
	(segment
		(start 89.43 68.32)
		(end 90.49 67.26)
		(width 0.15)
		(layer "F.Cu")
		(net 218)
	)
	(segment
		(start 92.62 73.17)
		(end 92.36 72.91)
		(width 0.15)
		(layer "F.Cu")
		(net 218)
	)
	(segment
		(start 94.62 74.16)
		(end 94.33 73.87)
		(width 0.15)
		(layer "F.Cu")
		(net 218)
	)
	(segment
		(start 90.49 67.26)
		(end 94.41 67.26)
		(width 0.15)
		(layer "F.Cu")
		(net 218)
	)
	(segment
		(start 96.464314 67.65)
		(end 96.795686 67.65)
		(width 0.15)
		(layer "F.Cu")
		(net 218)
	)
	(segment
		(start 95.68 67.6)
		(end 96.414314 67.6)
		(width 0.15)
		(layer "F.Cu")
		(net 218)
	)
	(segment
		(start 91.86 72.91)
		(end 89.43 70.48)
		(width 0.15)
		(layer "F.Cu")
		(net 218)
	)
	(segment
		(start 132.7 87.9005)
		(end 132.7 87.9)
		(width 0.182)
		(layer "F.Cu")
		(net 218)
	)
	(segment
		(start 95.1 75.4)
		(end 94.62 74.92)
		(width 0.15)
		(layer "F.Cu")
		(net 218)
	)
	(segment
		(start 89.43 70.48)
		(end 89.43 68.32)
		(width 0.15)
		(layer "F.Cu")
		(net 218)
	)
	(segment
		(start 96.795686 67.65)
		(end 96.845686 67.6)
		(width 0.15)
		(layer "F.Cu")
		(net 218)
	)
	(segment
		(start 94.62 74.92)
		(end 94.62 74.16)
		(width 0.15)
		(layer "F.Cu")
		(net 218)
	)
	(segment
		(start 96.414314 67.6)
		(end 96.464314 67.65)
		(width 0.15)
		(layer "F.Cu")
		(net 218)
	)
	(segment
		(start 92.84 73.87)
		(end 92.62 73.65)
		(width 0.15)
		(layer "F.Cu")
		(net 218)
	)
	(segment
		(start 92.36 72.91)
		(end 91.86 72.91)
		(width 0.15)
		(layer "F.Cu")
		(net 218)
	)
	(segment
		(start 92.62 73.65)
		(end 92.62 73.17)
		(width 0.15)
		(layer "F.Cu")
		(net 218)
	)
	(segment
		(start 94.33 73.87)
		(end 92.84 73.87)
		(width 0.15)
		(layer "F.Cu")
		(net 218)
	)
	(segment
		(start 95.215 68.065)
		(end 95.68 67.6)
		(width 0.15)
		(layer "F.Cu")
		(net 218)
	)
	(via
		(at 95.215 68.065)
		(size 0.45)
		(drill 0.2)
		(layers "F.Cu" "B.Cu")
		(remove_unused_layers yes)
		(keep_end_layers yes)
		(zone_layer_connections)
		(net 218)
	)
	(via
		(at 132.7 87.9005)
		(size 0.45)
		(drill 0.2)
		(layers "F.Cu" "B.Cu")
		(remove_unused_layers yes)
		(keep_end_layers yes)
		(zone_layer_connections)
		(net 218)
	)
	(segment
		(start 134.56 92.81)
		(end 134.56 95.39)
		(width 0.13)
		(layer "In2.Cu")
		(net 218)
	)
	(segment
		(start 134.4 87.9)
		(end 134.66 88.16)
		(width 0.13)
		(layer "In2.Cu")
		(net 218)
	)
	(segment
		(start 133.88251 90.891125)
		(end 134.27 91.278615)
		(width 0.13)
		(layer "In2.Cu")
		(net 218)
	)
	(segment
		(start 93.2 87.414314)
		(end 93.2 84.3)
		(width 0.13)
		(layer "In2.Cu")
		(net 218)
	)
	(segment
		(start 134.27 92.52)
		(end 134.56 92.81)
		(width 0.13)
		(layer "In2.Cu")
		(net 218)
	)
	(segment
		(start 134.27 91.278615)
		(end 134.27 92.52)
		(width 0.13)
		(layer "In2.Cu")
		(net 218)
	)
	(segment
		(start 122.586385 99.805)
		(end 121.991385 100.4)
		(width 0.13)
		(layer "In2.Cu")
		(net 218)
	)
	(segment
		(start 134.3995 87.9005)
		(end 134.4 87.9)
		(width 0.13)
		(layer "In2.Cu")
		(net 218)
	)
	(segment
		(start 126.365 99.805)
		(end 122.586385 99.805)
		(width 0.13)
		(layer "In2.Cu")
		(net 218)
	)
	(segment
		(start 134.66 89.786405)
		(end 133.88251 90.563895)
		(width 0.13)
		(layer "In2.Cu")
		(net 218)
	)
	(segment
		(start 132.7 87.9005)
		(end 134.3995 87.9005)
		(width 0.13)
		(layer "In2.Cu")
		(net 218)
	)
	(segment
		(start 93.2 84.3)
		(end 95.1 82.4)
		(width 0.13)
		(layer "In2.Cu")
		(net 218)
	)
	(segment
		(start 130.65 96.29)
		(end 128.75 98.19)
		(width 0.13)
		(layer "In2.Cu")
		(net 218)
	)
	(segment
		(start 128.75 98.19)
		(end 127.98 98.19)
		(width 0.13)
		(layer "In2.Cu")
		(net 218)
	)
	(segment
		(start 127.98 98.19)
		(end 126.365 99.805)
		(width 0.13)
		(layer "In2.Cu")
		(net 218)
	)
	(segment
		(start 134.66 88.16)
		(end 134.66 89.786405)
		(width 0.13)
		(layer "In2.Cu")
		(net 218)
	)
	(segment
		(start 133.66 96.29)
		(end 130.65 96.29)
		(width 0.13)
		(layer "In2.Cu")
		(net 218)
	)
	(segment
		(start 95.1 82.4)
		(end 95.1 68.83831)
		(width 0.13)
		(layer "In2.Cu")
		(net 218)
	)
	(segment
		(start 95.1 68.83831)
		(end 95.005051 68.743361)
		(width 0.13)
		(layer "In2.Cu")
		(net 218)
	)
	(segment
		(start 109.1 100.4)
		(end 106.45 97.75)
		(width 0.13)
		(layer "In2.Cu")
		(net 218)
	)
	(segment
		(start 95.005051 68.743361)
		(end 95.005051 68.274949)
		(width 0.13)
		(layer "In2.Cu")
		(net 218)
	)
	(segment
		(start 121.991385 100.4)
		(end 109.1 100.4)
		(width 0.13)
		(layer "In2.Cu")
		(net 218)
	)
	(segment
		(start 133.88251 90.563895)
		(end 133.88251 90.891125)
		(width 0.13)
		(layer "In2.Cu")
		(net 218)
	)
	(segment
		(start 95.005051 68.274949)
		(end 95.215 68.065)
		(width 0.13)
		(layer "In2.Cu")
		(net 218)
	)
	(segment
		(start 134.56 95.39)
		(end 133.66 96.29)
		(width 0.13)
		(layer "In2.Cu")
		(net 218)
	)
	(segment
		(start 106.45 97.75)
		(end 103.535686 97.75)
		(width 0.13)
		(layer "In2.Cu")
		(net 218)
	)
	(segment
		(start 103.535686 97.75)
		(end 93.2 87.414314)
		(width 0.13)
		(layer "In2.Cu")
		(net 218)
	)
	(segment
		(start 108.25 67.25)
		(end 108.75 67.75)
		(width 0.15)
		(layer "F.Cu")
		(net 219)
	)
	(segment
		(start 96.632952 69.741543)
		(end 96.6 69.774495)
		(width 0.15)
		(layer "F.Cu")
		(net 219)
	)
	(segment
		(start 96.63 67.25)
		(end 108.25 67.25)
		(width 0.15)
		(layer "F.Cu")
		(net 219)
	)
	(segment
		(start 96.6 73.9)
		(end 96.1 74.4)
		(width 0.15)
		(layer "F.Cu")
		(net 219)
	)
	(segment
		(start 96.6 69.774495)
		(end 96.6 73.9)
		(width 0.15)
		(layer "F.Cu")
		(net 219)
	)
	(segment
		(start 108.75 67.75)
		(end 108.75 69.85)
		(width 0.15)
		(layer "F.Cu")
		(net 219)
	)
	(segment
		(start 132.3 86.7)
		(end 132.7 87.1)
		(width 0.15)
		(layer "F.Cu")
		(net 219)
	)
	(via
		(at 96.63 67.25)
		(size 0.45)
		(drill 0.2)
		(layers "F.Cu" "B.Cu")
		(remove_unused_layers yes)
		(keep_end_layers yes)
		(zone_layer_connections)
		(net 219)
	)
	(via
		(at 96.632952 69.741543)
		(size 0.45)
		(drill 0.2)
		(layers "F.Cu" "B.Cu")
		(remove_unused_layers yes)
		(keep_end_layers yes)
		(zone_layer_connections)
		(net 219)
	)
	(via
		(at 132.7 87.1)
		(size 0.45)
		(drill 0.2)
		(layers "F.Cu" "B.Cu")
		(remove_unused_layers yes)
		(keep_end_layers yes)
		(zone_layer_connections)
		(net 219)
	)
	(segment
		(start 125.15 100.36)
		(end 126.35 100.36)
		(width 0.13)
		(layer "In2.Cu")
		(net 219)
	)
	(segment
		(start 96.63 67.25)
		(end 94.49 67.25)
		(width 0.13)
		(layer "In2.Cu")
		(net 219)
	)
	(segment
		(start 94.49 67.25)
		(end 93.77 67.97)
		(width 0.13)
		(layer "In2.Cu")
		(net 219)
	)
	(segment
		(start 134.885 96.085)
		(end 134.885 90.575)
		(width 0.13)
		(layer "In2.Cu")
		(net 219)
	)
	(segment
		(start 97.26 69.46)
		(end 97.26 67.88)
		(width 0.13)
		(layer "In2.Cu")
		(net 219)
	)
	(segment
		(start 94.1 73.59)
		(end 94.1 82.5)
		(width 0.13)
		(layer "In2.Cu")
		(net 219)
	)
	(segment
		(start 126.35 100.36)
		(end 127.92 98.79)
		(width 0.13)
		(layer "In2.Cu")
		(net 219)
	)
	(segment
		(start 93.77 73.26)
		(end 94.1 73.59)
		(width 0.13)
		(layer "In2.Cu")
		(net 219)
	)
	(segment
		(start 135.08 90.38)
		(end 135.08 87.33)
		(width 0.13)
		(layer "In2.Cu")
		(net 219)
	)
	(segment
		(start 124.51 101)
		(end 125.15 100.36)
		(width 0.13)
		(layer "In2.Cu")
		(net 219)
	)
	(segment
		(start 133.775 97.195)
		(end 134.885 96.085)
		(width 0.13)
		(layer "In2.Cu")
		(net 219)
	)
	(segment
		(start 96.632952 69.741543)
		(end 96.978457 69.741543)
		(width 0.13)
		(layer "In2.Cu")
		(net 219)
	)
	(segment
		(start 92.8 87.8)
		(end 103.32 98.32)
		(width 0.13)
		(layer "In2.Cu")
		(net 219)
	)
	(segment
		(start 106.42 98.32)
		(end 109.1 101)
		(width 0.13)
		(layer "In2.Cu")
		(net 219)
	)
	(segment
		(start 109.1 101)
		(end 124.51 101)
		(width 0.13)
		(layer "In2.Cu")
		(net 219)
	)
	(segment
		(start 130.23 97.38)
		(end 131.760001 97.38)
		(width 0.13)
		(layer "In2.Cu")
		(net 219)
	)
	(segment
		(start 97.26 67.88)
		(end 96.63 67.25)
		(width 0.13)
		(layer "In2.Cu")
		(net 219)
	)
	(segment
		(start 127.92 98.79)
		(end 128.82 98.79)
		(width 0.13)
		(layer "In2.Cu")
		(net 219)
	)
	(segment
		(start 93.77 67.97)
		(end 93.77 73.26)
		(width 0.13)
		(layer "In2.Cu")
		(net 219)
	)
	(segment
		(start 134.85 87.1)
		(end 132.7 87.1)
		(width 0.13)
		(layer "In2.Cu")
		(net 219)
	)
	(segment
		(start 134.885 90.575)
		(end 135.08 90.38)
		(width 0.13)
		(layer "In2.Cu")
		(net 219)
	)
	(segment
		(start 131.945001 97.195)
		(end 133.775 97.195)
		(width 0.13)
		(layer "In2.Cu")
		(net 219)
	)
	(segment
		(start 103.32 98.32)
		(end 106.42 98.32)
		(width 0.13)
		(layer "In2.Cu")
		(net 219)
	)
	(segment
		(start 96.978457 69.741543)
		(end 97.26 69.46)
		(width 0.13)
		(layer "In2.Cu")
		(net 219)
	)
	(segment
		(start 92.8 83.8)
		(end 92.8 87.8)
		(width 0.13)
		(layer "In2.Cu")
		(net 219)
	)
	(segment
		(start 94.1 82.5)
		(end 92.8 83.8)
		(width 0.13)
		(layer "In2.Cu")
		(net 219)
	)
	(segment
		(start 131.760001 97.38)
		(end 131.945001 97.195)
		(width 0.13)
		(layer "In2.Cu")
		(net 219)
	)
	(segment
		(start 135.08 87.33)
		(end 134.85 87.1)
		(width 0.13)
		(layer "In2.Cu")
		(net 219)
	)
	(segment
		(start 128.82 98.79)
		(end 130.23 97.38)
		(width 0.13)
		(layer "In2.Cu")
		(net 219)
	)
	(segment
		(start 133.282894 82.065053)
		(end 133.282894 81.829586)
		(width 0.2)
		(layer "F.Cu")
		(net 220)
	)
	(segment
		(start 134.759 80.35348)
		(end 134.759 79.711)
		(width 0.2)
		(layer "F.Cu")
		(net 220)
	)
	(segment
		(start 134.759 78.655)
		(end 134.759 78.355)
		(width 0.2)
		(layer "F.Cu")
		(net 220)
	)
	(segment
		(start 131.458 68.774976)
		(end 131.458 66.986564)
		(width 0.2)
		(layer "F.Cu")
		(net 220)
	)
	(segment
		(start 134.381 79.333)
		(end 134.192 79.333)
		(width 0.2)
		(layer "F.Cu")
		(net 220)
	)
	(segment
		(start 130.397463 66.27209)
		(end 130.272464 66.147091)
		(width 0.2)
		(layer "F.Cu")
		(net 220)
	)
	(segment
		(start 134.192 77.977)
		(end 134.192 77.677)
		(width 0.2)
		(layer "F.Cu")
		(net 220)
	)
	(segment
		(start 134.192 77.677)
		(end 134.381 77.677)
		(width 0.2)
		(layer "F.Cu")
		(net 220)
	)
	(segment
		(start 134.759 77.299)
		(end 134.759 72.075976)
		(width 0.2)
		(layer "F.Cu")
		(net 220)
	)
	(segment
		(start 134.192 79.333)
		(end 134.192 79.033)
		(width 0.2)
		(layer "F.Cu")
		(net 220)
	)
	(segment
		(start 125.452881 66.550957)
		(end 125.849043 66.550957)
		(width 0.162)
		(layer "F.Cu")
		(net 220)
	)
	(segment
		(start 134.192 79.033)
		(end 134.381 79.033)
		(width 0.2)
		(layer "F.Cu")
		(net 220)
	)
	(segment
		(start 134.381 77.977)
		(end 134.192 77.977)
		(width 0.2)
		(layer "F.Cu")
		(net 220)
	)
	(segment
		(start 131.458 66.986564)
		(end 130.743526 66.27209)
		(width 0.2)
		(layer "F.Cu")
		(net 220)
	)
	(segment
		(start 134.759 72.075976)
		(end 131.458 68.774976)
		(width 0.2)
		(layer "F.Cu")
		(net 220)
	)
	(segment
		(start 129.122886 85.9)
		(end 129.511443 86.288557)
		(width 0.2)
		(layer "F.Cu")
		(net 220)
	)
	(segment
		(start 133.282894 81.829586)
		(end 134.759 80.35348)
		(width 0.2)
		(layer "F.Cu")
		(net 220)
	)
	(segment
		(start 130.743526 66.27209)
		(end 130.397463 66.27209)
		(width 0.2)
		(layer "F.Cu")
		(net 220)
	)
	(via
		(at 133.282894 82.065053)
		(size 0.45)
		(drill 0.2)
		(layers "F.Cu" "B.Cu")
		(remove_unused_layers yes)
		(keep_end_layers yes)
		(zone_layer_connections)
		(net 220)
	)
	(via
		(at 129.511443 86.288557)
		(size 0.45)
		(drill 0.2)
		(layers "F.Cu" "B.Cu")
		(remove_unused_layers yes)
		(keep_end_layers yes)
		(zone_layer_connections)
		(net 220)
	)
	(via
		(at 130.272464 66.147091)
		(size 0.45)
		(drill 0.2)
		(layers "F.Cu" "B.Cu")
		(remove_unused_layers yes)
		(keep_end_layers yes)
		(zone_layer_connections)
		(net 220)
	)
	(via
		(at 125.452881 66.550957)
		(size 0.45)
		(drill 0.2)
		(layers "F.Cu" "B.Cu")
		(remove_unused_layers yes)
		(keep_end_layers yes)
		(zone_layer_connections)
		(net 220)
	)
	(arc
		(start 134.759 79.711)
		(mid 134.648286 79.443714)
		(end 134.381 79.333)
		(width 0.2)
		(layer "F.Cu")
		(net 220)
	)
	(arc
		(start 134.381 79.033)
		(mid 134.648286 78.922286)
		(end 134.759 78.655)
		(width 0.2)
		(layer "F.Cu")
		(net 220)
	)
	(arc
		(start 134.381 77.677)
		(mid 134.648286 77.566286)
		(end 134.759 77.299)
		(width 0.2)
		(layer "F.Cu")
		(net 220)
	)
	(arc
		(start 134.759 78.355)
		(mid 134.648286 78.087714)
		(end 134.381 77.977)
		(width 0.2)
		(layer "F.Cu")
		(net 220)
	)
	(segment
		(start 130.136383 85.081765)
		(end 130.2 85.081765)
		(width 0.15)
		(layer "In2.Cu")
		(net 220)
	)
	(segment
		(start 125.423608 66.540866)
		(end 125.554871 66.672129)
		(width 0.162)
		(layer "In2.Cu")
		(net 220)
	)
	(segment
		(start 129.161947 66.233591)
		(end 130.185964 66.233591)
		(width 0.162)
		(layer "In2.Cu")
		(net 220)
	)
	(segment
		(start 125.423608 66.540866)
		(end 125.44279 66.540866)
		(width 0.162)
		(layer "In2.Cu")
		(net 220)
	)
	(segment
		(start 125.44279 66.540866)
		(end 125.452881 66.550957)
		(width 0.162)
		(layer "In2.Cu")
		(net 220)
	)
	(segment
		(start 127.357871 66.672129)
		(end 127.5665 66.4635)
		(width 0.162)
		(layer "In2.Cu")
		(net 220)
	)
	(segment
		(start 133.282894 82.101568)
		(end 130.4 84.984462)
		(width 0.162)
		(layer "In2.Cu")
		(net 220)
	)
	(segment
		(start 130.2 85.081765)
		(end 130.318235 85.081765)
		(width 0.15)
		(layer "In2.Cu")
		(net 220)
	)
	(segment
		(start 128.932038 66.4635)
		(end 129.161947 66.233591)
		(width 0.162)
		(layer "In2.Cu")
		(net 220)
	)
	(segment
		(start 129.9 85.9)
		(end 129.9 85.318148)
		(width 0.15)
		(layer "In2.Cu")
		(net 220)
	)
	(segment
		(start 130.4 84.984462)
		(end 130.4 85)
		(width 0.162)
		(layer "In2.Cu")
		(net 220)
	)
	(segment
		(start 125.554871 66.672129)
		(end 127.357871 66.672129)
		(width 0.162)
		(layer "In2.Cu")
		(net 220)
	)
	(segment
		(start 130.318235 85.081765)
		(end 130.4 85)
		(width 0.15)
		(layer "In2.Cu")
		(net 220)
	)
	(segment
		(start 133.282894 82.065053)
		(end 133.282894 82.101568)
		(width 0.162)
		(layer "In2.Cu")
		(net 220)
	)
	(segment
		(start 127.5665 66.4635)
		(end 128.932038 66.4635)
		(width 0.162)
		(layer "In2.Cu")
		(net 220)
	)
	(segment
		(start 129.9 85.318148)
		(end 130.136383 85.081765)
		(width 0.15)
		(layer "In2.Cu")
		(net 220)
	)
	(segment
		(start 130.185964 66.233591)
		(end 130.272464 66.147091)
		(width 0.162)
		(layer "In2.Cu")
		(net 220)
	)
	(segment
		(start 129.511443 86.288557)
		(end 129.9 85.9)
		(width 0.15)
		(layer "In2.Cu")
		(net 220)
	)
	(segment
		(start 132 71.9)
		(end 129.94 69.84)
		(width 0.2)
		(layer "F.Cu")
		(net 221)
	)
	(segment
		(start 129.9 83.97)
		(end 131.5 82.37)
		(width 0.2)
		(layer "F.Cu")
		(net 221)
	)
	(segment
		(start 131.5 82.37)
		(end 131.5 81)
		(width 0.2)
		(layer "F.Cu")
		(net 221)
	)
	(segment
		(start 126.26 67.74)
		(end 125.86 68.14)
		(width 0.182)
		(layer "F.Cu")
		(net 221)
	)
	(segment
		(start 131.5 81)
		(end 132 80.5)
		(width 0.2)
		(layer "F.Cu")
		(net 221)
	)
	(segment
		(start 132 80.5)
		(end 132 71.9)
		(width 0.2)
		(layer "F.Cu")
		(net 221)
	)
	(segment
		(start 129.9 84.3)
		(end 129.9 83.97)
		(width 0.2)
		(layer "F.Cu")
		(net 221)
	)
	(via
		(at 129.94 69.84)
		(size 0.45)
		(drill 0.2)
		(layers "F.Cu" "B.Cu")
		(remove_unused_layers yes)
		(keep_end_layers yes)
		(zone_layer_connections)
		(net 221)
	)
	(via
		(at 126.26 67.74)
		(size 0.45)
		(drill 0.2)
		(layers "F.Cu" "B.Cu")
		(remove_unused_layers yes)
		(keep_end_layers yes)
		(zone_layer_connections)
		(net 221)
	)
	(segment
		(start 125.7 69.6)
		(end 125.7 69.3)
		(width 0.162)
		(layer "In2.Cu")
		(net 221)
	)
	(segment
		(start 126.6 69.6)
		(end 126.469 69.731)
		(width 0.162)
		(layer "In2.Cu")
		(net 221)
	)
	(segment
		(start 126.6 68.3)
		(end 126.6 69.6)
		(width 0.162)
		(layer "In2.Cu")
		(net 221)
	)
	(segment
		(start 128.49 69)
		(end 128.7 69.21)
		(width 0.162)
		(layer "In2.Cu")
		(net 221)
	)
	(segment
		(start 128.7 69.21)
		(end 128.7 69.6)
		(width 0.162)
		(layer "In2.Cu")
		(net 221)
	)
	(segment
		(start 127.5 69.2)
		(end 127.5 68.4)
		(width 0.162)
		(layer "In2.Cu")
		(net 221)
	)
	(segment
		(start 126.26 67.56)
		(end 126.26 67.74)
		(width 0.162)
		(layer "In2.Cu")
		(net 221)
	)
	(segment
		(start 129.8 70.2)
		(end 129.4 70.2)
		(width 0.162)
		(layer "In2.Cu")
		(net 221)
	)
	(segment
		(start 128.472958 69.7)
		(end 128.121958 69.349)
		(width 0.162)
		(layer "In2.Cu")
		(net 221)
	)
	(segment
		(start 126.1 68.2)
		(end 125.7 68.2)
		(width 0.162)
		(layer "In2.Cu")
		(net 221)
	)
	(segment
		(start 129 68.7)
		(end 128.58 68.7)
		(width 0.162)
		(layer "In2.Cu")
		(net 221)
	)
	(segment
		(start 126.17 67.47)
		(end 126.26 67.56)
		(width 0.162)
		(layer "In2.Cu")
		(net 221)
	)
	(segment
		(start 129.94 69.84)
		(end 129.94 70.06)
		(width 0.162)
		(layer "In2.Cu")
		(net 221)
	)
	(segment
		(start 125.94 67.47)
		(end 126.17 67.47)
		(width 0.162)
		(layer "In2.Cu")
		(net 221)
	)
	(segment
		(start 129.4 70.2)
		(end 129.2 70)
		(width 0.162)
		(layer "In2.Cu")
		(net 221)
	)
	(segment
		(start 125.831 69.731)
		(end 125.7 69.6)
		(width 0.162)
		(layer "In2.Cu")
		(net 221)
	)
	(segment
		(start 128.49 68.79)
		(end 128.49 69)
		(width 0.162)
		(layer "In2.Cu")
		(net 221)
	)
	(segment
		(start 127.649 69.349)
		(end 127.5 69.2)
		(width 0.162)
		(layer "In2.Cu")
		(net 221)
	)
	(segment
		(start 127.5 68.4)
		(end 127.249 68.149)
		(width 0.162)
		(layer "In2.Cu")
		(net 221)
	)
	(segment
		(start 128.58 68.7)
		(end 128.49 68.79)
		(width 0.162)
		(layer "In2.Cu")
		(net 221)
	)
	(segment
		(start 129.94 70.06)
		(end 129.8 70.2)
		(width 0.162)
		(layer "In2.Cu")
		(net 221)
	)
	(segment
		(start 126.469 69.731)
		(end 125.831 69.731)
		(width 0.162)
		(layer "In2.Cu")
		(net 221)
	)
	(segment
		(start 125.6 68.1)
		(end 125.6 67.81)
		(width 0.162)
		(layer "In2.Cu")
		(net 221)
	)
	(segment
		(start 126.751 68.149)
		(end 126.6 68.3)
		(width 0.162)
		(layer "In2.Cu")
		(net 221)
	)
	(segment
		(start 125.7 69.3)
		(end 126.2 68.8)
		(width 0.162)
		(layer "In2.Cu")
		(net 221)
	)
	(segment
		(start 125.6 67.81)
		(end 125.94 67.47)
		(width 0.162)
		(layer "In2.Cu")
		(net 221)
	)
	(segment
		(start 128.7 69.6)
		(end 128.6 69.7)
		(width 0.162)
		(layer "In2.Cu")
		(net 221)
	)
	(segment
		(start 127.249 68.149)
		(end 126.751 68.149)
		(width 0.162)
		(layer "In2.Cu")
		(net 221)
	)
	(segment
		(start 125.7 68.2)
		(end 125.6 68.1)
		(width 0.162)
		(layer "In2.Cu")
		(net 221)
	)
	(segment
		(start 126.2 68.8)
		(end 126.2 68.3)
		(width 0.162)
		(layer "In2.Cu")
		(net 221)
	)
	(segment
		(start 128.121958 69.349)
		(end 127.649 69.349)
		(width 0.162)
		(layer "In2.Cu")
		(net 221)
	)
	(segment
		(start 128.6 69.7)
		(end 128.472958 69.7)
		(width 0.162)
		(layer "In2.Cu")
		(net 221)
	)
	(segment
		(start 126.2 68.3)
		(end 126.1 68.2)
		(width 0.162)
		(layer "In2.Cu")
		(net 221)
	)
	(segment
		(start 129.2 68.9)
		(end 129 68.7)
		(width 0.162)
		(layer "In2.Cu")
		(net 221)
	)
	(segment
		(start 129.2 70)
		(end 129.2 68.9)
		(width 0.162)
		(layer "In2.Cu")
		(net 221)
	)
	(segment
		(start 128.7 84.7)
		(end 128.7 83.7)
		(width 0.15)
		(layer "F.Cu")
		(net 222)
	)
	(segment
		(start 129.415 73.391)
		(end 129.415 82.985)
		(width 0.2)
		(layer "F.Cu")
		(net 222)
	)
	(segment
		(start 121.46 66.94)
		(end 121.86 67.34)
		(width 0.182)
		(layer "F.Cu")
		(net 222)
	)
	(segment
		(start 128.3 85.1)
		(end 128.7 84.7)
		(width 0.15)
		(layer "F.Cu")
		(net 222)
	)
	(segment
		(start 129.1245 73.1005)
		(end 129.415 73.391)
		(width 0.2)
		(layer "F.Cu")
		(net 222)
	)
	(segment
		(start 129.415 82.985)
		(end 128.7 83.7)
		(width 0.2)
		(layer "F.Cu")
		(net 222)
	)
	(via
		(at 121.46 66.94)
		(size 0.45)
		(drill 0.2)
		(layers "F.Cu" "B.Cu")
		(remove_unused_layers yes)
		(keep_end_layers yes)
		(zone_layer_connections)
		(net 222)
	)
	(via
		(at 129.1245 73.1005)
		(size 0.45)
		(drill 0.2)
		(layers "F.Cu" "B.Cu")
		(remove_unused_layers yes)
		(keep_end_layers yes)
		(zone_layer_connections)
		(net 222)
	)
	(segment
		(start 129.1245 72.4945)
		(end 129.1245 73.1005)
		(width 0.162)
		(layer "In2.Cu")
		(net 222)
	)
	(segment
		(start 122.73 67.33)
		(end 123.32 67.92)
		(width 0.162)
		(layer "In2.Cu")
		(net 222)
	)
	(segment
		(start 123.32 67.92)
		(end 123.32 73.7)
		(width 0.162)
		(layer "In2.Cu")
		(net 222)
	)
	(segment
		(start 128.93 72.3)
		(end 129.1245 72.4945)
		(width 0.162)
		(layer "In2.Cu")
		(net 222)
	)
	(segment
		(start 125.21 74.02)
		(end 125.88 74.02)
		(width 0.162)
		(layer "In2.Cu")
		(net 222)
	)
	(segment
		(start 127.6 72.3)
		(end 128.93 72.3)
		(width 0.162)
		(layer "In2.Cu")
		(net 222)
	)
	(segment
		(start 123.64 74.02)
		(end 123.96 74.02)
		(width 0.162)
		(layer "In2.Cu")
		(net 222)
	)
	(segment
		(start 125.88 74.02)
		(end 127.6 72.3)
		(width 0.162)
		(layer "In2.Cu")
		(net 222)
	)
	(segment
		(start 124.86 74.42)
		(end 124.86 74.32)
		(width 0.162)
		(layer "In2.Cu")
		(net 222)
	)
	(segment
		(start 123.32 73.7)
		(end 123.64 74.02)
		(width 0.162)
		(layer "In2.Cu")
		(net 222)
	)
	(segment
		(start 124.26 74.32)
		(end 124.26 74.42)
		(width 0.162)
		(layer "In2.Cu")
		(net 222)
	)
	(segment
		(start 121.85 67.33)
		(end 122.73 67.33)
		(width 0.162)
		(layer "In2.Cu")
		(net 222)
	)
	(segment
		(start 125.16 74.02)
		(end 125.21 74.02)
		(width 0.162)
		(layer "In2.Cu")
		(net 222)
	)
	(segment
		(start 121.46 66.94)
		(end 121.85 67.33)
		(width 0.162)
		(layer "In2.Cu")
		(net 222)
	)
	(arc
		(start 124.56 74.72)
		(mid 124.772132 74.632132)
		(end 124.86 74.42)
		(width 0.162)
		(layer "In2.Cu")
		(net 222)
	)
	(arc
		(start 123.96 74.02)
		(mid 124.172132 74.107868)
		(end 124.26 74.32)
		(width 0.162)
		(layer "In2.Cu")
		(net 222)
	)
	(arc
		(start 124.26 74.42)
		(mid 124.347868 74.632132)
		(end 124.56 74.72)
		(width 0.162)
		(layer "In2.Cu")
		(net 222)
	)
	(arc
		(start 124.86 74.32)
		(mid 124.947868 74.107868)
		(end 125.16 74.02)
		(width 0.162)
		(layer "In2.Cu")
		(net 222)
	)
	(segment
		(start 131.062 68.939008)
		(end 134.381 72.258008)
		(width 0.2)
		(layer "F.Cu")
		(net 223)
	)
	(segment
		(start 134.381 74.969)
		(end 134.381 77.299)
		(width 0.2)
		(layer "F.Cu")
		(net 223)
	)
	(segment
		(start 134.381 74.919)
		(end 134.381 74.969)
		(width 0.2)
		(layer "F.Cu")
		(net 223)
	)
	(segment
		(start 134.038698 74.619)
		(end 134.081 74.619)
		(width 0.2)
		(layer "F.Cu")
		(net 223)
	)
	(segment
		(start 130.397463 66.668092)
		(end 130.450805 66.668092)
		(width 0.2)
		(layer "F.Cu")
		(net 223)
	)
	(segment
		(start 133.814 77.677)
		(end 133.814 77.977)
		(width 0.2)
		(layer "F.Cu")
		(net 223)
	)
	(segment
		(start 134.381 78.655)
		(end 134.192 78.655)
		(width 0.2)
		(layer "F.Cu")
		(net 223)
	)
	(segment
		(start 134.381 77.299)
		(end 134.192 77.299)
		(width 0.2)
		(layer "F.Cu")
		(net 223)
	)
	(segment
		(start 134.381 72.258008)
		(end 134.381 73.719)
		(width 0.2)
		(layer "F.Cu")
		(net 223)
	)
	(segment
		(start 133.015607 81.562299)
		(end 132.78014 81.562299)
		(width 0.2)
		(layer "F.Cu")
		(net 223)
	)
	(segment
		(start 134.381 79.711)
		(end 134.381 80.196906)
		(width 0.2)
		(layer "F.Cu")
		(net 223)
	)
	(segment
		(start 134.192 78.355)
		(end 134.381 78.355)
		(width 0.2)
		(layer "F.Cu")
		(net 223)
	)
	(segment
		(start 125.34 67.38)
		(end 125.82 67.38)
		(width 0.162)
		(layer "F.Cu")
		(net 223)
	)
	(segment
		(start 131.062 67.279287)
		(end 131.062 68.939008)
		(width 0.2)
		(layer "F.Cu")
		(net 223)
	)
	(segment
		(start 129.1 85.11)
		(end 129.49 85.5)
		(width 0.2)
		(layer "F.Cu")
		(net 223)
	)
	(segment
		(start 134.192 79.711)
		(end 134.381 79.711)
		(width 0.2)
		(layer "F.Cu")
		(net 223)
	)
	(segment
		(start 133.814 79.033)
		(end 133.814 79.333)
		(width 0.2)
		(layer "F.Cu")
		(net 223)
	)
	(segment
		(start 134.381 80.196906)
		(end 133.015607 81.562299)
		(width 0.2)
		(layer "F.Cu")
		(net 223)
	)
	(segment
		(start 130.272464 66.793091)
		(end 130.397463 66.668092)
		(width 0.2)
		(layer "F.Cu")
		(net 223)
	)
	(segment
		(start 130.450805 66.668092)
		(end 131.062 67.279287)
		(width 0.2)
		(layer "F.Cu")
		(net 223)
	)
	(segment
		(start 134.081 74.019)
		(end 134.038698 74.019)
		(width 0.2)
		(layer "F.Cu")
		(net 223)
	)
	(segment
		(start 134.381 78.355)
		(end 134.381 78.655)
		(width 0.2)
		(layer "F.Cu")
		(net 223)
	)
	(via
		(at 130.272464 66.793091)
		(size 0.45)
		(drill 0.2)
		(layers "F.Cu" "B.Cu")
		(remove_unused_layers yes)
		(keep_end_layers yes)
		(zone_layer_connections)
		(net 223)
	)
	(via
		(at 125.34 67.38)
		(size 0.45)
		(drill 0.2)
		(layers "F.Cu" "B.Cu")
		(remove_unused_layers yes)
		(keep_end_layers yes)
		(zone_layer_connections)
		(net 223)
	)
	(via
		(at 129.49 85.5)
		(size 0.45)
		(drill 0.2)
		(layers "F.Cu" "B.Cu")
		(remove_unused_layers yes)
		(keep_end_layers yes)
		(zone_layer_connections)
		(net 223)
	)
	(via
		(at 132.78014 81.562299)
		(size 0.45)
		(drill 0.2)
		(layers "F.Cu" "B.Cu")
		(remove_unused_layers yes)
		(keep_end_layers yes)
		(zone_layer_connections)
		(net 223)
	)
	(arc
		(start 134.038698 74.019)
		(mid 133.826566 74.106868)
		(end 133.738698 74.319)
		(width 0.2)
		(layer "F.Cu")
		(net 223)
	)
	(arc
		(start 134.192 78.655)
		(mid 133.924714 78.765714)
		(end 133.814 79.033)
		(width 0.2)
		(layer "F.Cu")
		(net 223)
	)
	(arc
		(start 133.814 77.977)
		(mid 133.924714 78.244286)
		(end 134.192 78.355)
		(width 0.2)
		(layer "F.Cu")
		(net 223)
	)
	(arc
		(start 134.381 73.719)
		(mid 134.293132 73.931132)
		(end 134.081 74.019)
		(width 0.2)
		(layer "F.Cu")
		(net 223)
	)
	(arc
		(start 134.192 77.299)
		(mid 133.924714 77.409714)
		(end 133.814 77.677)
		(width 0.2)
		(layer "F.Cu")
		(net 223)
	)
	(arc
		(start 133.814 79.333)
		(mid 133.924714 79.600286)
		(end 134.192 79.711)
		(width 0.2)
		(layer "F.Cu")
		(net 223)
	)
	(arc
		(start 134.081 74.619)
		(mid 134.293132 74.706868)
		(end 134.381 74.919)
		(width 0.2)
		(layer "F.Cu")
		(net 223)
	)
	(arc
		(start 133.738698 74.319)
		(mid 133.826566 74.531132)
		(end 134.038698 74.619)
		(width 0.2)
		(layer "F.Cu")
		(net 223)
	)
	(segment
		(start 127.269333 67.145129)
		(end 127.477962 66.9365)
		(width 0.162)
		(layer "In2.Cu")
		(net 223)
	)
	(segment
		(start 129.9 84.8)
		(end 130 84.7)
		(width 0.15)
		(layer "In2.Cu")
		(net 223)
	)
	(segment
		(start 125.36 67.36)
		(end 125.34 67.38)
		(width 0.162)
		(layer "In2.Cu")
		(net 223)
	)
	(segment
		(start 132.78014 81.935398)
		(end 130.015538 84.7)
		(width 0.162)
		(layer "In2.Cu")
		(net 223)
	)
	(segment
		(start 127.477962 66.9365)
		(end 129.127962 66.9365)
		(width 0.162)
		(layer "In2.Cu")
		(net 223)
	)
	(segment
		(start 125.554871 67.145129)
		(end 125.36 67.34)
		(width 0.162)
		(layer "In2.Cu")
		(net 223)
	)
	(segment
		(start 125.554871 67.145129)
		(end 127.269333 67.145129)
		(width 0.162)
		(layer "In2.Cu")
		(net 223)
	)
	(segment
		(start 132.78014 81.562299)
		(end 132.78014 81.935398)
		(width 0.162)
		(layer "In2.Cu")
		(net 223)
	)
	(segment
		(start 129.127962 66.9365)
		(end 129.357871 66.706591)
		(width 0.162)
		(layer "In2.Cu")
		(net 223)
	)
	(segment
		(start 129.49 85.5)
		(end 129.49 85.21)
		(width 0.15)
		(layer "In2.Cu")
		(net 223)
	)
	(segment
		(start 125.36 67.34)
		(end 125.36 67.36)
		(width 0.162)
		(layer "In2.Cu")
		(net 223)
	)
	(segment
		(start 129.357871 66.706591)
		(end 130.185964 66.706591)
		(width 0.162)
		(layer "In2.Cu")
		(net 223)
	)
	(segment
		(start 130.185964 66.706591)
		(end 130.272464 66.793091)
		(width 0.162)
		(layer "In2.Cu")
		(net 223)
	)
	(segment
		(start 130.015538 84.7)
		(end 130 84.7)
		(width 0.162)
		(layer "In2.Cu")
		(net 223)
	)
	(segment
		(start 129.49 85.21)
		(end 129.9 84.8)
		(width 0.15)
		(layer "In2.Cu")
		(net 223)
	)
	(segment
		(start 129.5 83.89)
		(end 130.124 83.266)
		(width 0.2)
		(layer "F.Cu")
		(net 224)
	)
	(segment
		(start 130.86 81.831687)
		(end 130.86 80.94)
		(width 0.2)
		(layer "F.Cu")
		(net 224)
	)
	(segment
		(start 131.2 72.45)
		(end 130.18 71.43)
		(width 0.2)
		(layer "F.Cu")
		(net 224)
	)
	(segment
		(start 130.86 80.94)
		(end 131.2 80.6)
		(width 0.2)
		(layer "F.Cu")
		(net 224)
	)
	(segment
		(start 129.5 84.7)
		(end 129.5 83.89)
		(width 0.15)
		(layer "F.Cu")
		(net 224)
	)
	(segment
		(start 121.3605 65.341001)
		(end 121.461001 65.341001)
		(width 0.182)
		(layer "F.Cu")
		(net 224)
	)
	(segment
		(start 121.461001 65.341001)
		(end 121.86 65.74)
		(width 0.182)
		(layer "F.Cu")
		(net 224)
	)
	(segment
		(start 129.9 85.1)
		(end 129.5 84.7)
		(width 0.15)
		(layer "F.Cu")
		(net 224)
	)
	(segment
		(start 130.124 82.567687)
		(end 130.86 81.831687)
		(width 0.2)
		(layer "F.Cu")
		(net 224)
	)
	(segment
		(start 130.124 83.266)
		(end 130.124 82.567687)
		(width 0.2)
		(layer "F.Cu")
		(net 224)
	)
	(segment
		(start 131.2 80.6)
		(end 131.2 72.45)
		(width 0.2)
		(layer "F.Cu")
		(net 224)
	)
	(via
		(at 130.18 71.43)
		(size 0.45)
		(drill 0.2)
		(layers "F.Cu" "B.Cu")
		(remove_unused_layers yes)
		(keep_end_layers yes)
		(zone_layer_connections)
		(net 224)
	)
	(via
		(at 121.3605 65.341001)
		(size 0.45)
		(drill 0.2)
		(layers "F.Cu" "B.Cu")
		(remove_unused_layers yes)
		(keep_end_layers yes)
		(zone_layer_connections)
		(net 224)
	)
	(segment
		(start 123.350464 65.680464)
		(end 124.71 67.04)
		(width 0.162)
		(layer "In2.Cu")
		(net 224)
	)
	(segment
		(start 130.13 71.43)
		(end 130.18 71.43)
		(width 0.162)
		(layer "In2.Cu")
		(net 224)
	)
	(segment
		(start 125.29 68.13)
		(end 125.29 69.12)
		(width 0.162)
		(layer "In2.Cu")
		(net 224)
	)
	(segment
		(start 125.29 69.12)
		(end 124.78 69.63)
		(width 0.162)
		(layer "In2.Cu")
		(net 224)
	)
	(segment
		(start 121.699963 65.680464)
		(end 123.350464 65.680464)
		(width 0.162)
		(layer "In2.Cu")
		(net 224)
	)
	(segment
		(start 124.78 69.63)
		(end 124.78 69.91)
		(width 0.162)
		(layer "In2.Cu")
		(net 224)
	)
	(segment
		(start 124.71 67.04)
		(end 124.71 67.55)
		(width 0.162)
		(layer "In2.Cu")
		(net 224)
	)
	(segment
		(start 124.991 70.121)
		(end 128.821 70.121)
		(width 0.162)
		(layer "In2.Cu")
		(net 224)
	)
	(segment
		(start 124.71 67.55)
		(end 125.29 68.13)
		(width 0.162)
		(layer "In2.Cu")
		(net 224)
	)
	(segment
		(start 128.821 70.121)
		(end 130.13 71.43)
		(width 0.162)
		(layer "In2.Cu")
		(net 224)
	)
	(segment
		(start 121.3605 65.341001)
		(end 121.699963 65.680464)
		(width 0.162)
		(layer "In2.Cu")
		(net 224)
	)
	(segment
		(start 124.78 69.91)
		(end 124.991 70.121)
		(width 0.162)
		(layer "In2.Cu")
		(net 224)
	)
	(segment
		(start 130.7 78.7)
		(end 130.7 78.5)
		(width 0.2)
		(layer "F.Cu")
		(net 225)
	)
	(segment
		(start 122.26 66.14)
		(end 122.66 65.74)
		(width 0.182)
		(layer "F.Cu")
		(net 225)
	)
	(segment
		(start 130.3 77.5)
		(end 130.3 73.21)
		(width 0.2)
		(layer "F.Cu")
		(net 225)
	)
	(segment
		(start 129.9 78.1)
		(end 129.9 77.9)
		(width 0.2)
		(layer "F.Cu")
		(net 225)
	)
	(segment
		(start 130.3 78.3)
		(end 130.1 78.3)
		(width 0.2)
		(layer "F.Cu")
		(net 225)
	)
	(segment
		(start 129.97 80.63)
		(end 130.3 80.3)
		(width 0.2)
		(layer "F.Cu")
		(net 225)
	)
	(segment
		(start 130.3 73.21)
		(end 129.91 72.82)
		(width 0.2)
		(layer "F.Cu")
		(net 225)
	)
	(segment
		(start 129.97 81.7)
		(end 129.97 80.63)
		(width 0.2)
		(layer "F.Cu")
		(net 225)
	)
	(segment
		(start 129.1 83.813875)
		(end 129.75 83.163875)
		(width 0.2)
		(layer "F.Cu")
		(net 225)
	)
	(segment
		(start 129.1 84.3)
		(end 129.1 83.813875)
		(width 0.2)
		(layer "F.Cu")
		(net 225)
	)
	(segment
		(start 129.75 83.163875)
		(end 129.75 81.92)
		(width 0.2)
		(layer "F.Cu")
		(net 225)
	)
	(segment
		(start 130.5 78.3)
		(end 130.3 78.3)
		(width 0.2)
		(layer "F.Cu")
		(net 225)
	)
	(segment
		(start 130.3 80.3)
		(end 130.3 79.1)
		(width 0.2)
		(layer "F.Cu")
		(net 225)
	)
	(segment
		(start 129.75 81.92)
		(end 129.97 81.7)
		(width 0.2)
		(layer "F.Cu")
		(net 225)
	)
	(via
		(at 129.91 72.82)
		(size 0.45)
		(drill 0.2)
		(layers "F.Cu" "B.Cu")
		(remove_unused_layers yes)
		(keep_end_layers yes)
		(zone_layer_connections)
		(net 225)
	)
	(via
		(at 122.26 66.14)
		(size 0.45)
		(drill 0.2)
		(layers "F.Cu" "B.Cu")
		(remove_unused_layers yes)
		(keep_end_layers yes)
		(zone_layer_connections)
		(net 225)
	)
	(arc
		(start 129.9 77.9)
		(mid 129.958579 77.758579)
		(end 130.1 77.7)
		(width 0.2)
		(layer "F.Cu")
		(net 225)
	)
	(arc
		(start 130.3 79.1)
		(mid 130.358579 78.958579)
		(end 130.5 78.9)
		(width 0.2)
		(layer "F.Cu")
		(net 225)
	)
	(arc
		(start 130.1 77.7)
		(mid 130.241421 77.641421)
		(end 130.3 77.5)
		(width 0.2)
		(layer "F.Cu")
		(net 225)
	)
	(arc
		(start 130.1 78.3)
		(mid 129.958579 78.241421)
		(end 129.9 78.1)
		(width 0.2)
		(layer "F.Cu")
		(net 225)
	)
	(arc
		(start 130.7 78.5)
		(mid 130.641421 78.358579)
		(end 130.5 78.3)
		(width 0.2)
		(layer "F.Cu")
		(net 225)
	)
	(arc
		(start 130.5 78.9)
		(mid 130.641421 78.841421)
		(end 130.7 78.7)
		(width 0.2)
		(layer "F.Cu")
		(net 225)
	)
	(segment
		(start 122.44 66.14)
		(end 122.26 66.14)
		(width 0.162)
		(layer "In2.Cu")
		(net 225)
	)
	(segment
		(start 125.379408 73.34)
		(end 124.87 73.34)
		(width 0.162)
		(layer "In2.Cu")
		(net 225)
	)
	(segment
		(start 128.459 70.959)
		(end 127.760408 70.959)
		(width 0.162)
		(layer "In2.Cu")
		(net 225)
	)
	(segment
		(start 123.8 72.27)
		(end 123.8 71.07)
		(width 0.162)
		(layer "In2.Cu")
		(net 225)
	)
	(segment
		(start 127.760408 70.959)
		(end 125.379408 73.34)
		(width 0.162)
		(layer "In2.Cu")
		(net 225)
	)
	(segment
		(start 129.91 72.82)
		(end 129.91 72.41)
		(width 0.162)
		(layer "In2.Cu")
		(net 225)
	)
	(segment
		(start 123.8 71.07)
		(end 123.95 70.92)
		(width 0.162)
		(layer "In2.Cu")
		(net 225)
	)
	(segment
		(start 123.95 67.65)
		(end 122.44 66.14)
		(width 0.162)
		(layer "In2.Cu")
		(net 225)
	)
	(segment
		(start 129.91 72.41)
		(end 128.459 70.959)
		(width 0.162)
		(layer "In2.Cu")
		(net 225)
	)
	(segment
		(start 123.95 70.92)
		(end 123.95 67.65)
		(width 0.162)
		(layer "In2.Cu")
		(net 225)
	)
	(segment
		(start 124.87 73.34)
		(end 123.8 72.27)
		(width 0.162)
		(layer "In2.Cu")
		(net 225)
	)
	(segment
		(start 119.74 85.1)
		(end 118.17 83.53)
		(width 0.2)
		(layer "F.Cu")
		(net 226)
	)
	(segment
		(start 122.09 69.33)
		(end 120.41 69.33)
		(width 0.15)
		(layer "F.Cu")
		(net 226)
	)
	(segment
		(start 118.17 70.69)
		(end 119.24 69.62)
		(width 0.2)
		(layer "F.Cu")
		(net 226)
	)
	(segment
		(start 119.96 69.62)
		(end 120.25 69.33)
		(width 0.2)
		(layer "F.Cu")
		(net 226)
	)
	(segment
		(start 120.3 85.1)
		(end 119.74 85.1)
		(width 0.2)
		(layer "F.Cu")
		(net 226)
	)
	(segment
		(start 122.48 68.94)
		(end 122.09 69.33)
		(width 0.15)
		(layer "F.Cu")
		(net 226)
	)
	(segment
		(start 120.25 69.33)
		(end 120.41 69.33)
		(width 0.2)
		(layer "F.Cu")
		(net 226)
	)
	(segment
		(start 118.17 83.53)
		(end 118.17 70.69)
		(width 0.2)
		(layer "F.Cu")
		(net 226)
	)
	(segment
		(start 122.48 68.94)
		(end 122.66 68.94)
		(width 0.15)
		(layer "F.Cu")
		(net 226)
	)
	(segment
		(start 119.24 69.62)
		(end 119.96 69.62)
		(width 0.2)
		(layer "F.Cu")
		(net 226)
	)
	(segment
		(start 123.1 84.15)
		(end 123.1 84.7)
		(width 0.15)
		(layer "F.Cu")
		(net 227)
	)
	(segment
		(start 122.871 69.951)
		(end 122.66 69.74)
		(width 0.2)
		(layer "F.Cu")
		(net 227)
	)
	(segment
		(start 123.1 75.760016)
		(end 123.808 75.052016)
		(width 0.2)
		(layer "F.Cu")
		(net 227)
	)
	(segment
		(start 123.181724 73.669724)
		(end 123.379724 73.669724)
		(width 0.2)
		(layer "F.Cu")
		(net 227)
	)
	(segment
		(start 124.25 76.95)
		(end 124.25 76.9)
		(width 0.2)
		(layer "F.Cu")
		(net 227)
	)
	(segment
		(start 123.258288 69.951)
		(end 122.871 69.951)
		(width 0.2)
		(layer "F.Cu")
		(net 227)
	)
	(segment
		(start 123.575 78.225)
		(end 123.375 78.225)
		(width 0.2)
		(layer "F.Cu")
		(net 227)
	)
	(segment
		(start 123.149448 73.937448)
		(end 123.149448 73.702)
		(width 0.2)
		(layer "F.Cu")
		(net 227)
	)
	(segment
		(start 123.379724 73.969724)
		(end 123.181724 73.969724)
		(width 0.2)
		(layer "F.Cu")
		(net 227)
	)
	(segment
		(start 123.575 76.225)
		(end 123.375 76.225)
		(width 0.2)
		(layer "F.Cu")
		(net 227)
	)
	(segment
		(start 123.1 84.15)
		(end 123.1 79.9)
		(width 0.2)
		(layer "F.Cu")
		(net 227)
	)
	(segment
		(start 123.1 75.9)
		(end 123.1 75.760016)
		(width 0.2)
		(layer "F.Cu")
		(net 227)
	)
	(segment
		(start 123.1 84.7)
		(end 123.5 85.1)
		(width 0.15)
		(layer "F.Cu")
		(net 227)
	)
	(segment
		(start 123.375 79.625)
		(end 123.575 79.625)
		(width 0.2)
		(layer "F.Cu")
		(net 227)
	)
	(segment
		(start 123.375 77.625)
		(end 123.575 77.625)
		(width 0.2)
		(layer "F.Cu")
		(net 227)
	)
	(segment
		(start 124.25 78.95)
		(end 124.25 78.9)
		(width 0.2)
		(layer "F.Cu")
		(net 227)
	)
	(segment
		(start 123.808 73.241448)
		(end 123.808 70.500712)
		(width 0.2)
		(layer "F.Cu")
		(net 227)
	)
	(segment
		(start 123.1 77.95)
		(end 123.1 77.9)
		(width 0.2)
		(layer "F.Cu")
		(net 227)
	)
	(segment
		(start 123.808 70.500712)
		(end 123.258288 69.951)
		(width 0.2)
		(layer "F.Cu")
		(net 227)
	)
	(segment
		(start 123.1 75.95)
		(end 123.1 75.9)
		(width 0.2)
		(layer "F.Cu")
		(net 227)
	)
	(segment
		(start 123.808 75.052016)
		(end 123.808 74.398)
		(width 0.2)
		(layer "F.Cu")
		(net 227)
	)
	(arc
		(start 123.808 74.398)
		(mid 123.682561 74.095163)
		(end 123.379724 73.969724)
		(width 0.2)
		(layer "F.Cu")
		(net 227)
	)
	(arc
		(start 123.575 79.625)
		(mid 124.052297 79.427297)
		(end 124.25 78.95)
		(width 0.2)
		(layer "F.Cu")
		(net 227)
	)
	(arc
		(start 123.575 77.625)
		(mid 124.052297 77.427297)
		(end 124.25 76.95)
		(width 0.2)
		(layer "F.Cu")
		(net 227)
	)
	(arc
		(start 124.25 76.9)
		(mid 124.052297 76.422703)
		(end 123.575 76.225)
		(width 0.2)
		(layer "F.Cu")
		(net 227)
	)
	(arc
		(start 124.25 78.9)
		(mid 124.052297 78.422703)
		(end 123.575 78.225)
		(width 0.2)
		(layer "F.Cu")
		(net 227)
	)
	(arc
		(start 123.181724 73.969724)
		(mid 123.158901 73.960271)
		(end 123.149448 73.937448)
		(width 0.2)
		(layer "F.Cu")
		(net 227)
	)
	(arc
		(start 123.379724 73.669724)
		(mid 123.682561 73.544285)
		(end 123.808 73.241448)
		(width 0.2)
		(layer "F.Cu")
		(net 227)
	)
	(arc
		(start 123.375 76.225)
		(mid 123.180546 76.144454)
		(end 123.1 75.95)
		(width 0.2)
		(layer "F.Cu")
		(net 227)
	)
	(arc
		(start 123.1 79.9)
		(mid 123.180546 79.705546)
		(end 123.375 79.625)
		(width 0.2)
		(layer "F.Cu")
		(net 227)
	)
	(arc
		(start 123.1 77.9)
		(mid 123.180546 77.705546)
		(end 123.375 77.625)
		(width 0.2)
		(layer "F.Cu")
		(net 227)
	)
	(arc
		(start 123.375 78.225)
		(mid 123.180546 78.144454)
		(end 123.1 77.95)
		(width 0.2)
		(layer "F.Cu")
		(net 227)
	)
	(arc
		(start 123.149448 73.702)
		(mid 123.158901 73.679177)
		(end 123.181724 73.669724)
		(width 0.2)
		(layer "F.Cu")
		(net 227)
	)
	(segment
		(start 123.9 82.30066)
		(end 124.57 81.63066)
		(width 0.2)
		(layer "F.Cu")
		(net 228)
	)
	(segment
		(start 125.73 78.9)
		(end 125.73 78.6)
		(width 0.2)
		(layer "F.Cu")
		(net 228)
	)
	(segment
		(start 124.57 81.63066)
		(end 124.57 80.63)
		(width 0.2)
		(layer "F.Cu")
		(net 228)
	)
	(segment
		(start 125.43 71.65)
		(end 125.15 71.37)
		(width 0.2)
		(layer "F.Cu")
		(net 228)
	)
	(segment
		(start 123.9 85.405686)
		(end 123.9 84)
		(width 0.15)
		(layer "F.Cu")
		(net 228)
	)
	(segment
		(start 125.43 79.77)
		(end 125.43 79.2)
		(width 0.2)
		(layer "F.Cu")
		(net 228)
	)
	(segment
		(start 123.805686 85.5)
		(end 123.9 85.405686)
		(width 0.15)
		(layer "F.Cu")
		(net 228)
	)
	(segment
		(start 123.9 84)
		(end 123.9 82.30066)
		(width 0.2)
		(layer "F.Cu")
		(net 228)
	)
	(segment
		(start 126.28 70.12)
		(end 126.66 69.74)
		(width 0.2)
		(layer "F.Cu")
		(net 228)
	)
	(segment
		(start 123.1 85.5)
		(end 123.805686 85.5)
		(width 0.15)
		(layer "F.Cu")
		(net 228)
	)
	(segment
		(start 125.15 70.46)
		(end 125.49 70.12)
		(width 0.2)
		(layer "F.Cu")
		(net 228)
	)
	(segment
		(start 125.49 70.12)
		(end 126.28 70.12)
		(width 0.2)
		(layer "F.Cu")
		(net 228)
	)
	(segment
		(start 125.43 78.3)
		(end 125.43 71.65)
		(width 0.2)
		(layer "F.Cu")
		(net 228)
	)
	(segment
		(start 122.7 85.1)
		(end 123.1 85.5)
		(width 0.15)
		(layer "F.Cu")
		(net 228)
	)
	(segment
		(start 124.57 80.63)
		(end 125.43 79.77)
		(width 0.2)
		(layer "F.Cu")
		(net 228)
	)
	(segment
		(start 125.15 71.37)
		(end 125.15 70.46)
		(width 0.2)
		(layer "F.Cu")
		(net 228)
	)
	(arc
		(start 125.73 78.6)
		(mid 125.686066 78.493934)
		(end 125.58 78.45)
		(width 0.2)
		(layer "F.Cu")
		(net 228)
	)
	(arc
		(start 125.58 79.05)
		(mid 125.686066 79.006066)
		(end 125.73 78.9)
		(width 0.2)
		(layer "F.Cu")
		(net 228)
	)
	(arc
		(start 125.58 78.45)
		(mid 125.473934 78.406066)
		(end 125.43 78.3)
		(width 0.2)
		(layer "F.Cu")
		(net 228)
	)
	(arc
		(start 125.43 79.2)
		(mid 125.473934 79.093934)
		(end 125.58 79.05)
		(width 0.2)
		(layer "F.Cu")
		(net 228)
	)
	(segment
		(start 122.243762 78.723119)
		(end 122.243762 78.666881)
		(width 0.2)
		(layer "F.Cu")
		(net 229)
	)
	(segment
		(start 122.66 71.01)
		(end 122.66 71.34)
		(width 0.2)
		(layer "F.Cu")
		(net 229)
	)
	(segment
		(start 122.243762 77.523119)
		(end 122.243762 77.466881)
		(width 0.2)
		(layer "F.Cu")
		(net 229)
	)
	(segment
		(start 121.7 77.795)
		(end 121.971881 77.795)
		(width 0.2)
		(layer "F.Cu")
		(net 229)
	)
	(segment
		(start 121.971881 79.598119)
		(end 121.7 79.598119)
		(width 0.2)
		(layer "F.Cu")
		(net 229)
	)
	(segment
		(start 122.3 81.67)
		(end 121.7 81.07)
		(width 0.2)
		(layer "F.Cu")
		(net 229)
	)
	(segment
		(start 121.7 79.598119)
		(end 121.7 79.595)
		(width 0.2)
		(layer "F.Cu")
		(net 229)
	)
	(segment
		(start 122.3 84.7)
		(end 122.3 84.01)
		(width 0.15)
		(layer "F.Cu")
		(net 229)
	)
	(segment
		(start 121.9 85.1)
		(end 122.3 84.7)
		(width 0.15)
		(layer "F.Cu")
		(net 229)
	)
	(segment
		(start 122.99 70.95)
		(end 122.72 70.95)
		(width 0.2)
		(layer "F.Cu")
		(net 229)
	)
	(segment
		(start 121.971881 78.395)
		(end 121.7 78.395)
		(width 0.2)
		(layer "F.Cu")
		(net 229)
	)
	(segment
		(start 121.7 78.995)
		(end 121.971881 78.995)
		(width 0.2)
		(layer "F.Cu")
		(net 229)
	)
	(segment
		(start 121.7 73.27)
		(end 123.09 71.88)
		(width 0.2)
		(layer "F.Cu")
		(net 229)
	)
	(segment
		(start 121.7 76.923119)
		(end 121.7 73.27)
		(width 0.2)
		(layer "F.Cu")
		(net 229)
	)
	(segment
		(start 123.09 71.05)
		(end 122.99 70.95)
		(width 0.2)
		(layer "F.Cu")
		(net 229)
	)
	(segment
		(start 121.456238 78.273119)
		(end 121.456238 77.916881)
		(width 0.2)
		(layer "F.Cu")
		(net 229)
	)
	(segment
		(start 121.7 81.07)
		(end 121.7 80.47)
		(width 0.2)
		(layer "F.Cu")
		(net 229)
	)
	(segment
		(start 121.456238 79.473119)
		(end 121.456238 79.116881)
		(width 0.2)
		(layer "F.Cu")
		(net 229)
	)
	(segment
		(start 123.09 71.88)
		(end 123.09 71.05)
		(width 0.2)
		(layer "F.Cu")
		(net 229)
	)
	(segment
		(start 121.7 78.395)
		(end 121.578119 78.395)
		(width 0.2)
		(layer "F.Cu")
		(net 229)
	)
	(segment
		(start 122.3 84.01)
		(end 122.3 81.67)
		(width 0.2)
		(layer "F.Cu")
		(net 229)
	)
	(segment
		(start 122.72 70.95)
		(end 122.66 71.01)
		(width 0.2)
		(layer "F.Cu")
		(net 229)
	)
	(segment
		(start 121.578119 78.995)
		(end 121.7 78.995)
		(width 0.2)
		(layer "F.Cu")
		(net 229)
	)
	(segment
		(start 121.7 79.595)
		(end 121.578119 79.595)
		(width 0.2)
		(layer "F.Cu")
		(net 229)
	)
	(segment
		(start 122.243762 79.926238)
		(end 122.243762 79.87)
		(width 0.2)
		(layer "F.Cu")
		(net 229)
	)
	(segment
		(start 121.578119 77.795)
		(end 121.7 77.795)
		(width 0.2)
		(layer "F.Cu")
		(net 229)
	)
	(arc
		(start 121.7 80.47)
		(mid 121.779632 80.277751)
		(end 121.971881 80.198119)
		(width 0.2)
		(layer "F.Cu")
		(net 229)
	)
	(arc
		(start 121.456238 79.116881)
		(mid 121.491936 79.030698)
		(end 121.578119 78.995)
		(width 0.2)
		(layer "F.Cu")
		(net 229)
	)
	(arc
		(start 121.971881 77.795)
		(mid 122.16413 77.715368)
		(end 122.243762 77.523119)
		(width 0.2)
		(layer "F.Cu")
		(net 229)
	)
	(arc
		(start 121.971881 80.198119)
		(mid 122.16413 80.118487)
		(end 122.243762 79.926238)
		(width 0.2)
		(layer "F.Cu")
		(net 229)
	)
	(arc
		(start 122.243762 79.87)
		(mid 122.16413 79.677751)
		(end 121.971881 79.598119)
		(width 0.2)
		(layer "F.Cu")
		(net 229)
	)
	(arc
		(start 122.243762 77.466881)
		(mid 122.16413 77.274632)
		(end 121.971881 77.195)
		(width 0.2)
		(layer "F.Cu")
		(net 229)
	)
	(arc
		(start 121.971881 77.195)
		(mid 121.779632 77.115368)
		(end 121.7 76.923119)
		(width 0.2)
		(layer "F.Cu")
		(net 229)
	)
	(arc
		(start 122.243762 78.666881)
		(mid 122.16413 78.474632)
		(end 121.971881 78.395)
		(width 0.2)
		(layer "F.Cu")
		(net 229)
	)
	(arc
		(start 121.578119 78.395)
		(mid 121.491936 78.359302)
		(end 121.456238 78.273119)
		(width 0.2)
		(layer "F.Cu")
		(net 229)
	)
	(arc
		(start 121.456238 77.916881)
		(mid 121.491936 77.830698)
		(end 121.578119 77.795)
		(width 0.2)
		(layer "F.Cu")
		(net 229)
	)
	(arc
		(start 121.578119 79.595)
		(mid 121.491936 79.559302)
		(end 121.456238 79.473119)
		(width 0.2)
		(layer "F.Cu")
		(net 229)
	)
	(arc
		(start 121.971881 78.995)
		(mid 122.16413 78.915368)
		(end 122.243762 78.723119)
		(width 0.2)
		(layer "F.Cu")
		(net 229)
	)
	(segment
		(start 122.26 71.76)
		(end 122.26 69.56)
		(width 0.2)
		(layer "F.Cu")
		(net 230)
	)
	(segment
		(start 124.13 68.94)
		(end 125.86 68.94)
		(width 0.2)
		(layer "F.Cu")
		(net 230)
	)
	(segment
		(start 123.73 69.34)
		(end 124.13 68.94)
		(width 0.2)
		(layer "F.Cu")
		(net 230)
	)
	(segment
		(start 120.82 77.34)
		(end 120.738526 77.34)
		(width 0.2)
		(layer "F.Cu")
		(net 230)
	)
	(segment
		(start 121.9 82.73)
		(end 121.12 81.95)
		(width 0.2)
		(layer "F.Cu")
		(net 230)
	)
	(segment
		(start 121.12 76.44)
		(end 121.12 72.9)
		(width 0.2)
		(layer "F.Cu")
		(net 230)
	)
	(segment
		(start 122.48 69.34)
		(end 123.73 69.34)
		(width 0.2)
		(layer "F.Cu")
		(net 230)
	)
	(segment
		(start 121.9 84.3)
		(end 121.9 82.73)
		(width 0.2)
		(layer "F.Cu")
		(net 230)
	)
	(segment
		(start 121.12 81.95)
		(end 121.12 77.64)
		(width 0.2)
		(layer "F.Cu")
		(net 230)
	)
	(segment
		(start 120.738526 76.74)
		(end 120.82 76.74)
		(width 0.2)
		(layer "F.Cu")
		(net 230)
	)
	(segment
		(start 121.12 72.9)
		(end 122.26 71.76)
		(width 0.2)
		(layer "F.Cu")
		(net 230)
	)
	(segment
		(start 122.26 69.56)
		(end 122.48 69.34)
		(width 0.2)
		(layer "F.Cu")
		(net 230)
	)
	(arc
		(start 120.438526 77.04)
		(mid 120.526394 76.827868)
		(end 120.738526 76.74)
		(width 0.2)
		(layer "F.Cu")
		(net 230)
	)
	(arc
		(start 120.738526 77.34)
		(mid 120.526394 77.252132)
		(end 120.438526 77.04)
		(width 0.2)
		(layer "F.Cu")
		(net 230)
	)
	(arc
		(start 121.12 77.64)
		(mid 121.032132 77.427868)
		(end 120.82 77.34)
		(width 0.2)
		(layer "F.Cu")
		(net 230)
	)
	(arc
		(start 120.82 76.74)
		(mid 121.032132 76.652132)
		(end 121.12 76.44)
		(width 0.2)
		(layer "F.Cu")
		(net 230)
	)
	(segment
		(start 124.3 82.84)
		(end 124.3 84.3)
		(width 0.2)
		(layer "F.Cu")
		(net 231)
	)
	(segment
		(start 125.55 81.74)
		(end 125.46 81.65)
		(width 0.2)
		(layer "F.Cu")
		(net 231)
	)
	(segment
		(start 125.89 80.61)
		(end 125.89 81.52)
		(width 0.2)
		(layer "F.Cu")
		(net 231)
	)
	(segment
		(start 124.73 82.41)
		(end 124.3 82.84)
		(width 0.2)
		(layer "F.Cu")
		(net 231)
	)
	(segment
		(start 126.01 72.69)
		(end 126.56 72.69)
		(width 0.2)
		(layer "F.Cu")
		(net 231)
	)
	(segment
		(start 124.86 82.41)
		(end 124.73 82.41)
		(width 0.2)
		(layer "F.Cu")
		(net 231)
	)
	(segment
		(start 125.23 80.66)
		(end 124.99 80.9)
		(width 0.2)
		(layer "F.Cu")
		(net 231)
	)
	(segment
		(start 125.76 73.54)
		(end 125.76 73.64)
		(width 0.2)
		(layer "F.Cu")
		(net 231)
	)
	(segment
		(start 125.61 80.13)
		(end 125.61 80.33)
		(width 0.2)
		(layer "F.Cu")
		(net 231)
	)
	(segment
		(start 125.86 71.34)
		(end 126.26 71.74)
		(width 0.2)
		(layer "F.Cu")
		(net 231)
	)
	(segment
		(start 126.04 80)
		(end 125.74 80)
		(width 0.2)
		(layer "F.Cu")
		(net 231)
	)
	(segment
		(start 125.76 74.64)
		(end 125.76 74.74)
		(width 0.2)
		(layer "F.Cu")
		(net 231)
	)
	(segment
		(start 126.26 79.78)
		(end 126.04 80)
		(width 0.2)
		(layer "F.Cu")
		(net 231)
	)
	(segment
		(start 126.26 77.64)
		(end 126.26 77.74)
		(width 0.2)
		(layer "F.Cu")
		(net 231)
	)
	(segment
		(start 125.76 72.34)
		(end 125.76 72.44)
		(width 0.2)
		(layer "F.Cu")
		(net 231)
	)
	(segment
		(start 125.89 81.52)
		(end 125.67 81.74)
		(width 0.2)
		(layer "F.Cu")
		(net 231)
	)
	(segment
		(start 125.46 81.22)
		(end 125.48 81.2)
		(width 0.2)
		(layer "F.Cu")
		(net 231)
	)
	(segment
		(start 126.26 76.44)
		(end 126.26 76.54)
		(width 0.2)
		(layer "F.Cu")
		(net 231)
	)
	(segment
		(start 125.34 80.66)
		(end 125.23 80.66)
		(width 0.2)
		(layer "F.Cu")
		(net 231)
	)
	(segment
		(start 125.48 80.8)
		(end 125.34 80.66)
		(width 0.2)
		(layer "F.Cu")
		(net 231)
	)
	(segment
		(start 125.76 75.84)
		(end 125.76 75.94)
		(width 0.2)
		(layer "F.Cu")
		(net 231)
	)
	(segment
		(start 126.26 71.74)
		(end 126.26 71.84)
		(width 0.2)
		(layer "F.Cu")
		(net 231)
	)
	(segment
		(start 124.99 82.28)
		(end 124.86 82.41)
		(width 0.2)
		(layer "F.Cu")
		(net 231)
	)
	(segment
		(start 126.36 78.515)
		(end 126.36 79.015)
		(width 0.2)
		(layer "F.Cu")
		(net 231)
	)
	(segment
		(start 125.48 81.2)
		(end 125.48 80.8)
		(width 0.2)
		(layer "F.Cu")
		(net 231)
	)
	(segment
		(start 125.67 81.74)
		(end 125.55 81.74)
		(width 0.2)
		(layer "F.Cu")
		(net 231)
	)
	(segment
		(start 125.76 77.04)
		(end 125.76 77.14)
		(width 0.2)
		(layer "F.Cu")
		(net 231)
	)
	(segment
		(start 124.99 80.9)
		(end 124.99 82.28)
		(width 0.2)
		(layer "F.Cu")
		(net 231)
	)
	(segment
		(start 126.26 79.115)
		(end 126.26 79.78)
		(width 0.2)
		(layer "F.Cu")
		(net 231)
	)
	(segment
		(start 126.01 77.99)
		(end 126.01 78.34)
		(width 0.2)
		(layer "F.Cu")
		(net 231)
	)
	(segment
		(start 125.61 80.33)
		(end 125.89 80.61)
		(width 0.2)
		(layer "F.Cu")
		(net 231)
	)
	(segment
		(start 126.135 78.465)
		(end 126.31 78.465)
		(width 0.2)
		(layer "F.Cu")
		(net 231)
	)
	(segment
		(start 126.56 73.29)
		(end 126.01 73.29)
		(width 0.2)
		(layer "F.Cu")
		(net 231)
	)
	(segment
		(start 126.26 75.24)
		(end 126.26 75.34)
		(width 0.2)
		(layer "F.Cu")
		(net 231)
	)
	(segment
		(start 125.46 81.65)
		(end 125.46 81.22)
		(width 0.2)
		(layer "F.Cu")
		(net 231)
	)
	(segment
		(start 125.74 80)
		(end 125.61 80.13)
		(width 0.2)
		(layer "F.Cu")
		(net 231)
	)
	(arc
		(start 126.01 74.39)
		(mid 125.833223 74.463223)
		(end 125.76 74.64)
		(width 0.2)
		(layer "F.Cu")
		(net 231)
	)
	(arc
		(start 126.26 77.74)
		(mid 126.223388 77.828388)
		(end 126.135 77.865)
		(width 0.2)
		(layer "F.Cu")
		(net 231)
	)
	(arc
		(start 126.86 72.99)
		(mid 126.772132 73.202132)
		(end 126.56 73.29)
		(width 0.2)
		(layer "F.Cu")
		(net 231)
	)
	(arc
		(start 125.76 72.44)
		(mid 125.833223 72.616777)
		(end 126.01 72.69)
		(width 0.2)
		(layer "F.Cu")
		(net 231)
	)
	(arc
		(start 126.26 74.14)
		(mid 126.186777 74.316777)
		(end 126.01 74.39)
		(width 0.2)
		(layer "F.Cu")
		(net 231)
	)
	(arc
		(start 126.31 78.465)
		(mid 126.345355 78.479645)
		(end 126.36 78.515)
		(width 0.2)
		(layer "F.Cu")
		(net 231)
	)
	(arc
		(start 126.01 75.59)
		(mid 125.833223 75.663223)
		(end 125.76 75.84)
		(width 0.2)
		(layer "F.Cu")
		(net 231)
	)
	(arc
		(start 126.26 71.84)
		(mid 126.186777 72.016777)
		(end 126.01 72.09)
		(width 0.2)
		(layer "F.Cu")
		(net 231)
	)
	(arc
		(start 126.135 77.865)
		(mid 126.046612 77.901612)
		(end 126.01 77.99)
		(width 0.2)
		(layer "F.Cu")
		(net 231)
	)
	(arc
		(start 126.31 79.065)
		(mid 126.274645 79.079645)
		(end 126.26 79.115)
		(width 0.2)
		(layer "F.Cu")
		(net 231)
	)
	(arc
		(start 126.01 73.89)
		(mid 126.186777 73.963223)
		(end 126.26 74.14)
		(width 0.2)
		(layer "F.Cu")
		(net 231)
	)
	(arc
		(start 125.76 73.64)
		(mid 125.833223 73.816777)
		(end 126.01 73.89)
		(width 0.2)
		(layer "F.Cu")
		(net 231)
	)
	(arc
		(start 125.76 74.74)
		(mid 125.833223 74.916777)
		(end 126.01 74.99)
		(width 0.2)
		(layer "F.Cu")
		(net 231)
	)
	(arc
		(start 126.01 76.79)
		(mid 125.833223 76.863223)
		(end 125.76 77.04)
		(width 0.2)
		(layer "F.Cu")
		(net 231)
	)
	(arc
		(start 126.01 74.99)
		(mid 126.186777 75.063223)
		(end 126.26 75.24)
		(width 0.2)
		(layer "F.Cu")
		(net 231)
	)
	(arc
		(start 126.01 72.09)
		(mid 125.833223 72.163223)
		(end 125.76 72.34)
		(width 0.2)
		(layer "F.Cu")
		(net 231)
	)
	(arc
		(start 126.26 75.34)
		(mid 126.186777 75.516777)
		(end 126.01 75.59)
		(width 0.2)
		(layer "F.Cu")
		(net 231)
	)
	(arc
		(start 125.76 75.94)
		(mid 125.833223 76.116777)
		(end 126.01 76.19)
		(width 0.2)
		(layer "F.Cu")
		(net 231)
	)
	(arc
		(start 126.26 76.54)
		(mid 126.186777 76.716777)
		(end 126.01 76.79)
		(width 0.2)
		(layer "F.Cu")
		(net 231)
	)
	(arc
		(start 126.56 72.69)
		(mid 126.772132 72.777868)
		(end 126.86 72.99)
		(width 0.2)
		(layer "F.Cu")
		(net 231)
	)
	(arc
		(start 125.76 77.14)
		(mid 125.833223 77.316777)
		(end 126.01 77.39)
		(width 0.2)
		(layer "F.Cu")
		(net 231)
	)
	(arc
		(start 126.36 79.015)
		(mid 126.345355 79.050355)
		(end 126.31 79.065)
		(width 0.2)
		(layer "F.Cu")
		(net 231)
	)
	(arc
		(start 126.01 76.19)
		(mid 126.186777 76.263223)
		(end 126.26 76.44)
		(width 0.2)
		(layer "F.Cu")
		(net 231)
	)
	(arc
		(start 126.01 78.34)
		(mid 126.046612 78.428388)
		(end 126.135 78.465)
		(width 0.2)
		(layer "F.Cu")
		(net 231)
	)
	(arc
		(start 126.01 77.39)
		(mid 126.186777 77.463223)
		(end 126.26 77.64)
		(width 0.2)
		(layer "F.Cu")
		(net 231)
	)
	(arc
		(start 126.01 73.29)
		(mid 125.833223 73.363223)
		(end 125.76 73.54)
		(width 0.2)
		(layer "F.Cu")
		(net 231)
	)
	(segment
		(start 122.26 68.54)
		(end 122.66 68.14)
		(width 0.182)
		(layer "F.Cu")
		(net 232)
	)
	(segment
		(start 127.11 83.875686)
		(end 127.11 83.05)
		(width 0.15)
		(layer "F.Cu")
		(net 232)
	)
	(segment
		(start 127.85 76.91)
		(end 127.85 82.31)
		(width 0.2)
		(layer "F.Cu")
		(net 232)
	)
	(segment
		(start 127.1 83.885686)
		(end 127.11 83.875686)
		(width 0.15)
		(layer "F.Cu")
		(net 232)
	)
	(segment
		(start 127.85 76.71)
		(end 127.85 76.91)
		(width 0.2)
		(layer "F.Cu")
		(net 232)
	)
	(segment
		(start 127.1 84.7)
		(end 127.1 83.885686)
		(width 0.15)
		(layer "F.Cu")
		(net 232)
	)
	(segment
		(start 127.85 82.31)
		(end 127.11 83.05)
		(width 0.2)
		(layer "F.Cu")
		(net 232)
	)
	(segment
		(start 127.95 76.41)
		(end 127.95 76.61)
		(width 0.2)
		(layer "F.Cu")
		(net 232)
	)
	(segment
		(start 127.8 74.5)
		(end 127.85 74.55)
		(width 0.2)
		(layer "F.Cu")
		(net 232)
	)
	(segment
		(start 127.5 85.1)
		(end 127.1 84.7)
		(width 0.15)
		(layer "F.Cu")
		(net 232)
	)
	(segment
		(start 127.85 74.55)
		(end 127.85 76.31)
		(width 0.2)
		(layer "F.Cu")
		(net 232)
	)
	(via
		(at 122.26 68.54)
		(size 0.45)
		(drill 0.2)
		(layers "F.Cu" "B.Cu")
		(remove_unused_layers yes)
		(keep_end_layers yes)
		(zone_layer_connections)
		(net 232)
	)
	(via
		(at 127.8 74.5)
		(size 0.45)
		(drill 0.2)
		(layers "F.Cu" "B.Cu")
		(remove_unused_layers yes)
		(keep_end_layers yes)
		(zone_layer_connections)
		(net 232)
	)
	(arc
		(start 127.9 76.36)
		(mid 127.935355 76.374645)
		(end 127.95 76.41)
		(width 0.2)
		(layer "F.Cu")
		(net 232)
	)
	(arc
		(start 127.85 76.31)
		(mid 127.864645 76.345355)
		(end 127.9 76.36)
		(width 0.2)
		(layer "F.Cu")
		(net 232)
	)
	(arc
		(start 127.95 76.61)
		(mid 127.935355 76.645355)
		(end 127.9 76.66)
		(width 0.2)
		(layer "F.Cu")
		(net 232)
	)
	(arc
		(start 127.9 76.66)
		(mid 127.864645 76.674645)
		(end 127.85 76.71)
		(width 0.2)
		(layer "F.Cu")
		(net 232)
	)
	(segment
		(start 120.37 75.7)
		(end 120.37 73.2925)
		(width 0.162)
		(layer "In2.Cu")
		(net 232)
	)
	(segment
		(start 121.5 72.54)
		(end 121.96 72.08)
		(width 0.162)
		(layer "In2.Cu")
		(net 232)
	)
	(segment
		(start 121.96 68.84)
		(end 122.26 68.54)
		(width 0.162)
		(layer "In2.Cu")
		(net 232)
	)
	(segment
		(start 127.8 74.5)
		(end 125.92 76.38)
		(width 0.162)
		(layer "In2.Cu")
		(net 232)
	)
	(segment
		(start 121.96 72.08)
		(end 121.96 68.84)
		(width 0.162)
		(layer "In2.Cu")
		(net 232)
	)
	(segment
		(start 120.37 73.2925)
		(end 121.1225 72.54)
		(width 0.162)
		(layer "In2.Cu")
		(net 232)
	)
	(segment
		(start 125.92 76.38)
		(end 121.05 76.38)
		(width 0.162)
		(layer "In2.Cu")
		(net 232)
	)
	(segment
		(start 121.05 76.38)
		(end 120.37 75.7)
		(width 0.162)
		(layer "In2.Cu")
		(net 232)
	)
	(segment
		(start 121.1225 72.54)
		(end 121.5 72.54)
		(width 0.162)
		(layer "In2.Cu")
		(net 232)
	)
	(segment
		(start 128.7 80.4)
		(end 128.7 73.17)
		(width 0.2)
		(layer "F.Cu")
		(net 233)
	)
	(segment
		(start 128.7 73.17)
		(end 128.4 72.87)
		(width 0.2)
		(layer "F.Cu")
		(net 233)
	)
	(segment
		(start 128.395 80.705)
		(end 128.7 80.4)
		(width 0.2)
		(layer "F.Cu")
		(net 233)
	)
	(segment
		(start 122.26 67.74)
		(end 122.66 67.34)
		(width 0.182)
		(layer "F.Cu")
		(net 233)
	)
	(segment
		(start 128.395 84.205)
		(end 128.395 80.705)
		(width 0.2)
		(layer "F.Cu")
		(net 233)
	)
	(segment
		(start 128.3 84.3)
		(end 128.395 84.205)
		(width 0.2)
		(layer "F.Cu")
		(net 233)
	)
	(via
		(at 122.26 67.74)
		(size 0.45)
		(drill 0.2)
		(layers "F.Cu" "B.Cu")
		(remove_unused_layers yes)
		(keep_end_layers yes)
		(zone_layer_connections)
		(net 233)
	)
	(via
		(at 128.4 72.87)
		(size 0.45)
		(drill 0.2)
		(layers "F.Cu" "B.Cu")
		(remove_unused_layers yes)
		(keep_end_layers yes)
		(zone_layer_connections)
		(net 233)
	)
	(segment
		(start 121.58 73.39)
		(end 122.65 72.32)
		(width 0.162)
		(layer "In2.Cu")
		(net 233)
	)
	(segment
		(start 121.58 75.36)
		(end 121.58 73.39)
		(width 0.162)
		(layer "In2.Cu")
		(net 233)
	)
	(segment
		(start 128.4 72.87)
		(end 128.17 72.87)
		(width 0.162)
		(layer "In2.Cu")
		(net 233)
	)
	(segment
		(start 125.35 75.69)
		(end 121.91 75.69)
		(width 0.162)
		(layer "In2.Cu")
		(net 233)
	)
	(segment
		(start 122.65 69.15)
		(end 122.8 69)
		(width 0.162)
		(layer "In2.Cu")
		(net 233)
	)
	(segment
		(start 122.65 72.32)
		(end 122.65 69.15)
		(width 0.162)
		(layer "In2.Cu")
		(net 233)
	)
	(segment
		(start 122.8 68.28)
		(end 122.26 67.74)
		(width 0.162)
		(layer "In2.Cu")
		(net 233)
	)
	(segment
		(start 128.17 72.87)
		(end 125.35 75.69)
		(width 0.162)
		(layer "In2.Cu")
		(net 233)
	)
	(segment
		(start 122.8 69)
		(end 122.8 68.28)
		(width 0.162)
		(layer "In2.Cu")
		(net 233)
	)
	(segment
		(start 121.91 75.69)
		(end 121.58 75.36)
		(width 0.162)
		(layer "In2.Cu")
		(net 233)
	)
	(segment
		(start 132.12 81.35)
		(end 133 80.47)
		(width 0.2)
		(layer "F.Cu")
		(net 234)
	)
	(segment
		(start 126.66 67.34)
		(end 127.06 67.74)
		(width 0.182)
		(layer "F.Cu")
		(net 234)
	)
	(segment
		(start 132.12 82.42)
		(end 132.12 81.35)
		(width 0.2)
		(layer "F.Cu")
		(net 234)
	)
	(segment
		(start 133 71.73)
		(end 130.31 69.04)
		(width 0.2)
		(layer "F.Cu")
		(net 234)
	)
	(segment
		(start 133 80.47)
		(end 133 71.73)
		(width 0.2)
		(layer "F.Cu")
		(net 234)
	)
	(segment
		(start 130.3 84.7)
		(end 130.7 85.1)
		(width 0.15)
		(layer "F.Cu")
		(net 234)
	)
	(segment
		(start 130.3 84.04)
		(end 130.3 84.7)
		(width 0.15)
		(layer "F.Cu")
		(net 234)
	)
	(segment
		(start 130.3 84.04)
		(end 130.67 83.67)
		(width 0.2)
		(layer "F.Cu")
		(net 234)
	)
	(segment
		(start 130.87 83.67)
		(end 132.12 82.42)
		(width 0.2)
		(layer "F.Cu")
		(net 234)
	)
	(segment
		(start 130.67 83.67)
		(end 130.87 83.67)
		(width 0.2)
		(layer "F.Cu")
		(net 234)
	)
	(segment
		(start 130.31 69.04)
		(end 130.04 69.04)
		(width 0.2)
		(layer "F.Cu")
		(net 234)
	)
	(via
		(at 127.06 67.74)
		(size 0.45)
		(drill 0.2)
		(layers "F.Cu" "B.Cu")
		(remove_unused_layers yes)
		(keep_end_layers yes)
		(zone_layer_connections)
		(net 234)
	)
	(via
		(at 130.04 69.04)
		(size 0.45)
		(drill 0.2)
		(layers "F.Cu" "B.Cu")
		(remove_unused_layers yes)
		(keep_end_layers yes)
		(zone_layer_connections)
		(net 234)
	)
	(segment
		(start 130.9 69.9)
		(end 130.669408 69.9)
		(width 0.162)
		(layer "In2.Cu")
		(net 234)
	)
	(segment
		(start 128.917402 68.094805)
		(end 128.962598 68.094805)
		(width 0.162)
		(layer "In2.Cu")
		(net 234)
	)
	(segment
		(start 129.74 67.74)
		(end 130.53 67.74)
		(width 0.162)
		(layer "In2.Cu")
		(net 234)
	)
	(segment
		(start 130.97 66.93)
		(end 131.1 67.06)
		(width 0.162)
		(layer "In2.Cu")
		(net 234)
	)
	(segment
		(start 130.5 68.7471)
		(end 130.5 68.8)
		(width 0.162)
		(layer "In2.Cu")
		(net 234)
	)
	(segment
		(start 130.66 67.61)
		(end 130.66 67.05)
		(width 0.162)
		(layer "In2.Cu")
		(net 234)
	)
	(segment
		(start 127.06 67.74)
		(end 128.14 67.74)
		(width 0.162)
		(layer "In2.Cu")
		(net 234)
	)
	(segment
		(start 128.74 67.485195)
		(end 128.74 67.917403)
		(width 0.162)
		(layer "In2.Cu")
		(net 234)
	)
	(segment
		(start 130.669408 69.9)
		(end 130.04 69.270592)
		(width 0.162)
		(layer "In2.Cu")
		(net 234)
	)
	(segment
		(start 130.78 66.93)
		(end 130.97 66.93)
		(width 0.162)
		(layer "In2.Cu")
		(net 234)
	)
	(segment
		(start 130.7 68.3)
		(end 130.7 68.5471)
		(width 0.162)
		(layer "In2.Cu")
		(net 234)
	)
	(segment
		(start 130.5 68.8)
		(end 131.1 69.4)
		(width 0.162)
		(layer "In2.Cu")
		(net 234)
	)
	(segment
		(start 129.14 67.917403)
		(end 129.14 67.435195)
		(width 0.162)
		(layer "In2.Cu")
		(net 234)
	)
	(segment
		(start 130.7 68.5471)
		(end 130.5 68.7471)
		(width 0.162)
		(layer "In2.Cu")
		(net 234)
	)
	(segment
		(start 131.1 67.06)
		(end 131.1 67.9)
		(width 0.162)
		(layer "In2.Cu")
		(net 234)
	)
	(segment
		(start 130.53 67.74)
		(end 130.66 67.61)
		(width 0.162)
		(layer "In2.Cu")
		(net 234)
	)
	(segment
		(start 131.1 69.7)
		(end 130.9 69.9)
		(width 0.162)
		(layer "In2.Cu")
		(net 234)
	)
	(segment
		(start 128.34 67.54)
		(end 128.34 67.485195)
		(width 0.162)
		(layer "In2.Cu")
		(net 234)
	)
	(segment
		(start 131.1 69.4)
		(end 131.1 69.7)
		(width 0.162)
		(layer "In2.Cu")
		(net 234)
	)
	(segment
		(start 130.04 69.270592)
		(end 130.04 69.04)
		(width 0.162)
		(layer "In2.Cu")
		(net 234)
	)
	(segment
		(start 131.1 67.9)
		(end 130.7 68.3)
		(width 0.162)
		(layer "In2.Cu")
		(net 234)
	)
	(segment
		(start 129.54 67.435195)
		(end 129.54 67.54)
		(width 0.162)
		(layer "In2.Cu")
		(net 234)
	)
	(segment
		(start 130.66 67.05)
		(end 130.78 66.93)
		(width 0.162)
		(layer "In2.Cu")
		(net 234)
	)
	(arc
		(start 128.74 67.917403)
		(mid 128.79196 68.042845)
		(end 128.917402 68.094805)
		(width 0.162)
		(layer "In2.Cu")
		(net 234)
	)
	(arc
		(start 129.54 67.54)
		(mid 129.598579 67.681421)
		(end 129.74 67.74)
		(width 0.162)
		(layer "In2.Cu")
		(net 234)
	)
	(arc
		(start 128.962598 68.094805)
		(mid 129.08804 68.042845)
		(end 129.14 67.917403)
		(width 0.162)
		(layer "In2.Cu")
		(net 234)
	)
	(arc
		(start 128.14 67.74)
		(mid 128.281421 67.681421)
		(end 128.34 67.54)
		(width 0.162)
		(layer "In2.Cu")
		(net 234)
	)
	(arc
		(start 128.54 67.285195)
		(mid 128.681421 67.343774)
		(end 128.74 67.485195)
		(width 0.162)
		(layer "In2.Cu")
		(net 234)
	)
	(arc
		(start 128.34 67.485195)
		(mid 128.398579 67.343774)
		(end 128.54 67.285195)
		(width 0.162)
		(layer "In2.Cu")
		(net 234)
	)
	(arc
		(start 129.14 67.435195)
		(mid 129.198579 67.293774)
		(end 129.34 67.235195)
		(width 0.162)
		(layer "In2.Cu")
		(net 234)
	)
	(arc
		(start 129.34 67.235195)
		(mid 129.481421 67.293774)
		(end 129.54 67.435195)
		(width 0.162)
		(layer "In2.Cu")
		(net 234)
	)
	(segment
		(start 132.703959 65.645)
		(end 132.705 65.645)
		(width 0.2)
		(layer "F.Cu")
		(net 235)
	)
	(segment
		(start 125.86 65.74)
		(end 126.26 66.14)
		(width 0.182)
		(layer "F.Cu")
		(net 235)
	)
	(segment
		(start 132.705 65.645)
		(end 136.3 69.24)
		(width 0.2)
		(layer "F.Cu")
		(net 235)
	)
	(segment
		(start 129.68 64.74)
		(end 131.8 64.74)
		(width 0.2)
		(layer "F.Cu")
		(net 235)
	)
	(segment
		(start 136.3 69.24)
		(end 136.3 80.7)
		(width 0.2)
		(layer "F.Cu")
		(net 235)
	)
	(segment
		(start 135.675 81.323959)
		(end 135.675 81.325)
		(width 0.2)
		(layer "F.Cu")
		(net 235)
	)
	(segment
		(start 135.675 81.325)
		(end 133.83 83.17)
		(width 0.2)
		(layer "F.Cu")
		(net 235)
	)
	(segment
		(start 135.923959 81.075)
		(end 135.675 81.323959)
		(width 0.2)
		(layer "F.Cu")
		(net 235)
	)
	(segment
		(start 132.455 65.396041)
		(end 132.703959 65.645)
		(width 0.2)
		(layer "F.Cu")
		(net 235)
	)
	(segment
		(start 132.63 83.17)
		(end 131.5 84.3)
		(width 0.2)
		(layer "F.Cu")
		(net 235)
	)
	(segment
		(start 135.925 81.075)
		(end 135.923959 81.075)
		(width 0.2)
		(layer "F.Cu")
		(net 235)
	)
	(segment
		(start 132.455 65.395)
		(end 132.455 65.396041)
		(width 0.2)
		(layer "F.Cu")
		(net 235)
	)
	(segment
		(start 136.3 80.7)
		(end 135.925 81.075)
		(width 0.2)
		(layer "F.Cu")
		(net 235)
	)
	(segment
		(start 129.45 64.97)
		(end 129.68 64.74)
		(width 0.2)
		(layer "F.Cu")
		(net 235)
	)
	(segment
		(start 131.8 64.74)
		(end 132.455 65.395)
		(width 0.2)
		(layer "F.Cu")
		(net 235)
	)
	(segment
		(start 133.83 83.17)
		(end 132.63 83.17)
		(width 0.2)
		(layer "F.Cu")
		(net 235)
	)
	(via
		(at 126.26 66.14)
		(size 0.45)
		(drill 0.2)
		(layers "F.Cu" "B.Cu")
		(remove_unused_layers yes)
		(keep_end_layers yes)
		(zone_layer_connections)
		(net 235)
	)
	(via
		(at 129.45 64.97)
		(size 0.45)
		(drill 0.2)
		(layers "F.Cu" "B.Cu")
		(remove_unused_layers yes)
		(keep_end_layers yes)
		(zone_layer_connections)
		(net 235)
	)
	(segment
		(start 127.83 64.97)
		(end 129.45 64.97)
		(width 0.162)
		(layer "In2.Cu")
		(net 235)
	)
	(segment
		(start 125.87 65.81)
		(end 125.94 65.74)
		(width 0.15)
		(layer "In2.Cu")
		(net 235)
	)
	(segment
		(start 127.57 65.23)
		(end 127.83 64.97)
		(width 0.162)
		(layer "In2.Cu")
		(net 235)
	)
	(segment
		(start 127.36 65.74)
		(end 127.379 65.721)
		(width 0.15)
		(layer "In2.Cu")
		(net 235)
	)
	(segment
		(start 126.26 66.14)
		(end 126.03 66.14)
		(width 0.162)
		(layer "In2.Cu")
		(net 235)
	)
	(segment
		(start 127.57 65.53)
		(end 127.57 65.23)
		(width 0.162)
		(layer "In2.Cu")
		(net 235)
	)
	(segment
		(start 126.03 66.14)
		(end 125.87 65.98)
		(width 0.162)
		(layer "In2.Cu")
		(net 235)
	)
	(segment
		(start 125.94 65.74)
		(end 127.36 65.74)
		(width 0.15)
		(layer "In2.Cu")
		(net 235)
	)
	(segment
		(start 127.379 65.721)
		(end 127.57 65.53)
		(width 0.162)
		(layer "In2.Cu")
		(net 235)
	)
	(segment
		(start 125.87 65.98)
		(end 125.87 65.81)
		(width 0.162)
		(layer "In2.Cu")
		(net 235)
	)
	(segment
		(start 132.247178 66.8)
		(end 132.247179 66.8)
		(width 0.2)
		(layer "F.Cu")
		(net 236)
	)
	(segment
		(start 133.297044 68.524223)
		(end 133.634223 68.187043)
		(width 0.2)
		(layer "F.Cu")
		(net 236)
	)
	(segment
		(start 133.756663 68.983843)
		(end 134.093841 68.646662)
		(width 0.2)
		(layer "F.Cu")
		(net 236)
	)
	(segment
		(start 134.431021 68.646663)
		(end 134.553462 68.769104)
		(width 0.2)
		(layer "F.Cu")
		(net 236)
	)
	(segment
		(start 134.216283 69.443462)
		(end 134.553462 69.106282)
		(width 0.2)
		(layer "F.Cu")
		(net 236)
	)
	(segment
		(start 135.01308 69.903081)
		(end 135.4 70.29)
		(width 0.2)
		(layer "F.Cu")
		(net 236)
	)
	(segment
		(start 135.4 70.29)
		(end 135.4 80.8)
		(width 0.2)
		(layer "F.Cu")
		(net 236)
	)
	(segment
		(start 132.706798 67.259619)
		(end 132.706796 67.259618)
		(width 0.2)
		(layer "F.Cu")
		(net 236)
	)
	(segment
		(start 132.538207 67.428207)
		(end 132.546395 67.436395)
		(width 0.2)
		(layer "F.Cu")
		(net 236)
	)
	(segment
		(start 132.837424 68.064604)
		(end 133.174602 67.727423)
		(width 0.2)
		(layer "F.Cu")
		(net 236)
	)
	(segment
		(start 132.377805 67.942162)
		(end 132.377805 67.942163)
		(width 0.2)
		(layer "F.Cu")
		(net 236)
	)
	(segment
		(start 132.584357 66.8)
		(end 132.706798 66.922441)
		(width 0.2)
		(layer "F.Cu")
		(net 236)
	)
	(segment
		(start 133.297044 68.861402)
		(end 133.419485 68.983843)
		(width 0.2)
		(layer "F.Cu")
		(net 236)
	)
	(segment
		(start 130.76 65.65)
		(end 131.91 66.8)
		(width 0.2)
		(layer "F.Cu")
		(net 236)
	)
	(segment
		(start 134.216283 69.780641)
		(end 134.338724 69.903082)
		(width 0.2)
		(layer "F.Cu")
		(net 236)
	)
	(segment
		(start 135.4 80.8)
		(end 133.33 82.87)
		(width 0.2)
		(layer "F.Cu")
		(net 236)
	)
	(segment
		(start 132.13 82.87)
		(end 130.7 84.3)
		(width 0.2)
		(layer "F.Cu")
		(net 236)
	)
	(segment
		(start 129.43 65.67)
		(end 129.45 65.65)
		(width 0.2)
		(layer "F.Cu")
		(net 236)
	)
	(segment
		(start 133.511782 67.727425)
		(end 133.511782 67.727424)
		(width 0.2)
		(layer "F.Cu")
		(net 236)
	)
	(segment
		(start 132.377805 67.942163)
		(end 132.500246 68.064604)
		(width 0.2)
		(layer "F.Cu")
		(net 236)
	)
	(segment
		(start 134.216283 69.78064)
		(end 134.216283 69.780641)
		(width 0.2)
		(layer "F.Cu")
		(net 236)
	)
	(segment
		(start 129.45 65.65)
		(end 130.76 65.65)
		(width 0.2)
		(layer "F.Cu")
		(net 236)
	)
	(segment
		(start 134.675902 69.903082)
		(end 134.675902 69.903081)
		(width 0.2)
		(layer "F.Cu")
		(net 236)
	)
	(segment
		(start 132.247179 66.799999)
		(end 132.247178 66.8)
		(width 0.2)
		(layer "F.Cu")
		(net 236)
	)
	(segment
		(start 132.706796 67.259618)
		(end 132.538207 67.428207)
		(width 0.2)
		(layer "F.Cu")
		(net 236)
	)
	(segment
		(start 126.66 66.54)
		(end 127.06 66.14)
		(width 0.182)
		(layer "F.Cu")
		(net 236)
	)
	(segment
		(start 133.297044 68.861401)
		(end 133.297044 68.861402)
		(width 0.2)
		(layer "F.Cu")
		(net 236)
	)
	(segment
		(start 134.431021 68.646664)
		(end 134.431021 68.646663)
		(width 0.2)
		(layer "F.Cu")
		(net 236)
	)
	(segment
		(start 133.33 82.87)
		(end 132.13 82.87)
		(width 0.2)
		(layer "F.Cu")
		(net 236)
	)
	(segment
		(start 132.546395 67.436395)
		(end 132.377805 67.604984)
		(width 0.2)
		(layer "F.Cu")
		(net 236)
	)
	(segment
		(start 133.511782 67.727424)
		(end 133.634223 67.849865)
		(width 0.2)
		(layer "F.Cu")
		(net 236)
	)
	(via
		(at 127.06 66.14)
		(size 0.45)
		(drill 0.2)
		(layers "F.Cu" "B.Cu")
		(remove_unused_layers yes)
		(keep_end_layers yes)
		(zone_layer_connections)
		(net 236)
	)
	(via
		(at 129.43 65.67)
		(size 0.45)
		(drill 0.2)
		(layers "F.Cu" "B.Cu")
		(remove_unused_layers yes)
		(keep_end_layers yes)
		(zone_layer_connections)
		(net 236)
	)
	(arc
		(start 132.377805 67.604984)
		(mid 132.307973 67.773573)
		(end 132.377805 67.942162)
		(width 0.2)
		(layer "F.Cu")
		(net 236)
	)
	(arc
		(start 131.91 66.8)
		(mid 132.07859 66.869832)
		(end 132.247179 66.799999)
		(width 0.2)
		(layer "F.Cu")
		(net 236)
	)
	(arc
		(start 133.419485 68.983843)
		(mid 133.588074 69.053675)
		(end 133.756663 68.983843)
		(width 0.2)
		(layer "F.Cu")
		(net 236)
	)
	(arc
		(start 132.247179 66.8)
		(mid 132.415767 66.730167)
		(end 132.584357 66.8)
		(width 0.2)
		(layer "F.Cu")
		(net 236)
	)
	(arc
		(start 134.553462 68.769104)
		(mid 134.623295 68.937694)
		(end 134.553462 69.106282)
		(width 0.2)
		(layer "F.Cu")
		(net 236)
	)
	(arc
		(start 133.297044 68.524223)
		(mid 133.227212 68.692812)
		(end 133.297044 68.861401)
		(width 0.2)
		(layer "F.Cu")
		(net 236)
	)
	(arc
		(start 134.675902 69.903081)
		(mid 134.844491 69.833249)
		(end 135.01308 69.903081)
		(width 0.2)
		(layer "F.Cu")
		(net 236)
	)
	(arc
		(start 132.706798 66.922441)
		(mid 132.776629 67.091029)
		(end 132.706798 67.259619)
		(width 0.2)
		(layer "F.Cu")
		(net 236)
	)
	(arc
		(start 132.500246 68.064604)
		(mid 132.668835 68.134436)
		(end 132.837424 68.064604)
		(width 0.2)
		(layer "F.Cu")
		(net 236)
	)
	(arc
		(start 134.338724 69.903082)
		(mid 134.507313 69.972914)
		(end 134.675902 69.903082)
		(width 0.2)
		(layer "F.Cu")
		(net 236)
	)
	(arc
		(start 134.093841 68.646662)
		(mid 134.262431 68.576831)
		(end 134.431021 68.646664)
		(width 0.2)
		(layer "F.Cu")
		(net 236)
	)
	(arc
		(start 134.216283 69.443462)
		(mid 134.146451 69.612051)
		(end 134.216283 69.78064)
		(width 0.2)
		(layer "F.Cu")
		(net 236)
	)
	(arc
		(start 133.174602 67.727423)
		(mid 133.343192 67.657592)
		(end 133.511782 67.727425)
		(width 0.2)
		(layer "F.Cu")
		(net 236)
	)
	(arc
		(start 133.634223 67.849865)
		(mid 133.704056 68.018455)
		(end 133.634223 68.187043)
		(width 0.2)
		(layer "F.Cu")
		(net 236)
	)
	(segment
		(start 128.2 65.5)
		(end 127.56 66.14)
		(width 0.162)
		(layer "In2.Cu")
		(net 236)
	)
	(segment
		(start 129.03 65.67)
		(end 128.86 65.5)
		(width 0.162)
		(layer "In2.Cu")
		(net 236)
	)
	(segment
		(start 127.56 66.14)
		(end 127.06 66.14)
		(width 0.162)
		(layer "In2.Cu")
		(net 236)
	)
	(segment
		(start 128.86 65.5)
		(end 128.2 65.5)
		(width 0.162)
		(layer "In2.Cu")
		(net 236)
	)
	(segment
		(start 129.43 65.67)
		(end 129.03 65.67)
		(width 0.162)
		(layer "In2.Cu")
		(net 236)
	)
	(segment
		(start 118.827681 73.305)
		(end 118.827682 73.305)
		(width 0.2)
		(layer "F.Cu")
		(net 237)
	)
	(segment
		(start 118.827681 73.955)
		(end 119.352319 73.955)
		(width 0.2)
		(layer "F.Cu")
		(net 237)
	)
	(segment
		(start 118.827681 74.605)
		(end 119.352319 74.605)
		(width 0.2)
		(layer "F.Cu")
		(net 237)
	)
	(segment
		(start 118.565363 73.692682)
		(end 118.565363 73.567318)
		(width 0.2)
		(layer "F.Cu")
		(net 237)
	)
	(segment
		(start 119.614637 74.342682)
		(end 119.614637 74.217318)
		(width 0.2)
		(layer "F.Cu")
		(net 237)
	)
	(segment
		(start 119.09 75.255)
		(end 118.827681 75.255)
		(width 0.2)
		(layer "F.Cu")
		(net 237)
	)
	(segment
		(start 119.09 73.042682)
		(end 119.09 71.078959)
		(width 0.2)
		(layer "F.Cu")
		(net 237)
	)
	(segment
		(start 119.09 75.267682)
		(end 119.09 75.255)
		(width 0.2)
		(layer "F.Cu")
		(net 237)
	)
	(segment
		(start 121.1 84.3)
		(end 121.1 83.83)
		(width 0.2)
		(layer "F.Cu")
		(net 237)
	)
	(segment
		(start 118.565363 74.992682)
		(end 118.565363 74.867318)
		(width 0.2)
		(layer "F.Cu")
		(net 237)
	)
	(segment
		(start 119.614637 75.655364)
		(end 119.614637 75.53)
		(width 0.2)
		(layer "F.Cu")
		(net 237)
	)
	(segment
		(start 119.09 71.078959)
		(end 120.022459 70.1465)
		(width 0.2)
		(layer "F.Cu")
		(net 237)
	)
	(segment
		(start 121.4535 70.1465)
		(end 120.0435 70.1465)
		(width 0.15)
		(layer "F.Cu")
		(net 237)
	)
	(segment
		(start 119.09 81.82)
		(end 119.09 76.18)
		(width 0.2)
		(layer "F.Cu")
		(net 237)
	)
	(segment
		(start 119.352319 75.267682)
		(end 119.352318 75.267682)
		(width 0.2)
		(layer "F.Cu")
		(net 237)
	)
	(segment
		(start 121.1 83.83)
		(end 119.09 81.82)
		(width 0.2)
		(layer "F.Cu")
		(net 237)
	)
	(segment
		(start 120.022459 70.1465)
		(end 120.0435 70.1465)
		(width 0.2)
		(layer "F.Cu")
		(net 237)
	)
	(segment
		(start 119.352318 75.267682)
		(end 119.09 75.267682)
		(width 0.2)
		(layer "F.Cu")
		(net 237)
	)
	(segment
		(start 119.352318 75.917682)
		(end 119.352319 75.917682)
		(width 0.2)
		(layer "F.Cu")
		(net 237)
	)
	(segment
		(start 121.4535 70.1465)
		(end 121.86 69.74)
		(width 0.2)
		(layer "F.Cu")
		(net 237)
	)
	(arc
		(start 119.09 76.18)
		(mid 119.166831 75.994513)
		(end 119.352318 75.917682)
		(width 0.2)
		(layer "F.Cu")
		(net 237)
	)
	(arc
		(start 119.614637 74.217318)
		(mid 119.537806 74.031831)
		(end 119.352319 73.955)
		(width 0.2)
		(layer "F.Cu")
		(net 237)
	)
	(arc
		(start 119.614637 75.53)
		(mid 119.537806 75.344513)
		(end 119.352319 75.267682)
		(width 0.2)
		(layer "F.Cu")
		(net 237)
	)
	(arc
		(start 119.352319 74.605)
		(mid 119.537806 74.528169)
		(end 119.614637 74.342682)
		(width 0.2)
		(layer "F.Cu")
		(net 237)
	)
	(arc
		(start 118.827681 73.955)
		(mid 118.642194 73.878169)
		(end 118.565363 73.692682)
		(width 0.2)
		(layer "F.Cu")
		(net 237)
	)
	(arc
		(start 118.827682 73.305)
		(mid 119.013169 73.228169)
		(end 119.09 73.042682)
		(width 0.2)
		(layer "F.Cu")
		(net 237)
	)
	(arc
		(start 118.565363 74.867318)
		(mid 118.642194 74.681831)
		(end 118.827681 74.605)
		(width 0.2)
		(layer "F.Cu")
		(net 237)
	)
	(arc
		(start 118.565363 73.567318)
		(mid 118.642194 73.381831)
		(end 118.827681 73.305)
		(width 0.2)
		(layer "F.Cu")
		(net 237)
	)
	(arc
		(start 119.352319 75.917682)
		(mid 119.537806 75.840851)
		(end 119.614637 75.655364)
		(width 0.2)
		(layer "F.Cu")
		(net 237)
	)
	(arc
		(start 118.827681 75.255)
		(mid 118.642194 75.178169)
		(end 118.565363 74.992682)
		(width 0.2)
		(layer "F.Cu")
		(net 237)
	)
	(segment
		(start 124.456221 76.3555)
		(end 124.5805 76.3555)
		(width 0.2)
		(layer "F.Cu")
		(net 238)
	)
	(segment
		(start 123.5 81.64)
		(end 123.5 84.3)
		(width 0.2)
		(layer "F.Cu")
		(net 238)
	)
	(segment
		(start 125.129058 73.029058)
		(end 125.129058 73.0805)
		(width 0.2)
		(layer "F.Cu")
		(net 238)
	)
	(segment
		(start 124.01 81.13)
		(end 123.5 81.64)
		(width 0.2)
		(layer "F.Cu")
		(net 238)
	)
	(segment
		(start 124.5805 77.229779)
		(end 124.5805 78.9295)
		(width 0.2)
		(layer "F.Cu")
		(net 238)
	)
	(segment
		(start 124.356221 75.1555)
		(end 124.854779 75.1555)
		(width 0.2)
		(layer "F.Cu")
		(net 238)
	)
	(segment
		(start 124.5805 75.7555)
		(end 124.456221 75.7555)
		(width 0.2)
		(layer "F.Cu")
		(net 238)
	)
	(segment
		(start 124.5805 73.3555)
		(end 124.306221 73.3555)
		(width 0.2)
		(layer "F.Cu")
		(net 238)
	)
	(segment
		(start 124.5805 78.9295)
		(end 124.58 78.93)
		(width 0.2)
		(layer "F.Cu")
		(net 238)
	)
	(segment
		(start 124.76 71.474959)
		(end 124.5805 71.654459)
		(width 0.2)
		(layer "F.Cu")
		(net 238)
	)
	(segment
		(start 125.129058 74.229779)
		(end 125.129058 74.281221)
		(width 0.2)
		(layer "F.Cu")
		(net 238)
	)
	(segment
		(start 124.356221 74.5555)
		(end 124.854779 74.5555)
		(width 0.2)
		(layer "F.Cu")
		(net 238)
	)
	(segment
		(start 124.76 70.03)
		(end 124.76 71.474959)
		(width 0.2)
		(layer "F.Cu")
		(net 238)
	)
	(segment
		(start 124.58 78.93)
		(end 124.58 79.51)
		(width 0.2)
		(layer "F.Cu")
		(net 238)
	)
	(segment
		(start 124.306221 73.9555)
		(end 124.854779 73.9555)
		(width 0.2)
		(layer "F.Cu")
		(net 238)
	)
	(segment
		(start 124.854779 75.7555)
		(end 124.5805 75.7555)
		(width 0.2)
		(layer "F.Cu")
		(net 238)
	)
	(segment
		(start 124.031942 73.629779)
		(end 124.031942 73.681221)
		(width 0.2)
		(layer "F.Cu")
		(net 238)
	)
	(segment
		(start 125.129058 76.629779)
		(end 125.129058 76.681221)
		(width 0.2)
		(layer "F.Cu")
		(net 238)
	)
	(segment
		(start 124.5805 76.3555)
		(end 124.854779 76.3555)
		(width 0.2)
		(layer "F.Cu")
		(net 238)
	)
	(segment
		(start 124.58 79.51)
		(end 124.01 80.08)
		(width 0.2)
		(layer "F.Cu")
		(net 238)
	)
	(segment
		(start 125.86 69.74)
		(end 125.05 69.74)
		(width 0.2)
		(layer "F.Cu")
		(net 238)
	)
	(segment
		(start 124.854779 73.354779)
		(end 124.5805 73.354779)
		(width 0.2)
		(layer "F.Cu")
		(net 238)
	)
	(segment
		(start 125.05 69.74)
		(end 124.76 70.03)
		(width 0.2)
		(layer "F.Cu")
		(net 238)
	)
	(segment
		(start 124.331942 75.879779)
		(end 124.331942 76.231221)
		(width 0.2)
		(layer "F.Cu")
		(net 238)
	)
	(segment
		(start 125.129058 75.429779)
		(end 125.129058 75.481221)
		(width 0.2)
		(layer "F.Cu")
		(net 238)
	)
	(segment
		(start 124.5805 73.354779)
		(end 124.5805 73.3555)
		(width 0.2)
		(layer "F.Cu")
		(net 238)
	)
	(segment
		(start 124.5805 71.654459)
		(end 124.5805 72.4805)
		(width 0.2)
		(layer "F.Cu")
		(net 238)
	)
	(segment
		(start 124.131942 74.779779)
		(end 124.131942 74.931221)
		(width 0.2)
		(layer "F.Cu")
		(net 238)
	)
	(segment
		(start 124.01 80.08)
		(end 124.01 81.13)
		(width 0.2)
		(layer "F.Cu")
		(net 238)
	)
	(arc
		(start 124.456221 75.7555)
		(mid 124.368342 75.7919)
		(end 124.331942 75.879779)
		(width 0.2)
		(layer "F.Cu")
		(net 238)
	)
	(arc
		(start 124.356221 74.5555)
		(mid 124.197632 74.62119)
		(end 124.131942 74.779779)
		(width 0.2)
		(layer "F.Cu")
		(net 238)
	)
	(arc
		(start 124.854779 73.9555)
		(mid 125.048724 74.035834)
		(end 125.129058 74.229779)
		(width 0.2)
		(layer "F.Cu")
		(net 238)
	)
	(arc
		(start 124.854779 76.3555)
		(mid 125.048724 76.435834)
		(end 125.129058 76.629779)
		(width 0.2)
		(layer "F.Cu")
		(net 238)
	)
	(arc
		(start 124.854779 72.754779)
		(mid 125.048724 72.835113)
		(end 125.129058 73.029058)
		(width 0.2)
		(layer "F.Cu")
		(net 238)
	)
	(arc
		(start 124.131942 74.931221)
		(mid 124.197632 75.08981)
		(end 124.356221 75.1555)
		(width 0.2)
		(layer "F.Cu")
		(net 238)
	)
	(arc
		(start 125.129058 75.481221)
		(mid 125.048724 75.675166)
		(end 124.854779 75.7555)
		(width 0.2)
		(layer "F.Cu")
		(net 238)
	)
	(arc
		(start 124.306221 73.3555)
		(mid 124.112276 73.435834)
		(end 124.031942 73.629779)
		(width 0.2)
		(layer "F.Cu")
		(net 238)
	)
	(arc
		(start 125.129058 76.681221)
		(mid 125.048724 76.875166)
		(end 124.854779 76.9555)
		(width 0.2)
		(layer "F.Cu")
		(net 238)
	)
	(arc
		(start 125.129058 74.281221)
		(mid 125.048724 74.475166)
		(end 124.854779 74.5555)
		(width 0.2)
		(layer "F.Cu")
		(net 238)
	)
	(arc
		(start 124.854779 76.9555)
		(mid 124.660834 77.035834)
		(end 124.5805 77.229779)
		(width 0.2)
		(layer "F.Cu")
		(net 238)
	)
	(arc
		(start 124.5805 72.4805)
		(mid 124.660834 72.674445)
		(end 124.854779 72.754779)
		(width 0.2)
		(layer "F.Cu")
		(net 238)
	)
	(arc
		(start 125.129058 73.0805)
		(mid 125.048724 73.274445)
		(end 124.854779 73.354779)
		(width 0.2)
		(layer "F.Cu")
		(net 238)
	)
	(arc
		(start 124.854779 75.1555)
		(mid 125.048724 75.235834)
		(end 125.129058 75.429779)
		(width 0.2)
		(layer "F.Cu")
		(net 238)
	)
	(arc
		(start 124.331942 76.231221)
		(mid 124.368342 76.3191)
		(end 124.456221 76.3555)
		(width 0.2)
		(layer "F.Cu")
		(net 238)
	)
	(arc
		(start 124.031942 73.681221)
		(mid 124.112276 73.875166)
		(end 124.306221 73.9555)
		(width 0.2)
		(layer "F.Cu")
		(net 238)
	)
	(segment
		(start 123.412 73.241448)
		(end 123.412 70.639288)
		(width 0.2)
		(layer "F.Cu")
		(net 239)
	)
	(segment
		(start 123.412 74.887984)
		(end 123.412 74.398)
		(width 0.2)
		(layer "F.Cu")
		(net 239)
	)
	(segment
		(start 122.724992 75.256794)
		(end 122.415954 74.947756)
		(width 0.2)
		(layer "F.Cu")
		(net 239)
	)
	(segment
		(start 123.36139 74.938595)
		(end 123.412 74.887984)
		(width 0.2)
		(layer "F.Cu")
		(net 239)
	)
	(segment
		(start 123.375 79.225)
		(end 123.575 79.225)
		(width 0.2)
		(layer "F.Cu")
		(net 239)
	)
	(segment
		(start 123.361391 74.938596)
		(end 123.36139 74.938595)
		(width 0.2)
		(layer "F.Cu")
		(net 239)
	)
	(segment
		(start 123.101712 70.329)
		(end 122.871 70.329)
		(width 0.2)
		(layer "F.Cu")
		(net 239)
	)
	(segment
		(start 122.734154 74.629558)
		(end 122.734154 74.629557)
		(width 0.2)
		(layer "F.Cu")
		(net 239)
	)
	(segment
		(start 123.85 76.95)
		(end 123.85 76.9)
		(width 0.2)
		(layer "F.Cu")
		(net 239)
	)
	(segment
		(start 122.7 75.599984)
		(end 122.724992 75.574992)
		(width 0.2)
		(layer "F.Cu")
		(net 239)
	)
	(segment
		(start 123.375 77.225)
		(end 123.575 77.225)
		(width 0.2)
		(layer "F.Cu")
		(net 239)
	)
	(segment
		(start 123.379724 74.365724)
		(end 123.181724 74.365724)
		(width 0.2)
		(layer "F.Cu")
		(net 239)
	)
	(segment
		(start 123.85 78.95)
		(end 123.85 78.9)
		(width 0.2)
		(layer "F.Cu")
		(net 239)
	)
	(segment
		(start 122.753448 73.937448)
		(end 122.753448 73.702)
		(width 0.2)
		(layer "F.Cu")
		(net 239)
	)
	(segment
		(start 122.871 70.329)
		(end 122.66 70.54)
		(width 0.2)
		(layer "F.Cu")
		(net 239)
	)
	(segment
		(start 123.575 78.625)
		(end 123.375 78.625)
		(width 0.2)
		(layer "F.Cu")
		(net 239)
	)
	(segment
		(start 122.7 75.9)
		(end 122.7 75.599984)
		(width 0.2)
		(layer "F.Cu")
		(net 239)
	)
	(segment
		(start 122.734154 74.629557)
		(end 123.043193 74.938596)
		(width 0.2)
		(layer "F.Cu")
		(net 239)
	)
	(segment
		(start 123.181724 73.273724)
		(end 123.379724 73.273724)
		(width 0.2)
		(layer "F.Cu")
		(net 239)
	)
	(segment
		(start 123.575 76.625)
		(end 123.375 76.625)
		(width 0.2)
		(layer "F.Cu")
		(net 239)
	)
	(segment
		(start 122.7 75.95)
		(end 122.7 75.9)
		(width 0.2)
		(layer "F.Cu")
		(net 239)
	)
	(segment
		(start 122.7 77.95)
		(end 122.7 77.9)
		(width 0.2)
		(layer "F.Cu")
		(net 239)
	)
	(segment
		(start 123.412 70.639288)
		(end 123.101712 70.329)
		(width 0.2)
		(layer "F.Cu")
		(net 239)
	)
	(segment
		(start 122.7 84.3)
		(end 122.7 79.9)
		(width 0.2)
		(layer "F.Cu")
		(net 239)
	)
	(arc
		(start 123.575 79.225)
		(mid 123.769454 79.144454)
		(end 123.85 78.95)
		(width 0.2)
		(layer "F.Cu")
		(net 239)
	)
	(arc
		(start 123.85 78.9)
		(mid 123.769454 78.705546)
		(end 123.575 78.625)
		(width 0.2)
		(layer "F.Cu")
		(net 239)
	)
	(arc
		(start 122.753448 73.702)
		(mid 122.878887 73.399163)
		(end 123.181724 73.273724)
		(width 0.2)
		(layer "F.Cu")
		(net 239)
	)
	(arc
		(start 122.415954 74.629558)
		(mid 122.575055 74.563656)
		(end 122.734154 74.629558)
		(width 0.2)
		(layer "F.Cu")
		(net 239)
	)
	(arc
		(start 123.85 76.9)
		(mid 123.769454 76.705546)
		(end 123.575 76.625)
		(width 0.2)
		(layer "F.Cu")
		(net 239)
	)
	(arc
		(start 123.412 74.398)
		(mid 123.402547 74.375177)
		(end 123.379724 74.365724)
		(width 0.2)
		(layer "F.Cu")
		(net 239)
	)
	(arc
		(start 123.043193 74.938596)
		(mid 123.202292 75.004497)
		(end 123.361391 74.938596)
		(width 0.2)
		(layer "F.Cu")
		(net 239)
	)
	(arc
		(start 123.375 76.625)
		(mid 122.897703 76.427297)
		(end 122.7 75.95)
		(width 0.2)
		(layer "F.Cu")
		(net 239)
	)
	(arc
		(start 123.181724 74.365724)
		(mid 122.878887 74.240285)
		(end 122.753448 73.937448)
		(width 0.2)
		(layer "F.Cu")
		(net 239)
	)
	(arc
		(start 123.375 78.625)
		(mid 122.897703 78.427297)
		(end 122.7 77.95)
		(width 0.2)
		(layer "F.Cu")
		(net 239)
	)
	(arc
		(start 122.7 79.9)
		(mid 122.897703 79.422703)
		(end 123.375 79.225)
		(width 0.2)
		(layer "F.Cu")
		(net 239)
	)
	(arc
		(start 122.724992 75.574992)
		(mid 122.790893 75.415893)
		(end 122.724992 75.256794)
		(width 0.2)
		(layer "F.Cu")
		(net 239)
	)
	(arc
		(start 122.415954 74.947756)
		(mid 122.350053 74.788657)
		(end 122.415954 74.629558)
		(width 0.2)
		(layer "F.Cu")
		(net 239)
	)
	(arc
		(start 123.575 77.225)
		(mid 123.769454 77.144454)
		(end 123.85 76.95)
		(width 0.2)
		(layer "F.Cu")
		(net 239)
	)
	(arc
		(start 123.379724 73.273724)
		(mid 123.402547 73.264271)
		(end 123.412 73.241448)
		(width 0.2)
		(layer "F.Cu")
		(net 239)
	)
	(arc
		(start 122.7 77.9)
		(mid 122.897703 77.422703)
		(end 123.375 77.225)
		(width 0.2)
		(layer "F.Cu")
		(net 239)
	)
	(segment
		(start 126.52 80.98)
		(end 127.1 80.4)
		(width 0.2)
		(layer "F.Cu")
		(net 240)
	)
	(segment
		(start 127.17 76.575)
		(end 127.341035 76.575)
		(width 0.2)
		(layer "F.Cu")
		(net 240)
	)
	(segment
		(start 126.898965 78.978965)
		(end 127.17 78.978965)
		(width 0.2)
		(layer "F.Cu")
		(net 240)
	)
	(segment
		(start 127.51207 75.203965)
		(end 127.51207 74.946035)
		(width 0.2)
		(layer "F.Cu")
		(net 240)
	)
	(segment
		(start 127.51207 78.803965)
		(end 127.51207 78.546035)
		(width 0.2)
		(layer "F.Cu")
		(net 240)
	)
	(segment
		(start 124.7 84.09)
		(end 124.7 83.17)
		(width 0.2)
		(layer "F.Cu")
		(net 240)
	)
	(segment
		(start 126.62793 75.703965)
		(end 126.62793 75.646035)
		(width 0.2)
		(layer "F.Cu")
		(net 240)
	)
	(segment
		(start 126.898965 75.375)
		(end 127.17 75.375)
		(width 0.2)
		(layer "F.Cu")
		(net 240)
	)
	(segment
		(start 124.7 84.7)
		(end 125.1 85.1)
		(width 0.15)
		(layer "F.Cu")
		(net 240)
	)
	(segment
		(start 127.17 73.328965)
		(end 127.17 71.85)
		(width 0.2)
		(layer "F.Cu")
		(net 240)
	)
	(segment
		(start 126.62793 74.503965)
		(end 126.62793 74.446035)
		(width 0.2)
		(layer "F.Cu")
		(net 240)
	)
	(segment
		(start 124.7 84.09)
		(end 124.7 84.7)
		(width 0.15)
		(layer "F.Cu")
		(net 240)
	)
	(segment
		(start 127.17 74.775)
		(end 126.898965 74.775)
		(width 0.2)
		(layer "F.Cu")
		(net 240)
	)
	(segment
		(start 126.898965 76.575)
		(end 127.17 76.575)
		(width 0.2)
		(layer "F.Cu")
		(net 240)
	)
	(segment
		(start 126.898965 74.175)
		(end 127.416035 74.175)
		(width 0.2)
		(layer "F.Cu")
		(net 240)
	)
	(segment
		(start 126.898965 77.775)
		(end 127.17 77.775)
		(width 0.2)
		(layer "F.Cu")
		(net 240)
	)
	(segment
		(start 126.62793 79.30793)
		(end 126.62793 79.25)
		(width 0.2)
		(layer "F.Cu")
		(net 240)
	)
	(segment
		(start 127.341035 75.975)
		(end 127.17 75.975)
		(width 0.2)
		(layer "F.Cu")
		(net 240)
	)
	(segment
		(start 127.66207 73.928965)
		(end 127.66207 73.821035)
		(width 0.2)
		(layer "F.Cu")
		(net 240)
	)
	(segment
		(start 127.17 71.85)
		(end 126.66 71.34)
		(width 0.2)
		(layer "F.Cu")
		(net 240)
	)
	(segment
		(start 127.51207 76.403965)
		(end 127.51207 76.146035)
		(width 0.2)
		(layer "F.Cu")
		(net 240)
	)
	(segment
		(start 126.52 81.35)
		(end 126.52 80.98)
		(width 0.2)
		(layer "F.Cu")
		(net 240)
	)
	(segment
		(start 127.341035 78.375)
		(end 127.17 78.375)
		(width 0.2)
		(layer "F.Cu")
		(net 240)
	)
	(segment
		(start 127.17 78.975)
		(end 127.341035 78.975)
		(width 0.2)
		(layer "F.Cu")
		(net 240)
	)
	(segment
		(start 127.51207 77.603965)
		(end 127.51207 77.346035)
		(width 0.2)
		(layer "F.Cu")
		(net 240)
	)
	(segment
		(start 127.17 77.775)
		(end 127.341035 77.775)
		(width 0.2)
		(layer "F.Cu")
		(net 240)
	)
	(segment
		(start 127.17 80.231006)
		(end 127.17 79.85)
		(width 0.2)
		(layer "F.Cu")
		(net 240)
	)
	(segment
		(start 127.17 75.975)
		(end 126.898965 75.975)
		(width 0.2)
		(layer "F.Cu")
		(net 240)
	)
	(segment
		(start 127.17 75.375)
		(end 127.341035 75.375)
		(width 0.2)
		(layer "F.Cu")
		(net 240)
	)
	(segment
		(start 127.17 78.978965)
		(end 127.17 78.975)
		(width 0.2)
		(layer "F.Cu")
		(net 240)
	)
	(segment
		(start 126.62793 76.903965)
		(end 126.62793 76.846035)
		(width 0.2)
		(layer "F.Cu")
		(net 240)
	)
	(segment
		(start 126.62793 78.103965)
		(end 126.62793 78.046035)
		(width 0.2)
		(layer "F.Cu")
		(net 240)
	)
	(segment
		(start 127.17 78.375)
		(end 126.898965 78.375)
		(width 0.2)
		(layer "F.Cu")
		(net 240)
	)
	(segment
		(start 127.17 77.175)
		(end 126.898965 77.175)
		(width 0.2)
		(layer "F.Cu")
		(net 240)
	)
	(segment
		(start 124.7 83.17)
		(end 126.52 81.35)
		(width 0.2)
		(layer "F.Cu")
		(net 240)
	)
	(segment
		(start 127.341035 77.175)
		(end 127.17 77.175)
		(width 0.2)
		(layer "F.Cu")
		(net 240)
	)
	(segment
		(start 127.341035 74.775)
		(end 127.17 74.775)
		(width 0.2)
		(layer "F.Cu")
		(net 240)
	)
	(arc
		(start 127.341035 78.975)
		(mid 127.461975 78.924905)
		(end 127.51207 78.803965)
		(width 0.2)
		(layer "F.Cu")
		(net 240)
	)
	(arc
		(start 126.62793 79.25)
		(mid 126.707314 79.058349)
		(end 126.898965 78.978965)
		(width 0.2)
		(layer "F.Cu")
		(net 240)
	)
	(arc
		(start 127.1 80.4)
		(mid 127.151807 80.322465)
		(end 127.17 80.231006)
		(width 0.2)
		(layer "F.Cu")
		(net 240)
	)
	(arc
		(start 126.62793 75.646035)
		(mid 126.707314 75.454384)
		(end 126.898965 75.375)
		(width 0.2)
		(layer "F.Cu")
		(net 240)
	)
	(arc
		(start 126.898965 77.175)
		(mid 126.707314 77.095616)
		(end 126.62793 76.903965)
		(width 0.2)
		(layer "F.Cu")
		(net 240)
	)
	(arc
		(start 127.66207 73.821035)
		(mid 127.590008 73.647062)
		(end 127.416035 73.575)
		(width 0.2)
		(layer "F.Cu")
		(net 240)
	)
	(arc
		(start 127.341035 77.775)
		(mid 127.461975 77.724905)
		(end 127.51207 77.603965)
		(width 0.2)
		(layer "F.Cu")
		(net 240)
	)
	(arc
		(start 127.51207 78.546035)
		(mid 127.461975 78.425095)
		(end 127.341035 78.375)
		(width 0.2)
		(layer "F.Cu")
		(net 240)
	)
	(arc
		(start 126.898965 78.375)
		(mid 126.707314 78.295616)
		(end 126.62793 78.103965)
		(width 0.2)
		(layer "F.Cu")
		(net 240)
	)
	(arc
		(start 126.898965 74.775)
		(mid 126.707314 74.695616)
		(end 126.62793 74.503965)
		(width 0.2)
		(layer "F.Cu")
		(net 240)
	)
	(arc
		(start 126.898965 79.578965)
		(mid 126.707314 79.499581)
		(end 126.62793 79.30793)
		(width 0.2)
		(layer "F.Cu")
		(net 240)
	)
	(arc
		(start 127.17 79.85)
		(mid 127.090616 79.658349)
		(end 126.898965 79.578965)
		(width 0.2)
		(layer "F.Cu")
		(net 240)
	)
	(arc
		(start 127.51207 74.946035)
		(mid 127.461975 74.825095)
		(end 127.341035 74.775)
		(width 0.2)
		(layer "F.Cu")
		(net 240)
	)
	(arc
		(start 126.62793 76.846035)
		(mid 126.707314 76.654384)
		(end 126.898965 76.575)
		(width 0.2)
		(layer "F.Cu")
		(net 240)
	)
	(arc
		(start 126.898965 75.975)
		(mid 126.707314 75.895616)
		(end 126.62793 75.703965)
		(width 0.2)
		(layer "F.Cu")
		(net 240)
	)
	(arc
		(start 127.51207 76.146035)
		(mid 127.461975 76.025095)
		(end 127.341035 75.975)
		(width 0.2)
		(layer "F.Cu")
		(net 240)
	)
	(arc
		(start 127.416035 74.175)
		(mid 127.590008 74.102938)
		(end 127.66207 73.928965)
		(width 0.2)
		(layer "F.Cu")
		(net 240)
	)
	(arc
		(start 127.341035 75.375)
		(mid 127.461975 75.324905)
		(end 127.51207 75.203965)
		(width 0.2)
		(layer "F.Cu")
		(net 240)
	)
	(arc
		(start 126.62793 78.046035)
		(mid 126.707314 77.854384)
		(end 126.898965 77.775)
		(width 0.2)
		(layer "F.Cu")
		(net 240)
	)
	(arc
		(start 126.62793 74.446035)
		(mid 126.707314 74.254384)
		(end 126.898965 74.175)
		(width 0.2)
		(layer "F.Cu")
		(net 240)
	)
	(arc
		(start 127.341035 76.575)
		(mid 127.461975 76.524905)
		(end 127.51207 76.403965)
		(width 0.2)
		(layer "F.Cu")
		(net 240)
	)
	(arc
		(start 127.51207 77.346035)
		(mid 127.461975 77.225095)
		(end 127.341035 77.175)
		(width 0.2)
		(layer "F.Cu")
		(net 240)
	)
	(arc
		(start 127.416035 73.575)
		(mid 127.242062 73.502938)
		(end 127.17 73.328965)
		(width 0.2)
		(layer "F.Cu")
		(net 240)
	)
	(segment
		(start 119.97 77.65867)
		(end 119.97 71.41)
		(width 0.2)
		(layer "F.Cu")
		(net 241)
	)
	(segment
		(start 119.97 81.9)
		(end 119.97 81.2)
		(width 0.2)
		(layer "F.Cu")
		(net 241)
	)
	(segment
		(start 119.70367 78.525)
		(end 120.23633 78.525)
		(width 0.2)
		(layer "F.Cu")
		(net 241)
	)
	(segment
		(start 119.97 80.33367)
		(end 119.97 80.325)
		(width 0.2)
		(layer "F.Cu")
		(net 241)
	)
	(segment
		(start 119.43734 80.05867)
		(end 119.43734 79.99133)
		(width 0.2)
		(layer "F.Cu")
		(net 241)
	)
	(segment
		(start 119.70367 79.125)
		(end 120.23633 79.125)
		(width 0.2)
		(layer "F.Cu")
		(net 241)
	)
	(segment
		(start 119.70367 79.725)
		(end 120.23633 79.725)
		(width 0.2)
		(layer "F.Cu")
		(net 241)
	)
	(segment
		(start 120.50266 78.25867)
		(end 120.50266 78.19133)
		(width 0.2)
		(layer "F.Cu")
		(net 241)
	)
	(segment
		(start 121.46 70.94)
		(end 121.86 70.54)
		(width 0.2)
		(layer "F.Cu")
		(net 241)
	)
	(segment
		(start 119.97 80.325)
		(end 119.70367 80.325)
		(width 0.2)
		(layer "F.Cu")
		(net 241)
	)
	(segment
		(start 119.43734 78.85867)
		(end 119.43734 78.79133)
		(width 0.2)
		(layer "F.Cu")
		(net 241)
	)
	(segment
		(start 120.50266 80.66734)
		(end 120.50266 80.6)
		(width 0.2)
		(layer "F.Cu")
		(net 241)
	)
	(segment
		(start 121.5 84.7)
		(end 121.5 84)
		(width 0.15)
		(layer "F.Cu")
		(net 241)
	)
	(segment
		(start 119.97 71.41)
		(end 120.23 71.15)
		(width 0.2)
		(layer "F.Cu")
		(net 241)
	)
	(segment
		(start 120.69 70.94)
		(end 121.46 70.94)
		(width 0.2)
		(layer "F.Cu")
		(net 241)
	)
	(segment
		(start 121.5 84)
		(end 121.5 83.43)
		(width 0.2)
		(layer "F.Cu")
		(net 241)
	)
	(segment
		(start 121.1 85.1)
		(end 121.5 84.7)
		(width 0.15)
		(layer "F.Cu")
		(net 241)
	)
	(segment
		(start 121.5 83.43)
		(end 119.97 81.9)
		(width 0.2)
		(layer "F.Cu")
		(net 241)
	)
	(segment
		(start 120.48 71.15)
		(end 120.69 70.94)
		(width 0.2)
		(layer "F.Cu")
		(net 241)
	)
	(segment
		(start 120.50266 79.45867)
		(end 120.50266 79.39133)
		(width 0.2)
		(layer "F.Cu")
		(net 241)
	)
	(segment
		(start 120.23633 80.33367)
		(end 119.97 80.33367)
		(width 0.2)
		(layer "F.Cu")
		(net 241)
	)
	(segment
		(start 120.23 71.15)
		(end 120.48 71.15)
		(width 0.2)
		(layer "F.Cu")
		(net 241)
	)
	(arc
		(start 119.70367 80.325)
		(mid 119.515346 80.246994)
		(end 119.43734 80.05867)
		(width 0.2)
		(layer "F.Cu")
		(net 241)
	)
	(arc
		(start 120.50266 80.6)
		(mid 120.424654 80.411676)
		(end 120.23633 80.33367)
		(width 0.2)
		(layer "F.Cu")
		(net 241)
	)
	(arc
		(start 119.43734 78.79133)
		(mid 119.515346 78.603006)
		(end 119.70367 78.525)
		(width 0.2)
		(layer "F.Cu")
		(net 241)
	)
	(arc
		(start 119.70367 79.125)
		(mid 119.515346 79.046994)
		(end 119.43734 78.85867)
		(width 0.2)
		(layer "F.Cu")
		(net 241)
	)
	(arc
		(start 120.23633 80.93367)
		(mid 120.424654 80.855664)
		(end 120.50266 80.66734)
		(width 0.2)
		(layer "F.Cu")
		(net 241)
	)
	(arc
		(start 119.43734 79.99133)
		(mid 119.515346 79.803006)
		(end 119.70367 79.725)
		(width 0.2)
		(layer "F.Cu")
		(net 241)
	)
	(arc
		(start 120.50266 78.19133)
		(mid 120.424654 78.003006)
		(end 120.23633 77.925)
		(width 0.2)
		(layer "F.Cu")
		(net 241)
	)
	(arc
		(start 120.23633 77.925)
		(mid 120.048006 77.846994)
		(end 119.97 77.65867)
		(width 0.2)
		(layer "F.Cu")
		(net 241)
	)
	(arc
		(start 120.50266 79.39133)
		(mid 120.424654 79.203006)
		(end 120.23633 79.125)
		(width 0.2)
		(layer "F.Cu")
		(net 241)
	)
	(arc
		(start 120.23633 79.725)
		(mid 120.424654 79.646994)
		(end 120.50266 79.45867)
		(width 0.2)
		(layer "F.Cu")
		(net 241)
	)
	(arc
		(start 119.97 81.2)
		(mid 120.048006 81.011676)
		(end 120.23633 80.93367)
		(width 0.2)
		(layer "F.Cu")
		(net 241)
	)
	(arc
		(start 120.23633 78.525)
		(mid 120.424654 78.446994)
		(end 120.50266 78.25867)
		(width 0.2)
		(layer "F.Cu")
		(net 241)
	)
	(segment
		(start 91.1 73.4)
		(end 90.39 73.4)
		(width 0.5)
		(layer "F.Cu")
		(net 242)
	)
	(via
		(at 90.39 73.4)
		(size 0.45)
		(drill 0.2)
		(layers "F.Cu" "B.Cu")
		(remove_unused_layers yes)
		(keep_end_layers yes)
		(zone_layer_connections)
		(net 242)
	)
	(segment
		(start 90.56 73.23)
		(end 90.39 73.4)
		(width 0.5)
		(layer "B.Cu")
		(net 242)
	)
	(segment
		(start 90.56 72.595)
		(end 90.56 73.23)
		(width 0.5)
		(layer "B.Cu")
		(net 242)
	)
	(segment
		(start 86.675 77.415)
		(end 87.085 77.005)
		(width 0.45)
		(layer "F.Cu")
		(net 243)
	)
	(segment
		(start 87.085 77.005)
		(end 87.085 76.4)
		(width 0.45)
		(layer "F.Cu")
		(net 243)
	)
	(segment
		(start 87.085 76.4)
		(end 87.085 75.4)
		(width 0.45)
		(layer "F.Cu")
		(net 243)
	)
	(segment
		(start 87.085 75.4)
		(end 88.015 75.4)
		(width 0.45)
		(layer "F.Cu")
		(net 243)
	)
	(segment
		(start 86.1 77.415)
		(end 86.675 77.415)
		(width 0.45)
		(layer "F.Cu")
		(net 243)
	)
	(segment
		(start 93 70.7)
		(end 93 69.8)
		(width 0.15)
		(layer "F.Cu")
		(net 244)
	)
	(segment
		(start 94.1 71.415)
		(end 94.3 71.215)
		(width 0.3)
		(layer "F.Cu")
		(net 244)
	)
	(segment
		(start 93.515 71.215)
		(end 93 70.7)
		(width 0.15)
		(layer "F.Cu")
		(net 244)
	)
	(segment
		(start 94.3 71.215)
		(end 93.515 71.215)
		(width 0.15)
		(layer "F.Cu")
		(net 244)
	)
	(segment
		(start 94.1 73.4)
		(end 94.1 71.415)
		(width 0.3)
		(layer "F.Cu")
		(net 244)
	)
	(segment
		(start 124.03 110.4)
		(end 122.765 110.4)
		(width 0.15)
		(layer "F.Cu")
		(net 245)
	)
	(segment
		(start 122.765 110.4)
		(end 122.515 110.65)
		(width 0.15)
		(layer "F.Cu")
		(net 245)
	)
	(segment
		(start 105.58 71.25)
		(end 105.58 72.62)
		(width 0.3)
		(layer "F.Cu")
		(net 246)
	)
	(segment
		(start 108.75 71.25)
		(end 108.75 72.65)
		(width 0.3)
		(layer "F.Cu")
		(net 247)
	)
	(segment
		(start 121.06 68.94)
		(end 121.02 68.94)
		(width 0.3)
		(layer "F.Cu")
		(net 248)
	)
	(segment
		(start 128.7 87.1)
		(end 128.689355 87.1)
		(width 0.3)
		(layer "F.Cu")
		(net 248)
	)
	(segment
		(start 126.26 64.54)
		(end 126.66 64.14)
		(width 0.3)
		(layer "F.Cu")
		(net 248)
	)
	(segment
		(start 121.86 64.08)
		(end 122.25 63.69)
		(width 0.3)
		(layer "F.Cu")
		(net 248)
	)
	(segment
		(start 120.9 68.14)
		(end 120.56 68.48)
		(width 0.3)
		(layer "F.Cu")
		(net 248)
	)
	(segment
		(start 126.66 68.94)
		(end 127.06 69.34)
		(width 0.3)
		(layer "F.Cu")
		(net 248)
	)
	(segment
		(start 128.689355 87.1)
		(end 128.3 86.710645)
		(width 0.3)
		(layer "F.Cu")
		(net 248)
	)
	(segment
		(start 121.86 64.14)
		(end 121.86 64.08)
		(width 0.3)
		(layer "F.Cu")
		(net 248)
	)
	(segment
		(start 127.46 71.34)
		(end 127.96 71.34)
		(width 0.3)
		(layer "F.Cu")
		(net 248)
	)
	(segment
		(start 121.02 68.94)
		(end 120.56 68.48)
		(width 0.3)
		(layer "F.Cu")
		(net 248)
	)
	(segment
		(start 128.4695 61.74)
		(end 127.46 61.74)
		(width 0.3)
		(layer "F.Cu")
		(net 248)
	)
	(segment
		(start 121.06 61.74)
		(end 119.96 61.74)
		(width 0.3)
		(layer "F.Cu")
		(net 248)
	)
	(segment
		(start 120.56 65.74)
		(end 121.06 65.74)
		(width 0.3)
		(layer "F.Cu")
		(net 248)
	)
	(segment
		(start 122.26 66.94)
		(end 122.66 66.54)
		(width 0.3)
		(layer "F.Cu")
		(net 248)
	)
	(segment
		(start 121.86 71.38)
		(end 121.51 71.73)
		(width 0.3)
		(layer "F.Cu")
		(net 248)
	)
	(segment
		(start 121.86 71.34)
		(end 121.86 71.38)
		(width 0.3)
		(layer "F.Cu")
		(net 248)
	)
	(segment
		(start 123.5 85.9)
		(end 123.9 86.3)
		(width 0.3)
		(layer "F.Cu")
		(net 248)
	)
	(segment
		(start 120.5265 69.74)
		(end 120.52 69.7465)
		(width 0.3)
		(layer "F.Cu")
		(net 248)
	)
	(segment
		(start 126.66 70.54)
		(end 127.06 70.94)
		(width 0.3)
		(layer "F.Cu")
		(net 248)
	)
	(segment
		(start 127.96 67.34)
		(end 129.17 67.34)
		(width 0.3)
		(layer "F.Cu")
		(net 248)
	)
	(segment
		(start 128.7 87.1)
		(end 128.65 87.1)
		(width 0.1)
		(layer "F.Cu")
		(net 248)
	)
	(segment
		(start 121.06 69.74)
		(end 120.5265 69.74)
		(width 0.3)
		(layer "F.Cu")
		(net 248)
	)
	(segment
		(start 121.06 60.14)
		(end 119.96 60.14)
		(width 0.3)
		(layer "F.Cu")
		(net 248)
	)
	(segment
		(start 129.17 67.34)
		(end 129.33 67.5)
		(width 0.3)
		(layer "F.Cu")
		(net 248)
	)
	(segment
		(start 134.43 58.8)
		(end 137.265 58.8)
		(width 0.5)
		(layer "F.Cu")
		(net 248)
	)
	(segment
		(start 128.39 60.14)
		(end 128.55 59.98)
		(width 0.3)
		(layer "F.Cu")
		(net 248)
	)
	(segment
		(start 137.265 58.8)
		(end 137.59 58.475)
		(width 0.5)
		(layer "F.Cu")
		(net 248)
	)
	(segment
		(start 124.3 85.9)
		(end 124.7 86.3)
		(width 0.3)
		(layer "F.Cu")
		(net 248)
	)
	(segment
		(start 127.46 67.34)
		(end 127.96 67.34)
		(width 0.3)
		(layer "F.Cu")
		(net 248)
	)
	(segment
		(start 128.77 61.59)
		(end 128.4695 61.74)
		(width 0.3)
		(layer "F.Cu")
		(net 248)
	)
	(segment
		(start 131.523233 85.1)
		(end 131.923235 84.699998)
		(width 0.3)
		(layer "F.Cu")
		(net 248)
	)
	(segment
		(start 127.46 69.74)
		(end 127.96 69.74)
		(width 0.3)
		(layer "F.Cu")
		(net 248)
	)
	(segment
		(start 127.46 60.14)
		(end 128.39 60.14)
		(width 0.3)
		(layer "F.Cu")
		(net 248)
	)
	(segment
		(start 128.65 87.1)
		(end 128.3 86.75)
		(width 0.1)
		(layer "F.Cu")
		(net 248)
	)
	(segment
		(start 121.06 68.14)
		(end 120.9 68.14)
		(width 0.3)
		(layer "F.Cu")
		(net 248)
	)
	(segment
		(start 126.66 65.74)
		(end 127.06 65.34)
		(width 0.3)
		(layer "F.Cu")
		(net 248)
	)
	(via
		(at 137.59 60.575)
		(size 0.45)
		(drill 0.2)
		(layers "F.Cu" "B.Cu")
		(remove_unused_layers yes)
		(keep_end_layers yes)
		(free yes)
		(zone_layer_connections "In6.Cu")
		(net 248)
	)
	(via
		(at 123.9 86.3)
		(size 0.45)
		(drill 0.2)
		(layers "F.Cu" "B.Cu")
		(remove_unused_layers yes)
		(keep_end_layers yes)
		(zone_layer_connections "In6.Cu")
		(net 248)
	)
	(via
		(at 119.96 60.14)
		(size 0.45)
		(drill 0.2)
		(layers "F.Cu" "B.Cu")
		(remove_unused_layers yes)
		(keep_end_layers yes)
		(zone_layer_connections "In6.Cu")
		(net 248)
	)
	(via
		(at 126.26 64.54)
		(size 0.45)
		(drill 0.2)
		(layers "F.Cu" "B.Cu")
		(remove_unused_layers yes)
		(keep_end_layers yes)
		(zone_layer_connections "In6.Cu")
		(net 248)
	)
	(via
		(at 137.59 58.475)
		(size 0.45)
		(drill 0.2)
		(layers "F.Cu" "B.Cu")
		(remove_unused_layers yes)
		(keep_end_layers yes)
		(free yes)
		(zone_layer_connections "In6.Cu")
		(net 248)
	)
	(via
		(at 127.06 69.34)
		(size 0.45)
		(drill 0.2)
		(layers "F.Cu" "B.Cu")
		(remove_unused_layers yes)
		(keep_end_layers yes)
		(zone_layer_connections "In6.Cu")
		(net 248)
	)
	(via
		(at 127.96 67.34)
		(size 0.45)
		(drill 0.2)
		(layers "F.Cu" "B.Cu")
		(remove_unused_layers yes)
		(keep_end_layers yes)
		(zone_layer_connections "In6.Cu")
		(net 248)
	)
	(via
		(at 131.923235 84.699998)
		(size 0.45)
		(drill 0.2)
		(layers "F.Cu" "B.Cu")
		(remove_unused_layers yes)
		(keep_end_layers yes)
		(zone_layer_connections "In6.Cu")
		(net 248)
	)
	(via
		(at 120.56 65.74)
		(size 0.45)
		(drill 0.2)
		(layers "F.Cu" "B.Cu")
		(remove_unused_layers yes)
		(keep_end_layers yes)
		(zone_layer_connections "In6.Cu")
		(net 248)
	)
	(via
		(at 128.55 59.98)
		(size 0.45)
		(drill 0.2)
		(layers "F.Cu" "B.Cu")
		(remove_unused_layers yes)
		(keep_end_layers yes)
		(zone_layer_connections "In6.Cu")
		(net 248)
	)
	(via
		(at 120.52 69.7465)
		(size 0.45)
		(drill 0.2)
		(layers "F.Cu" "B.Cu")
		(remove_unused_layers yes)
		(keep_end_layers yes)
		(zone_layer_connections "In6.Cu")
		(net 248)
	)
	(via
		(at 124.7 86.3)
		(size 0.45)
		(drill 0.2)
		(layers "F.Cu" "B.Cu")
		(remove_unused_layers yes)
		(keep_end_layers yes)
		(zone_layer_connections "In6.Cu")
		(net 248)
	)
	(via
		(at 121.51 71.73)
		(size 0.45)
		(drill 0.2)
		(layers "F.Cu" "B.Cu")
		(remove_unused_layers yes)
		(keep_end_layers yes)
		(zone_layer_connections "In6.Cu")
		(net 248)
	)
	(via
		(at 120.56 68.48)
		(size 0.45)
		(drill 0.2)
		(layers "F.Cu" "B.Cu")
		(remove_unused_layers yes)
		(keep_end_layers yes)
		(zone_layer_connections "In6.Cu")
		(net 248)
	)
	(via
		(at 127.06 65.34)
		(size 0.45)
		(drill 0.2)
		(layers "F.Cu" "B.Cu")
		(remove_unused_layers yes)
		(keep_end_layers yes)
		(zone_layer_connections "In6.Cu")
		(net 248)
	)
	(via
		(at 155.03 82.15)
		(size 0.45)
		(drill 0.2)
		(layers "F.Cu" "B.Cu")
		(remove_unused_layers yes)
		(keep_end_layers yes)
		(zone_layer_connections)
		(net 248)
	)
	(via
		(at 127.96 71.34)
		(size 0.45)
		(drill 0.2)
		(layers "F.Cu" "B.Cu")
		(remove_unused_layers yes)
		(keep_end_layers yes)
		(zone_layer_connections "In6.Cu")
		(net 248)
	)
	(via
		(at 137.59 59.175)
		(size 0.45)
		(drill 0.2)
		(layers "F.Cu" "B.Cu")
		(remove_unused_layers yes)
		(keep_end_layers yes)
		(free yes)
		(zone_layer_connections "In6.Cu")
		(net 248)
	)
	(via
		(at 119.96 61.74)
		(size 0.45)
		(drill 0.2)
		(layers "F.Cu" "B.Cu")
		(remove_unused_layers yes)
		(keep_end_layers yes)
		(zone_layer_connections "In6.Cu")
		(net 248)
	)
	(via
		(at 122.25 63.69)
		(size 0.45)
		(drill 0.2)
		(layers "F.Cu" "B.Cu")
		(remove_unused_layers yes)
		(keep_end_layers yes)
		(zone_layer_connections "In6.Cu")
		(net 248)
	)
	(via
		(at 138.39 60.575)
		(size 0.45)
		(drill 0.2)
		(layers "F.Cu" "B.Cu")
		(remove_unused_layers yes)
		(keep_end_layers yes)
		(free yes)
		(zone_layer_connections "In6.Cu")
		(net 248)
	)
	(via
		(at 137.59 59.875)
		(size 0.45)
		(drill 0.2)
		(layers "F.Cu" "B.Cu")
		(remove_unused_layers yes)
		(keep_end_layers yes)
		(free yes)
		(zone_layer_connections "In6.Cu")
		(net 248)
	)
	(via
		(at 128.77 61.59)
		(size 0.45)
		(drill 0.2)
		(layers "F.Cu" "B.Cu")
		(remove_unused_layers yes)
		(keep_end_layers yes)
		(zone_layer_connections "In6.Cu")
		(net 248)
	)
	(via
		(at 128.7 87.1)
		(size 0.45)
		(drill 0.2)
		(layers "F.Cu" "B.Cu")
		(remove_unused_layers yes)
		(keep_end_layers yes)
		(zone_layer_connections "In6.Cu")
		(net 248)
	)
	(via
		(at 138.39 58.475)
		(size 0.45)
		(drill 0.2)
		(layers "F.Cu" "B.Cu")
		(remove_unused_layers yes)
		(keep_end_layers yes)
		(free yes)
		(zone_layer_connections "In6.Cu")
		(net 248)
	)
	(via
		(at 138.39 59.175)
		(size 0.45)
		(drill 0.2)
		(layers "F.Cu" "B.Cu")
		(remove_unused_layers yes)
		(keep_end_layers yes)
		(free yes)
		(zone_layer_connections "In6.Cu")
		(net 248)
	)
	(via
		(at 127.06 70.94)
		(size 0.45)
		(drill 0.2)
		(layers "F.Cu" "B.Cu")
		(remove_unused_layers yes)
		(keep_end_layers yes)
		(zone_layer_connections "In6.Cu")
		(net 248)
	)
	(via
		(at 138.39 59.875)
		(size 0.45)
		(drill 0.2)
		(layers "F.Cu" "B.Cu")
		(remove_unused_layers yes)
		(keep_end_layers yes)
		(free yes)
		(zone_layer_connections "In6.Cu")
		(net 248)
	)
	(via
		(at 122.26 66.94)
		(size 0.45)
		(drill 0.2)
		(layers "F.Cu" "B.Cu")
		(remove_unused_layers yes)
		(keep_end_layers yes)
		(zone_layer_connections "In6.Cu")
		(net 248)
	)
	(via
		(at 127.96 69.74)
		(size 0.45)
		(drill 0.2)
		(layers "F.Cu" "B.Cu")
		(remove_unused_layers yes)
		(keep_end_layers yes)
		(zone_layer_connections "In6.Cu")
		(net 248)
	)
	(segment
		(start 119.955 61.735)
		(end 119.96 61.74)
		(width 0.3)
		(layer "B.Cu")
		(net 248)
	)
	(segment
		(start 152.83 92.15)
		(end 154.83 90.15)
		(width 0.15)
		(layer "B.Cu")
		(net 248)
	)
	(segment
		(start 157.43 87.75)
		(end 157.43 84.55)
		(width 0.15)
		(layer "B.Cu")
		(net 248)
	)
	(segment
		(start 119.96 61.74)
		(end 119.96 61.955)
		(width 0.3)
		(layer "B.Cu")
		(net 248)
	)
	(segment
		(start 156.83 88.35)
		(end 157.43 87.75)
		(width 0.15)
		(layer "B.Cu")
		(net 248)
	)
	(segment
		(start 119.96 61.74)
		(end 119.96 61.565)
		(width 0.3)
		(layer "B.Cu")
		(net 248)
	)
	(segment
		(start 157.43 84.55)
		(end 155.03 82.15)
		(width 0.15)
		(layer "B.Cu")
		(net 248)
	)
	(segment
		(start 153.43 93.35)
		(end 152.83 92.75)
		(width 0.15)
		(layer "B.Cu")
		(net 248)
	)
	(segment
		(start 133.073726 84.626274)
		(end 131.996959 84.626274)
		(width 0.3)
		(layer "B.Cu")
		(net 248)
	)
	(segment
		(start 154.6675 96.5)
		(end 153.58 96.5)
		(width 0.15)
		(layer "B.Cu")
		(net 248)
	)
	(segment
		(start 138.39 59.875)
		(end 139.04 59.875)
		(width 0.2)
		(layer "B.Cu")
		(net 248)
	)
	(segment
		(start 154.83 90.15)
		(end 154.83 89.15)
		(width 0.15)
		(layer "B.Cu")
		(net 248)
	)
	(segment
		(start 154.83 89.15)
		(end 155.63 88.35)
		(width 0.15)
		(layer "B.Cu")
		(net 248)
	)
	(segment
		(start 155.63 88.35)
		(end 156.83 88.35)
		(width 0.15)
		(layer "B.Cu")
		(net 248)
	)
	(segment
		(start 153.43 96.35)
		(end 153.43 93.35)
		(width 0.15)
		(layer "B.Cu")
		(net 248)
	)
	(segment
		(start 131.996959 84.626274)
		(end 131.923235 84.699998)
		(width 0.3)
		(layer "B.Cu")
		(net 248)
	)
	(segment
		(start 119.96 61.955)
		(end 119.505 62.41)
		(width 0.3)
		(layer "B.Cu")
		(net 248)
	)
	(segment
		(start 152.83 92.75)
		(end 152.83 92.15)
		(width 0.15)
		(layer "B.Cu")
		(net 248)
	)
	(segment
		(start 124.576274 86.523726)
		(end 124.576274 86.423726)
		(width 0.3)
		(layer "B.Cu")
		(net 248)
	)
	(segment
		(start 153.58 96.5)
		(end 153.43 96.35)
		(width 0.15)
		(layer "B.Cu")
		(net 248)
	)
	(segment
		(start 124.576274 86.423726)
		(end 124.7 86.3)
		(width 0.3)
		(layer "B.Cu")
		(net 248)
	)
	(segment
		(start 139.155 59.875)
		(end 138.39 59.875)
		(width 0.15)
		(layer "In2.Cu")
		(net 248)
	)
	(segment
		(start 142.09 77.84)
		(end 142.09 62.81)
		(width 0.15)
		(layer "In2.Cu")
		(net 248)
	)
	(segment
		(start 142.09 62.81)
		(end 139.155 59.875)
		(width 0.15)
		(layer "In2.Cu")
		(net 248)
	)
	(segment
		(start 146.4 82.15)
		(end 142.09 77.84)
		(width 0.15)
		(layer "In2.Cu")
		(net 248)
	)
	(segment
		(start 155.03 82.15)
		(end 146.4 82.15)
		(width 0.15)
		(layer "In2.Cu")
		(net 248)
	)
	(segment
		(start 86.7 107.15)
		(end 87.025 106.825)
		(width 0.4)
		(layer "F.Cu")
		(net 249)
	)
	(segment
		(start 84.685 107.15)
		(end 86.7 107.15)
		(width 0.4)
		(layer "F.Cu")
		(net 249)
	)
	(segment
		(start 84.685 107.15)
		(end 84.685 108.15)
		(width 0.4)
		(layer "F.Cu")
		(net 249)
	)
	(segment
		(start 83.715 108.15)
		(end 83.715 109.15)
		(width 0.1)
		(layer "F.Cu")
		(net 250)
	)
	(segment
		(start 83.785 104.675)
		(end 84.19 104.675)
		(width 0.45)
		(layer "F.Cu")
		(net 251)
	)
	(segment
		(start 83.785 104.675)
		(end 84.24 104.675)
		(width 0.45)
		(layer "F.Cu")
		(net 251)
	)
	(segment
		(start 84.24 104.675)
		(end 84.715 105.15)
		(width 0.45)
		(layer "F.Cu")
		(net 251)
	)
	(segment
		(start 84.19 104.675)
		(end 84.715 104.15)
		(width 0.45)
		(layer "F.Cu")
		(net 251)
	)
	(segment
		(start 76.15 104.675)
		(end 82.815 104.675)
		(width 0.45)
		(layer "F.Cu")
		(net 252)
	)
	(segment
		(start 86.115 76.4)
		(end 86.115 75.4)
		(width 0.45)
		(layer "F.Cu")
		(net 253)
	)
	(segment
		(start 85.565 74.85)
		(end 86.115 75.4)
		(width 0.45)
		(layer "F.Cu")
		(net 253)
	)
	(segment
		(start 76.35 74.85)
		(end 85.565 74.85)
		(width 0.45)
		(layer "F.Cu")
		(net 253)
	)
	(segment
		(start 85.685 105.15)
		(end 85.685 106.065)
		(width 0.4)
		(layer "F.Cu")
		(net 254)
	)
	(segment
		(start 87 106.15)
		(end 87.025 106.175)
		(width 0.4)
		(layer "F.Cu")
		(net 254)
	)
	(segment
		(start 84.685 106.15)
		(end 85.77 106.15)
		(width 0.4)
		(layer "F.Cu")
		(net 254)
	)
	(segment
		(start 85.685 106.065)
		(end 85.77 106.15)
		(width 0.4)
		(layer "F.Cu")
		(net 254)
	)
	(segment
		(start 85.685 104.15)
		(end 85.685 105.15)
		(width 0.4)
		(layer "F.Cu")
		(net 254)
	)
	(segment
		(start 85.77 106.15)
		(end 87 106.15)
		(width 0.4)
		(layer "F.Cu")
		(net 254)
	)
	(segment
		(start 170.548952 80.95)
		(end 171.88 80.95)
		(width 0.15)
		(layer "F.Cu")
		(net 255)
	)
	(segment
		(start 170.53 80.968952)
		(end 170.548952 80.95)
		(width 0.15)
		(layer "F.Cu")
		(net 255)
	)
	(segment
		(start 170.53 82.55)
		(end 171.88 82.55)
		(width 0.15)
		(layer "F.Cu")
		(net 256)
	)
	(segment
		(start 170.67 77.8)
		(end 171.94 77.8)
		(width 0.3)
		(layer "F.Cu")
		(net 257)
	)
	(segment
		(start 170.6 77.73)
		(end 170.67 77.8)
		(width 0.3)
		(layer "F.Cu")
		(net 257)
	)
	(segment
		(start 146.35 83.771046)
		(end 145.078954 82.5)
		(width 0.15)
		(layer "F.Cu")
		(net 258)
	)
	(segment
		(start 146.85 90.75)
		(end 146.35 90.25)
		(width 0.15)
		(layer "F.Cu")
		(net 258)
	)
	(segment
		(start 145.078954 82.5)
		(end 142.25 82.5)
		(width 0.15)
		(layer "F.Cu")
		(net 258)
	)
	(segment
		(start 146.35 90.25)
		(end 146.35 83.771046)
		(width 0.15)
		(layer "F.Cu")
		(net 258)
	)
	(segment
		(start 147.3 90.65)
		(end 146.85 90.75)
		(width 0.15)
		(layer "F.Cu")
		(net 258)
	)
	(via
		(at 147.3 90.65)
		(size 0.45)
		(drill 0.2)
		(layers "F.Cu" "B.Cu")
		(remove_unused_layers yes)
		(keep_end_layers yes)
		(zone_layer_connections)
		(net 258)
	)
	(segment
		(start 147.203554 90.75)
		(end 149.05 88.903554)
		(width 0.15)
		(layer "B.Cu")
		(net 258)
	)
	(segment
		(start 148.128554 85.575)
		(end 147.55 85.575)
		(width 0.15)
		(layer "B.Cu")
		(net 258)
	)
	(segment
		(start 147.3 90.65)
		(end 147.203554 90.75)
		(width 0.15)
		(layer "B.Cu")
		(net 258)
	)
	(segment
		(start 149.05 86.496446)
		(end 148.128554 85.575)
		(width 0.15)
		(layer "B.Cu")
		(net 258)
	)
	(segment
		(start 149.05 88.903554)
		(end 149.05 86.496446)
		(width 0.15)
		(layer "B.Cu")
		(net 258)
	)
	(segment
		(start 159.89 73.9)
		(end 159.69 73.7)
		(width 0.3)
		(layer "B.Cu")
		(net 259)
	)
	(segment
		(start 159.69 73.7)
		(end 159.69 73.3)
		(width 0.3)
		(layer "B.Cu")
		(net 259)
	)
	(segment
		(start 161.205 73.9)
		(end 159.89 73.9)
		(width 0.3)
		(layer "B.Cu")
		(net 259)
	)
	(segment
		(start 158.89 73.3)
		(end 159.69 73.3)
		(width 0.3)
		(layer "B.Cu")
		(net 259)
	)
	(segment
		(start 158.63 73.04)
		(end 158.89 73.3)
		(width 0.3)
		(layer "B.Cu")
		(net 259)
	)
	(segment
		(start 158.63 69.4)
		(end 158.63 73.04)
		(width 0.3)
		(layer "B.Cu")
		(net 259)
	)
	(segment
		(start 152.78 67)
		(end 152.23 67.55)
		(width 0.3)
		(layer "F.Cu")
		(net 260)
	)
	(segment
		(start 153.23 67)
		(end 152.78 67)
		(width 0.3)
		(layer "F.Cu")
		(net 260)
	)
	(via
		(at 152.23 67.55)
		(size 0.45)
		(drill 0.2)
		(layers "F.Cu" "B.Cu")
		(remove_unused_layers yes)
		(keep_end_layers yes)
		(zone_layer_connections)
		(net 260)
	)
	(segment
		(start 152.23 66.735)
		(end 152.23 67.55)
		(width 0.3)
		(layer "B.Cu")
		(net 260)
	)
	(segment
		(start 153.48 66.7)
		(end 152.265 66.7)
		(width 0.3)
		(layer "B.Cu")
		(net 260)
	)
	(segment
		(start 125.53 113.65)
		(end 123.015 113.65)
		(width 0.15)
		(layer "F.Cu")
		(net 261)
	)
	(segment
		(start 125.98 112.6)
		(end 125.98 113.2)
		(width 0.15)
		(layer "F.Cu")
		(net 261)
	)
	(segment
		(start 125.98 113.2)
		(end 125.53 113.65)
		(width 0.15)
		(layer "F.Cu")
		(net 261)
	)
	(segment
		(start 123.015 113.65)
		(end 122.515 114.15)
		(width 0.15)
		(layer "F.Cu")
		(net 261)
	)
	(segment
		(start 134.35 60.44)
		(end 134.95 59.84)
		(width 0.15)
		(layer "B.Cu")
		(net 262)
	)
	(segment
		(start 136.59 57.35)
		(end 137.005 57.35)
		(width 0.15)
		(layer "B.Cu")
		(net 262)
	)
	(segment
		(start 134.95 58.99)
		(end 136.59 57.35)
		(width 0.15)
		(layer "B.Cu")
		(net 262)
	)
	(segment
		(start 134.95 59.84)
		(end 134.95 58.99)
		(width 0.15)
		(layer "B.Cu")
		(net 262)
	)
	(segment
		(start 132.774 61.441)
		(end 132.774 60.556)
		(width 0.15)
		(layer "B.Cu")
		(net 262)
	)
	(segment
		(start 132.774 60.556)
		(end 132.89 60.44)
		(width 0.15)
		(layer "B.Cu")
		(net 262)
	)
	(segment
		(start 132.89 60.44)
		(end 134.35 60.44)
		(width 0.15)
		(layer "B.Cu")
		(net 262)
	)
	(segment
		(start 139.53 57.825)
		(end 139.53 58.855)
		(width 0.3)
		(layer "F.Cu")
		(net 263)
	)
	(segment
		(start 139.53 57.825)
		(end 139.715 57.825)
		(width 0.3)
		(layer "F.Cu")
		(net 263)
	)
	(segment
		(start 141.5 55.74)
		(end 147 55.74)
		(width 0.3)
		(layer "F.Cu")
		(net 263)
	)
	(segment
		(start 139.715 57.825)
		(end 140.1 57.44)
		(width 0.3)
		(layer "F.Cu")
		(net 263)
	)
	(segment
		(start 147.49 56.23)
		(end 147.49 57.95)
		(width 0.3)
		(layer "F.Cu")
		(net 263)
	)
	(segment
		(start 140.1 57.44)
		(end 140.1 57.14)
		(width 0.3)
		(layer "F.Cu")
		(net 263)
	)
	(segment
		(start 140.1 57.14)
		(end 141.5 55.74)
		(width 0.3)
		(layer "F.Cu")
		(net 263)
	)
	(segment
		(start 147 55.74)
		(end 147.49 56.23)
		(width 0.3)
		(layer "F.Cu")
		(net 263)
	)
	(segment
		(start 144.355 107.9)
		(end 144.355 106.87)
		(width 0.5)
		(layer "F.Cu")
		(net 264)
	)
	(segment
		(start 143.04 107.85)
		(end 144.305 107.85)
		(width 0.5)
		(layer "F.Cu")
		(net 264)
	)
	(segment
		(start 144.305 107.85)
		(end 144.355 107.9)
		(width 0.5)
		(layer "F.Cu")
		(net 264)
	)
	(segment
		(start 144.49 116.4)
		(end 145.705 116.4)
		(width 0.5)
		(layer "F.Cu")
		(net 265)
	)
	(segment
		(start 145.705 116.4)
		(end 145.855 116.55)
		(width 0.5)
		(layer "F.Cu")
		(net 265)
	)
	(segment
		(start 145.84 115.435)
		(end 145.84 116.535)
		(width 0.5)
		(layer "F.Cu")
		(net 265)
	)
	(segment
		(start 144.455 112.75)
		(end 144.455 111.72)
		(width 0.5)
		(layer "F.Cu")
		(net 266)
	)
	(segment
		(start 143.04 111.65)
		(end 144.455 111.65)
		(width 0.5)
		(layer "F.Cu")
		(net 266)
	)
	(segment
		(start 141.28 76.19)
		(end 139.29 74.2)
		(width 0.3)
		(layer "F.Cu")
		(net 267)
	)
	(segment
		(start 143.8 76.19)
		(end 143.805 76.195)
		(width 0.2)
		(layer "F.Cu")
		(net 267)
	)
	(segment
		(start 143.8 76.19)
		(end 141.28 76.19)
		(width 0.3)
		(layer "F.Cu")
		(net 267)
	)
	(segment
		(start 143.805 77.135)
		(end 143.8 77.14)
		(width 0.2)
		(layer "F.Cu")
		(net 267)
	)
	(segment
		(start 143.805 76.195)
		(end 143.805 77.135)
		(width 0.2)
		(layer "F.Cu")
		(net 267)
	)
	(segment
		(start 139.29 74.2)
		(end 139.29 68.6)
		(width 0.3)
		(layer "F.Cu")
		(net 267)
	)
	(segment
		(start 139.29 68.6)
		(end 139.59 68.3)
		(width 0.3)
		(layer "F.Cu")
		(net 267)
	)
	(segment
		(start 139.59 68.3)
		(end 141.69 68.3)
		(width 0.3)
		(layer "F.Cu")
		(net 267)
	)
	(segment
		(start 143.04 105.95)
		(end 144.305 105.95)
		(width 0.5)
		(layer "F.Cu")
		(net 268)
	)
	(segment
		(start 144.305 105.95)
		(end 144.39 105.865)
		(width 0.5)
		(layer "F.Cu")
		(net 268)
	)
	(segment
		(start 145.84 114.465)
		(end 144.525 114.465)
		(width 0.5)
		(layer "F.Cu")
		(net 269)
	)
	(segment
		(start 144.525 114.465)
		(end 144.49 114.5)
		(width 0.5)
		(layer "F.Cu")
		(net 269)
	)
	(segment
		(start 165.79 67.05)
		(end 167.34 67.05)
		(width 0.3)
		(layer "F.Cu")
		(net 270)
	)
	(segment
		(start 166.34 59.75)
		(end 164.94 59.75)
		(width 0.3)
		(layer "F.Cu")
		(net 270)
	)
	(segment
		(start 167.94 63.15)
		(end 166.74 61.95)
		(width 0.3)
		(layer "F.Cu")
		(net 270)
	)
	(segment
		(start 164.705 59.515)
		(end 164.705 59.04)
		(width 0.3)
		(layer "F.Cu")
		(net 270)
	)
	(segment
		(start 163.675 59.04)
		(end 164.705 59.04)
		(width 0.3)
		(layer "F.Cu")
		(net 270)
	)
	(segment
		(start 167.34 67.05)
		(end 167.94 66.45)
		(width 0.3)
		(layer "F.Cu")
		(net 270)
	)
	(segment
		(start 166.74 60.15)
		(end 166.34 59.75)
		(width 0.3)
		(layer "F.Cu")
		(net 270)
	)
	(segment
		(start 167.94 66.45)
		(end 167.94 63.15)
		(width 0.3)
		(layer "F.Cu")
		(net 270)
	)
	(segment
		(start 166.74 61.95)
		(end 166.74 60.15)
		(width 0.3)
		(layer "F.Cu")
		(net 270)
	)
	(segment
		(start 164.94 59.75)
		(end 164.705 59.515)
		(width 0.3)
		(layer "F.Cu")
		(net 270)
	)
	(segment
		(start 143.525 109.75)
		(end 144.49 110.715)
		(width 0.5)
		(layer "F.Cu")
		(net 271)
	)
	(segment
		(start 143.04 109.75)
		(end 143.525 109.75)
		(width 0.5)
		(layer "F.Cu")
		(net 271)
	)
	(segment
		(start 141.24 106.95)
		(end 141.24 105.4)
		(width 0.3)
		(layer "F.Cu")
		(net 272)
	)
	(segment
		(start 138.79 108.3)
		(end 139.24 107.85)
		(width 0.5)
		(layer "F.Cu")
		(net 272)
	)
	(segment
		(start 141.24 105.4)
		(end 142.19 104.45)
		(width 0.3)
		(layer "F.Cu")
		(net 272)
	)
	(segment
		(start 139.24 107.85)
		(end 140.34 107.85)
		(width 0.5)
		(layer "F.Cu")
		(net 272)
	)
	(segment
		(start 140.34 107.85)
		(end 141.24 106.95)
		(width 0.3)
		(layer "F.Cu")
		(net 272)
	)
	(segment
		(start 141.73 117.85)
		(end 141.73 116.46)
		(width 0.15)
		(layer "F.Cu")
		(net 279)
	)
	(segment
		(start 141.59 116.6)
		(end 141.79 116.4)
		(width 0.3)
		(layer "F.Cu")
		(net 279)
	)
	(segment
		(start 140.29 116.6)
		(end 141.59 116.6)
		(width 0.3)
		(layer "F.Cu")
		(net 279)
	)
	(segment
		(start 140.34 105.95)
		(end 140.34 105.3)
		(width 0.3)
		(layer "F.Cu")
		(net 280)
	)
	(segment
		(start 141.125 104.1475)
		(end 141.8075 103.465)
		(width 0.3)
		(layer "F.Cu")
		(net 280)
	)
	(segment
		(start 141.125 104.55)
		(end 141.125 104.1475)
		(width 0.3)
		(layer "F.Cu")
		(net 280)
	)
	(segment
		(start 140.34 105.3)
		(end 141.09 104.55)
		(width 0.3)
		(layer "F.Cu")
		(net 280)
	)
	(segment
		(start 141.8075 103.465)
		(end 142.19 103.465)
		(width 0.3)
		(layer "F.Cu")
		(net 280)
	)
	(segment
		(start 146.5 121.1005)
		(end 145.45 122.1505)
		(width 0.15)
		(layer "F.Cu")
		(net 281)
	)
	(segment
		(start 136.83 118.35)
		(end 145.03 118.35)
		(width 0.15)
		(layer "F.Cu")
		(net 281)
	)
	(segment
		(start 133.345 114.865)
		(end 136.83 118.35)
		(width 0.15)
		(layer "F.Cu")
		(net 281)
	)
	(segment
		(start 133.345 113.15)
		(end 133.345 114.865)
		(width 0.15)
		(layer "F.Cu")
		(net 281)
	)
	(via
		(at 146.5 121.1005)
		(size 0.45)
		(drill 0.2)
		(layers "F.Cu" "B.Cu")
		(remove_unused_layers yes)
		(keep_end_layers yes)
		(zone_layer_connections)
		(net 281)
	)
	(via
		(at 145.03 118.35)
		(size 0.45)
		(drill 0.2)
		(layers "F.Cu" "B.Cu")
		(remove_unused_layers yes)
		(keep_end_layers yes)
		(zone_layer_connections)
		(net 281)
	)
	(segment
		(start 146.5 121.1005)
		(end 146.5 119.82)
		(width 0.15)
		(layer "B.Cu")
		(net 281)
	)
	(segment
		(start 146.5 119.82)
		(end 145.03 118.35)
		(width 0.15)
		(layer "B.Cu")
		(net 281)
	)
	(segment
		(start 142.48 114.5)
		(end 141.79 114.5)
		(width 0.15)
		(layer "F.Cu")
		(net 282)
	)
	(segment
		(start 141.47 114.08)
		(end 140.57 114.08)
		(width 0.5)
		(layer "F.Cu")
		(net 282)
	)
	(segment
		(start 141.79 114.5)
		(end 141.79 114.4)
		(width 0.5)
		(layer "F.Cu")
		(net 282)
	)
	(segment
		(start 141.79 114.4)
		(end 141.47 114.08)
		(width 0.5)
		(layer "F.Cu")
		(net 282)
	)
	(segment
		(start 142.7 114.72)
		(end 142.48 114.5)
		(width 0.15)
		(layer "F.Cu")
		(net 282)
	)
	(segment
		(start 142.7 117.85)
		(end 142.7 114.72)
		(width 0.15)
		(layer "F.Cu")
		(net 282)
	)
	(segment
		(start 139.04 109.685)
		(end 140.275 109.685)
		(width 0.5)
		(layer "F.Cu")
		(net 283)
	)
	(segment
		(start 138.351075 108.976075)
		(end 138.056075 108.976075)
		(width 0.3)
		(layer "F.Cu")
		(net 283)
	)
	(segment
		(start 138.975 109.6)
		(end 138.351075 108.976075)
		(width 0.3)
		(layer "F.Cu")
		(net 283)
	)
	(segment
		(start 140.275 109.685)
		(end 140.34 109.75)
		(width 0.5)
		(layer "F.Cu")
		(net 283)
	)
	(segment
		(start 137.63 108.55)
		(end 138.056075 108.976075)
		(width 0.3)
		(layer "F.Cu")
		(net 283)
	)
	(segment
		(start 138.79 113.6)
		(end 138.79 113.52)
		(width 0.5)
		(layer "F.Cu")
		(net 284)
	)
	(segment
		(start 137.23 114.35)
		(end 137.83 114.35)
		(width 0.3)
		(layer "F.Cu")
		(net 284)
	)
	(segment
		(start 140.29 112.02)
		(end 140.29 111.9)
		(width 0.5)
		(layer "F.Cu")
		(net 284)
	)
	(segment
		(start 135.63 112.75)
		(end 137.23 114.35)
		(width 0.3)
		(layer "F.Cu")
		(net 284)
	)
	(segment
		(start 135.63 110.35)
		(end 135.63 112.75)
		(width 0.3)
		(layer "F.Cu")
		(net 284)
	)
	(segment
		(start 137.83 114.35)
		(end 138.58 113.6)
		(width 0.3)
		(layer "F.Cu")
		(net 284)
	)
	(segment
		(start 138.79 113.52)
		(end 140.29 112.02)
		(width 0.5)
		(layer "F.Cu")
		(net 284)
	)
	(segment
		(start 136.63 108.55)
		(end 136.63 109.35)
		(width 0.3)
		(layer "F.Cu")
		(net 284)
	)
	(segment
		(start 136.63 109.35)
		(end 135.63 110.35)
		(width 0.3)
		(layer "F.Cu")
		(net 284)
	)
	(segment
		(start 89.97 109.065)
		(end 89.97 107.83)
		(width 0.3)
		(layer "F.Cu")
		(net 285)
	)
	(segment
		(start 112.04 86.475)
		(end 112.915 85.6)
		(width 0.15)
		(layer "F.Cu")
		(net 286)
	)
	(segment
		(start 112.04 87.98)
		(end 112.04 86.475)
		(width 0.15)
		(layer "F.Cu")
		(net 286)
	)
	(segment
		(start 121.5645 63.0445)
		(end 121.86 63.34)
		(width 0.1)
		(layer "F.Cu")
		(net 287)
	)
	(segment
		(start 121.462717 63.0445)
		(end 121.5645 63.0445)
		(width 0.1)
		(layer "F.Cu")
		(net 287)
	)
	(via
		(at 121.462717 63.0445)
		(size 0.45)
		(drill 0.2)
		(layers "F.Cu" "B.Cu")
		(remove_unused_layers yes)
		(keep_end_layers yes)
		(zone_layer_connections)
		(net 287)
	)
	(segment
		(start 121.01 63.265)
		(end 120.855 63.42)
		(width 0.3)
		(layer "B.Cu")
		(net 287)
	)
	(segment
		(start 121.462717 63.0445)
		(end 121.242217 63.265)
		(width 0.3)
		(layer "B.Cu")
		(net 287)
	)
	(segment
		(start 121.242217 63.265)
		(end 121.01 63.265)
		(width 0.3)
		(layer "B.Cu")
		(net 287)
	)
	(segment
		(start 91.8 69.685)
		(end 90.8 69.685)
		(width 0.1)
		(layer "F.Cu")
		(net 288)
	)
	(segment
		(start 93.1 73.4)
		(end 93.1 72.4)
		(width 0.3)
		(layer "F.Cu")
		(net 288)
	)
	(segment
		(start 91.8 71.1)
		(end 91.8 69.685)
		(width 0.3)
		(layer "F.Cu")
		(net 288)
	)
	(segment
		(start 93.1 72.4)
		(end 91.8 71.1)
		(width 0.3)
		(layer "F.Cu")
		(net 288)
	)
	(segment
		(start 90.975 104.875)
		(end 92.09 104.875)
		(width 0.3)
		(layer "F.Cu")
		(net 289)
	)
	(segment
		(start 102.965 104.725)
		(end 104.915 104.725)
		(width 0.15)
		(layer "F.Cu")
		(net 290)
	)
	(segment
		(start 106.09 105.9)
		(end 104.915 104.725)
		(width 0.15)
		(layer "F.Cu")
		(net 290)
	)
	(segment
		(start 106.09 106.5)
		(end 106.09 105.9)
		(width 0.15)
		(layer "F.Cu")
		(net 290)
	)
	(segment
		(start 88.085 79.4)
		(end 89.085 79.4)
		(width 0.4)
		(layer "F.Cu")
		(net 291)
	)
	(segment
		(start 90.991 79.5)
		(end 91.091 79.4)
		(width 0.4)
		(layer "F.Cu")
		(net 291)
	)
	(segment
		(start 89.1 79.384)
		(end 89.216001 79.500001)
		(width 0.4)
		(layer "F.Cu")
		(net 291)
	)
	(segment
		(start 89.216001 79.500001)
		(end 90.991 79.5)
		(width 0.4)
		(layer "F.Cu")
		(net 291)
	)
	(segment
		(start 89.216001 78.299999)
		(end 90.992 78.3)
		(width 0.4)
		(layer "F.Cu")
		(net 292)
	)
	(segment
		(start 89.1 78.416)
		(end 89.216001 78.299999)
		(width 0.4)
		(layer "F.Cu")
		(net 292)
	)
	(segment
		(start 90.992 78.3)
		(end 91.091 78.399)
		(width 0.4)
		(layer "F.Cu")
		(net 292)
	)
	(segment
		(start 88.015 76.4)
		(end 88.015 77.4)
		(width 0.4)
		(layer "F.Cu")
		(net 293)
	)
	(segment
		(start 140.75 82.5)
		(end 140.75 81.05)
		(width 0.3)
		(layer "F.Cu")
		(net 294)
	)
	(segment
		(start 140.8 85.5)
		(end 140.8 84.05)
		(width 0.3)
		(layer "F.Cu")
		(net 295)
	)
	(segment
		(start 143.844 84)
		(end 144.25 83.594)
		(width 0.15)
		(layer "F.Cu")
		(net 296)
	)
	(segment
		(start 142.25 84)
		(end 143.844 84)
		(width 0.15)
		(layer "F.Cu")
		(net 296)
	)
	(via
		(at 144.25 83.594)
		(size 0.45)
		(drill 0.2)
		(layers "F.Cu" "B.Cu")
		(remove_unused_layers yes)
		(keep_end_layers yes)
		(zone_layer_connections)
		(net 296)
	)
	(segment
		(start 144.631 83.594)
		(end 144.775 83.45)
		(width 0.15)
		(layer "B.Cu")
		(net 296)
	)
	(segment
		(start 144.25 83.594)
		(end 144.631 83.594)
		(width 0.15)
		(layer "B.Cu")
		(net 296)
	)
	(segment
		(start 104.165 105.375)
		(end 104.59 105.8)
		(width 0.15)
		(layer "F.Cu")
		(net 298)
	)
	(segment
		(start 104.59 105.8)
		(end 104.59 106.715)
		(width 0.15)
		(layer "F.Cu")
		(net 298)
	)
	(segment
		(start 102.965 105.375)
		(end 104.165 105.375)
		(width 0.15)
		(layer "F.Cu")
		(net 298)
	)
	(segment
		(start 101.29 102.125)
		(end 102.965 102.125)
		(width 0.15)
		(layer "F.Cu")
		(net 299)
	)
	(segment
		(start 103.75 99.25)
		(end 103.75 97.07)
		(width 0.15)
		(layer "F.Cu")
		(net 300)
	)
	(segment
		(start 111.4 97.834314)
		(end 111.4 97.9)
		(width 0.15)
		(layer "F.Cu")
		(net 300)
	)
	(segment
		(start 111.8 96)
		(end 112.3 96.5)
		(width 0.15)
		(layer "F.Cu")
		(net 300)
	)
	(segment
		(start 102.765 97.0758)
		(end 103.7558 97.0758)
		(width 0.1)
		(layer "F.Cu")
		(net 300)
	)
	(segment
		(start 111.634314 97.6)
		(end 111.4 97.834314)
		(width 0.15)
		(layer "F.Cu")
		(net 300)
	)
	(segment
		(start 111 96)
		(end 111.8 96)
		(width 0.15)
		(layer "F.Cu")
		(net 300)
	)
	(segment
		(start 112.3 97.034314)
		(end 112.2 97.134314)
		(width 0.15)
		(layer "F.Cu")
		(net 300)
	)
	(segment
		(start 109.7 99.6)
		(end 107.6 99.6)
		(width 0.15)
		(layer "F.Cu")
		(net 300)
	)
	(segment
		(start 112.2 97.3)
		(end 111.9 97.6)
		(width 0.15)
		(layer "F.Cu")
		(net 300)
	)
	(segment
		(start 111.4 97.9)
		(end 109.7 99.6)
		(width 0.15)
		(layer "F.Cu")
		(net 300)
	)
	(segment
		(start 103.75 96.059)
		(end 103.75 97.07)
		(width 0.15)
		(layer "F.Cu")
		(net 300)
	)
	(segment
		(start 107.6 99.6)
		(end 106.8 100.4)
		(width 0.15)
		(layer "F.Cu")
		(net 300)
	)
	(segment
		(start 103.2905 95.5995)
		(end 103.75 96.059)
		(width 0.15)
		(layer "F.Cu")
		(net 300)
	)
	(segment
		(start 111.9 97.6)
		(end 111.634314 97.6)
		(width 0.15)
		(layer "F.Cu")
		(net 300)
	)
	(segment
		(start 104.9 100.4)
		(end 103.75 99.25)
		(width 0.15)
		(layer "F.Cu")
		(net 300)
	)
	(segment
		(start 112.2 97.134314)
		(end 112.2 97.3)
		(width 0.15)
		(layer "F.Cu")
		(net 300)
	)
	(segment
		(start 106.8 100.4)
		(end 104.9 100.4)
		(width 0.15)
		(layer "F.Cu")
		(net 300)
	)
	(segment
		(start 112.3 96.5)
		(end 112.3 97.034314)
		(width 0.15)
		(layer "F.Cu")
		(net 300)
	)
	(via
		(at 103.2905 95.5995)
		(size 0.45)
		(drill 0.2)
		(layers "F.Cu" "B.Cu")
		(remove_unused_layers yes)
		(keep_end_layers yes)
		(zone_layer_connections)
		(net 300)
	)
	(segment
		(start 103.19 95.7)
		(end 103.19 96.315)
		(width 0.15)
		(layer "B.Cu")
		(net 300)
	)
	(segment
		(start 103.2905 95.5995)
		(end 103.19 95.7)
		(width 0.15)
		(layer "B.Cu")
		(net 300)
	)
	(segment
		(start 108.355686 93.3)
		(end 109.055686 92.6)
		(width 0.15)
		(layer "F.Cu")
		(net 301)
	)
	(segment
		(start 106.7 93.3)
		(end 108.355686 93.3)
		(width 0.15)
		(layer "F.Cu")
		(net 301)
	)
	(segment
		(start 109.055686 92.6)
		(end 109.165686 92.6)
		(width 0.15)
		(layer "F.Cu")
		(net 301)
	)
	(segment
		(start 106.7 93.3)
		(end 106.3 93.3)
		(width 0.15)
		(layer "F.Cu")
		(net 301)
	)
	(segment
		(start 106.3 93.3)
		(end 104.4 95.2)
		(width 0.15)
		(layer "F.Cu")
		(net 301)
	)
	(segment
		(start 109.265686 92.5)
		(end 110.113052 92.5)
		(width 0.15)
		(layer "F.Cu")
		(net 301)
	)
	(segment
		(start 110.681906 93.068854)
		(end 110.768854 93.068854)
		(width 0.15)
		(layer "F.Cu")
		(net 301)
	)
	(segment
		(start 110.8 93.1)
		(end 110.8 94.6)
		(width 0.15)
		(layer "F.Cu")
		(net 301)
	)
	(segment
		(start 110.768854 93.068854)
		(end 110.8 93.1)
		(width 0.15)
		(layer "F.Cu")
		(net 301)
	)
	(segment
		(start 110.113052 92.5)
		(end 110.681906 93.068854)
		(width 0.15)
		(layer "F.Cu")
		(net 301)
	)
	(segment
		(start 106.29 92.14)
		(end 106.29 92.89)
		(width 0.15)
		(layer "F.Cu")
		(net 301)
	)
	(segment
		(start 106.2508 90.4)
		(end 106.2508 92.1008)
		(width 0.15)
		(layer "F.Cu")
		(net 301)
	)
	(segment
		(start 109.165686 92.6)
		(end 109.265686 92.5)
		(width 0.15)
		(layer "F.Cu")
		(net 301)
	)
	(segment
		(start 106.29 92.89)
		(end 106.7 93.3)
		(width 0.15)
		(layer "F.Cu")
		(net 301)
	)
	(via
		(at 104.4 95.2)
		(size 0.45)
		(drill 0.2)
		(layers "F.Cu" "B.Cu")
		(net 301)
	)
	(segment
		(start 104.19 96.315)
		(end 104.19 95.41)
		(width 0.15)
		(layer "B.Cu")
		(net 301)
	)
	(segment
		(start 104.19 95.41)
		(end 104.4 95.2)
		(width 0.15)
		(layer "B.Cu")
		(net 301)
	)
	(segment
		(start 132.18 120.125)
		(end 132.18 118.68)
		(width 0.15)
		(layer "F.Cu")
		(net 302)
	)
	(segment
		(start 131.75 118.25)
		(end 131.75 117.235)
		(width 0.15)
		(layer "F.Cu")
		(net 302)
	)
	(segment
		(start 132.18 118.68)
		(end 131.75 118.25)
		(width 0.15)
		(layer "F.Cu")
		(net 302)
	)
	(segment
		(start 110 94)
		(end 109.8 93.8)
		(width 0.15)
		(layer "F.Cu")
		(net 303)
	)
	(segment
		(start 105.02 98.0308)
		(end 104.3508 98.7)
		(width 0.15)
		(layer "F.Cu")
		(net 303)
	)
	(segment
		(start 110 94.6)
		(end 110 94)
		(width 0.15)
		(layer "F.Cu")
		(net 303)
	)
	(segment
		(start 105.02 97.07)
		(end 105.02 98.0308)
		(width 0.15)
		(layer "F.Cu")
		(net 303)
	)
	(segment
		(start 106.732382 93.8)
		(end 104.932882 95.5995)
		(width 0.15)
		(layer "F.Cu")
		(net 303)
	)
	(segment
		(start 105.02 95.686618)
		(end 104.932882 95.5995)
		(width 0.15)
		(layer "F.Cu")
		(net 303)
	)
	(segment
		(start 109.8 93.8)
		(end 106.732382 93.8)
		(width 0.15)
		(layer "F.Cu")
		(net 303)
	)
	(segment
		(start 105.02 97.07)
		(end 105.02 95.686618)
		(width 0.15)
		(layer "F.Cu")
		(net 303)
	)
	(via
		(at 104.932882 95.5995)
		(size 0.45)
		(drill 0.2)
		(layers "F.Cu" "B.Cu")
		(remove_unused_layers yes)
		(keep_end_layers yes)
		(zone_layer_connections)
		(net 303)
	)
	(segment
		(start 105.19 95.856618)
		(end 104.932882 95.5995)
		(width 0.15)
		(layer "B.Cu")
		(net 303)
	)
	(segment
		(start 105.19 96.315)
		(end 105.19 95.856618)
		(width 0.15)
		(layer "B.Cu")
		(net 303)
	)
	(segment
		(start 153.83 66.05)
		(end 154.93 66.05)
		(width 0.3)
		(layer "F.Cu")
		(net 304)
	)
	(segment
		(start 154.93 66.05)
		(end 155.13 66.25)
		(width 0.3)
		(layer "F.Cu")
		(net 304)
	)
	(segment
		(start 155.13 66.25)
		(end 155.13 67)
		(width 0.3)
		(layer "F.Cu")
		(net 304)
	)
	(via
		(at 157.69 68.5)
		(size 0.45)
		(drill 0.2)
		(layers "F.Cu" "B.Cu")
		(remove_unused_layers yes)
		(keep_end_layers yes)
		(free yes)
		(zone_layer_connections)
		(net 304)
	)
	(via
		(at 156.49 68.5)
		(size 0.45)
		(drill 0.2)
		(layers "F.Cu" "B.Cu")
		(remove_unused_layers yes)
		(keep_end_layers yes)
		(free yes)
		(zone_layer_connections)
		(net 304)
	)
	(via
		(at 153.83 66.05)
		(size 0.45)
		(drill 0.2)
		(layers "F.Cu" "B.Cu")
		(remove_unused_layers yes)
		(keep_end_layers yes)
		(zone_layer_connections)
		(net 304)
	)
	(via
		(at 157.09 69.3)
		(size 0.45)
		(drill 0.2)
		(layers "F.Cu" "B.Cu")
		(remove_unused_layers yes)
		(keep_end_layers yes)
		(free yes)
		(zone_layer_connections)
		(net 304)
	)
	(via
		(at 157.69 70.1)
		(size 0.45)
		(drill 0.2)
		(layers "F.Cu" "B.Cu")
		(remove_unused_layers yes)
		(keep_end_layers yes)
		(free yes)
		(zone_layer_connections)
		(net 304)
	)
	(via
		(at 156.49 70.1)
		(size 0.45)
		(drill 0.2)
		(layers "F.Cu" "B.Cu")
		(remove_unused_layers yes)
		(keep_end_layers yes)
		(free yes)
		(zone_layer_connections)
		(net 304)
	)
	(segment
		(start 153.48 64.8)
		(end 153.48 65.7)
		(width 0.3)
		(layer "B.Cu")
		(net 304)
	)
	(segment
		(start 153.48 65.7)
		(end 153.83 66.05)
		(width 0.3)
		(layer "B.Cu")
		(net 304)
	)
	(segment
		(start 159.5792 74.8992)
		(end 159.58 74.9)
		(width 0.15)
		(layer "F.Cu")
		(net 305)
	)
	(segment
		(start 158.83 74.8992)
		(end 159.5792 74.8992)
		(width 0.15)
		(layer "F.Cu")
		(net 305)
	)
	(via
		(at 159.58 74.9)
		(size 0.45)
		(drill 0.2)
		(layers "F.Cu" "B.Cu")
		(remove_unused_layers yes)
		(keep_end_layers yes)
		(zone_layer_connections)
		(net 305)
	)
	(segment
		(start 161.205 74.9)
		(end 159.58 74.9)
		(width 0.3)
		(layer "B.Cu")
		(net 305)
	)
	(segment
		(start 159.58 74.9)
		(end 157.89 74.9)
		(width 0.3)
		(layer "B.Cu")
		(net 305)
	)
	(segment
		(start 157.89 74.9)
		(end 157.39 74.4)
		(width 0.3)
		(layer "B.Cu")
		(net 305)
	)
	(segment
		(start 157.39 74.4)
		(end 157.39 73.3)
		(width 0.3)
		(layer "B.Cu")
		(net 305)
	)
	(segment
		(start 108.09 92.1)
		(end 107.6 92.1)
		(width 0.15)
		(layer "F.Cu")
		(net 306)
	)
	(segment
		(start 107.56 92.14)
		(end 107.56 90.456084)
		(width 0.15)
		(layer "F.Cu")
		(net 306)
	)
	(segment
		(start 108.19 92.9)
		(end 108.19 92.2)
		(width 0.15)
		(layer "F.Cu")
		(net 306)
	)
	(segment
		(start 108.19 92.2)
		(end 108.09 92.1)
		(width 0.15)
		(layer "F.Cu")
		(net 306)
	)
	(via
		(at 108.19 92.9)
		(size 0.45)
		(drill 0.2)
		(layers "F.Cu" "B.Cu")
		(remove_unused_layers yes)
		(keep_end_layers yes)
		(zone_layer_connections)
		(net 306)
	)
	(segment
		(start 107.1 95.632843)
		(end 106.865686 95.867157)
		(width 0.15)
		(layer "B.Cu")
		(net 306)
	)
	(segment
		(start 106.485 96.315)
		(end 106.19 96.315)
		(width 0.15)
		(layer "B.Cu")
		(net 306)
	)
	(segment
		(start 106.865686 95.867157)
		(end 106.865686 95.934314)
		(width 0.15)
		(layer "B.Cu")
		(net 306)
	)
	(segment
		(start 107.575 92.285)
		(end 108.19 92.9)
		(width 0.15)
		(layer "B.Cu")
		(net 306)
	)
	(segment
		(start 106.865686 95.934314)
		(end 106.485 96.315)
		(width 0.15)
		(layer "B.Cu")
		(net 306)
	)
	(segment
		(start 105.89 92.285)
		(end 107.575 92.285)
		(width 0.15)
		(layer "B.Cu")
		(net 306)
	)
	(segment
		(start 108.19 92.9)
		(end 107.1 93.99)
		(width 0.15)
		(layer "B.Cu")
		(net 306)
	)
	(segment
		(start 107.1 93.99)
		(end 107.1 95.632843)
		(width 0.15)
		(layer "B.Cu")
		(net 306)
	)
	(segment
		(start 159.23 87.25)
		(end 160.3 87.25)
		(width 0.15)
		(layer "F.Cu")
		(net 307)
	)
	(segment
		(start 161.15 87.83)
		(end 161.38 87.6)
		(width 0.15)
		(layer "F.Cu")
		(net 307)
	)
	(segment
		(start 160.65 87.6)
		(end 161.38 87.6)
		(width 0.15)
		(layer "F.Cu")
		(net 307)
	)
	(segment
		(start 160.6 92.05)
		(end 161.15 91.5)
		(width 0.15)
		(layer "F.Cu")
		(net 307)
	)
	(segment
		(start 156.25 87.22)
		(end 156.25 87.24)
		(width 0.15)
		(layer "F.Cu")
		(net 307)
	)
	(segment
		(start 123.099999 93.5)
		(end 123.099999 93.482514)
		(width 0.15)
		(layer "F.Cu")
		(net 307)
	)
	(segment
		(start 157.03 87.95)
		(end 158.53 87.95)
		(width 0.15)
		(layer "F.Cu")
		(net 307)
	)
	(segment
		(start 160.3 87.25)
		(end 160.65 87.6)
		(width 0.15)
		(layer "F.Cu")
		(net 307)
	)
	(segment
		(start 156.25 87.24)
		(end 156.96 87.95)
		(width 0.15)
		(layer "F.Cu")
		(net 307)
	)
	(segment
		(start 158.53 87.95)
		(end 159.23 87.25)
		(width 0.15)
		(layer "F.Cu")
		(net 307)
	)
	(segment
		(start 161.15 91.5)
		(end 161.15 87.83)
		(width 0.15)
		(layer "F.Cu")
		(net 307)
	)
	(segment
		(start 123.099999 93.482514)
		(end 123.5 93.082513)
		(width 0.15)
		(layer "F.Cu")
		(net 307)
	)
	(via
		(at 123.25 106.95)
		(size 0.45)
		(drill 0.2)
		(layers "F.Cu" "B.Cu")
		(remove_unused_layers yes)
		(keep_end_layers yes)
		(zone_layer_connections)
		(net 307)
	)
	(via
		(at 123.099999 93.5)
		(size 0.45)
		(drill 0.2)
		(layers "F.Cu" "B.Cu")
		(remove_unused_layers yes)
		(keep_end_layers yes)
		(free yes)
		(zone_layer_connections)
		(net 307)
	)
	(via
		(at 156.25 87.22)
		(size 0.45)
		(drill 0.2)
		(layers "F.Cu" "B.Cu")
		(remove_unused_layers yes)
		(keep_end_layers yes)
		(zone_layer_connections)
		(net 307)
	)
	(segment
		(start 130.67 112.34)
		(end 135.56 107.45)
		(width 0.15)
		(layer "B.Cu")
		(net 307)
	)
	(segment
		(start 135.56 105.19)
		(end 138.3 102.45)
		(width 0.15)
		(layer "B.Cu")
		(net 307)
	)
	(segment
		(start 128.7 112.34)
		(end 130.67 112.34)
		(width 0.15)
		(layer "B.Cu")
		(net 307)
	)
	(segment
		(start 150.95 94.132549)
		(end 150.95 90.2)
		(width 0.15)
		(layer "B.Cu")
		(net 307)
	)
	(segment
		(start 153.93 87.22)
		(end 156.25 87.22)
		(width 0.15)
		(layer "B.Cu")
		(net 307)
	)
	(segment
		(start 142.632549 102.45)
		(end 150.95 94.132549)
		(width 0.15)
		(layer "B.Cu")
		(net 307)
	)
	(segment
		(start 123.25 106.95)
		(end 128.7 112.34)
		(width 0.15)
		(layer "B.Cu")
		(net 307)
	)
	(segment
		(start 135.56 107.45)
		(end 135.56 105.19)
		(width 0.15)
		(layer "B.Cu")
		(net 307)
	)
	(segment
		(start 150.95 90.2)
		(end 153.93 87.22)
		(width 0.15)
		(layer "B.Cu")
		(net 307)
	)
	(segment
		(start 138.3 102.45)
		(end 142.632549 102.45)
		(width 0.15)
		(layer "B.Cu")
		(net 307)
	)
	(segment
		(start 121.2 104.84)
		(end 122.58 106.22)
		(width 0.125)
		(layer "In6.Cu")
		(net 307)
	)
	(segment
		(start 123.099999 97.500001)
		(end 121.2 99.4)
		(width 0.125)
		(layer "In6.Cu")
		(net 307)
	)
	(segment
		(start 121.2 99.4)
		(end 121.2 104.84)
		(width 0.125)
		(layer "In6.Cu")
		(net 307)
	)
	(segment
		(start 122.58 106.22)
		(end 123.25 106.95)
		(width 0.15)
		(layer "In6.Cu")
		(net 307)
	)
	(segment
		(start 123.099999 93.5)
		(end 123.099999 97.500001)
		(width 0.125)
		(layer "In6.Cu")
		(net 307)
	)
	(segment
		(start 109.88 100.825)
		(end 108.615 100.825)
		(width 0.15)
		(layer "F.Cu")
		(net 308)
	)
	(segment
		(start 110.305 100.4)
		(end 109.88 100.825)
		(width 0.15)
		(layer "F.Cu")
		(net 308)
	)
	(segment
		(start 109.97 105.375)
		(end 108.615 105.375)
		(width 0.15)
		(layer "F.Cu")
		(net 309)
	)
	(segment
		(start 162.44 78.85)
		(end 161.84 78.85)
		(width 0.3)
		(layer "F.Cu")
		(net 310)
	)
	(segment
		(start 160.99 76.6)
		(end 161.74 75.85)
		(width 0.3)
		(layer "F.Cu")
		(net 310)
	)
	(segment
		(start 160.99 78)
		(end 160.99 76.6)
		(width 0.3)
		(layer "F.Cu")
		(net 310)
	)
	(segment
		(start 169.19 77.72)
		(end 169.2 77.73)
		(width 0.3)
		(layer "F.Cu")
		(net 310)
	)
	(segment
		(start 169.53 72.65)
		(end 168.44 72.65)
		(width 0.3)
		(layer "F.Cu")
		(net 310)
	)
	(segment
		(start 169.19 77.21)
		(end 169.19 77.72)
		(width 0.3)
		(layer "F.Cu")
		(net 310)
	)
	(segment
		(start 161.74 75.85)
		(end 167.83 75.85)
		(width 0.3)
		(layer "F.Cu")
		(net 310)
	)
	(segment
		(start 167.83 75.85)
		(end 169.19 77.21)
		(width 0.3)
		(layer "F.Cu")
		(net 310)
	)
	(segment
		(start 168.19 72.9)
		(end 168.19 75.49)
		(width 0.3)
		(layer "F.Cu")
		(net 310)
	)
	(segment
		(start 161.84 78.85)
		(end 160.99 78)
		(width 0.3)
		(layer "F.Cu")
		(net 310)
	)
	(segment
		(start 168.19 75.49)
		(end 167.83 75.85)
		(width 0.3)
		(layer "F.Cu")
		(net 310)
	)
	(segment
		(start 168.44 72.65)
		(end 168.19 72.9)
		(width 0.3)
		(layer "F.Cu")
		(net 310)
	)
	(segment
		(start 155.28 61.3)
		(end 155.28 62.505)
		(width 0.15)
		(layer "F.Cu")
		(net 311)
	)
	(segment
		(start 155.33 61.25)
		(end 155.28 61.3)
		(width 0.15)
		(layer "F.Cu")
		(net 311)
	)
	(via
		(at 155.33 61.25)
		(size 0.45)
		(drill 0.2)
		(layers "F.Cu" "B.Cu")
		(remove_unused_layers yes)
		(keep_end_layers yes)
		(zone_layer_connections)
		(net 311)
	)
	(segment
		(start 155.33 61.25)
		(end 155.33 60.735)
		(width 0.3)
		(layer "B.Cu")
		(net 311)
	)
	(segment
		(start 166.69 75.5)
		(end 167.69 74.5)
		(width 0.15)
		(layer "F.Cu")
		(net 312)
	)
	(segment
		(start 160.89 75.5)
		(end 166.69 75.5)
		(width 0.15)
		(layer "F.Cu")
		(net 312)
	)
	(segment
		(start 159.69 78.2)
		(end 160.39 77.5)
		(width 0.15)
		(layer "F.Cu")
		(net 312)
	)
	(segment
		(start 160.39 76)
		(end 160.89 75.5)
		(width 0.15)
		(layer "F.Cu")
		(net 312)
	)
	(segment
		(start 160.39 77.5)
		(end 160.39 76)
		(width 0.15)
		(layer "F.Cu")
		(net 312)
	)
	(segment
		(start 168.44 71.65)
		(end 169.53 71.65)
		(width 0.15)
		(layer "F.Cu")
		(net 312)
	)
	(segment
		(start 158.99 78.2)
		(end 159.69 78.2)
		(width 0.15)
		(layer "F.Cu")
		(net 312)
	)
	(segment
		(start 167.69 74.5)
		(end 167.69 72.4)
		(width 0.15)
		(layer "F.Cu")
		(net 312)
	)
	(segment
		(start 167.69 72.4)
		(end 168.44 71.65)
		(width 0.15)
		(layer "F.Cu")
		(net 312)
	)
	(segment
		(start 168.34 70.65)
		(end 169.53 70.65)
		(width 0.15)
		(layer "F.Cu")
		(net 313)
	)
	(segment
		(start 166.89 72.1)
		(end 168.34 70.65)
		(width 0.15)
		(layer "F.Cu")
		(net 313)
	)
	(segment
		(start 166.89 74.5)
		(end 166.89 72.1)
		(width 0.15)
		(layer "F.Cu")
		(net 313)
	)
	(segment
		(start 158.99 76.6)
		(end 160.49 75.1)
		(width 0.15)
		(layer "F.Cu")
		(net 313)
	)
	(segment
		(start 160.49 75.1)
		(end 166.29 75.1)
		(width 0.15)
		(layer "F.Cu")
		(net 313)
	)
	(segment
		(start 166.29 75.1)
		(end 166.89 74.5)
		(width 0.15)
		(layer "F.Cu")
		(net 313)
	)
	(segment
		(start 159.89 79.3)
		(end 159.89 79)
		(width 0.15)
		(layer "F.Cu")
		(net 314)
	)
	(segment
		(start 161.79 79.8)
		(end 164.09 79.8)
		(width 0.15)
		(layer "F.Cu")
		(net 314)
	)
	(segment
		(start 165.29 79.4)
		(end 164.79 78.9)
		(width 0.15)
		(layer "F.Cu")
		(net 314)
	)
	(segment
		(start 159.49 79.7)
		(end 159.89 79.3)
		(width 0.15)
		(layer "F.Cu")
		(net 314)
	)
	(segment
		(start 160.79 78.8)
		(end 161.79 79.8)
		(width 0.15)
		(layer "F.Cu")
		(net 314)
	)
	(segment
		(start 164.34 79.55)
		(end 164.34 78.85)
		(width 0.15)
		(layer "F.Cu")
		(net 314)
	)
	(segment
		(start 159.89 79)
		(end 160.09 78.8)
		(width 0.15)
		(layer "F.Cu")
		(net 314)
	)
	(segment
		(start 158.99 79.7)
		(end 159.49 79.7)
		(width 0.15)
		(layer "F.Cu")
		(net 314)
	)
	(segment
		(start 166.9392 79.4)
		(end 165.29 79.4)
		(width 0.15)
		(layer "F.Cu")
		(net 314)
	)
	(segment
		(start 164.09 79.8)
		(end 164.34 79.55)
		(width 0.15)
		(layer "F.Cu")
		(net 314)
	)
	(segment
		(start 160.09 78.8)
		(end 160.79 78.8)
		(width 0.15)
		(layer "F.Cu")
		(net 314)
	)
	(segment
		(start 164.79 78.9)
		(end 164.39 78.9)
		(width 0.15)
		(layer "F.Cu")
		(net 314)
	)
	(segment
		(start 163.69 82.7)
		(end 164.34 82.05)
		(width 0.15)
		(layer "F.Cu")
		(net 315)
	)
	(segment
		(start 158.99 81.2)
		(end 158.99 82.7)
		(width 0.15)
		(layer "F.Cu")
		(net 315)
	)
	(segment
		(start 173.955 79.875)
		(end 173.83 79.75)
		(width 0.15)
		(layer "F.Cu")
		(net 315)
	)
	(segment
		(start 167.29 124)
		(end 172.49 124)
		(width 0.15)
		(layer "F.Cu")
		(net 315)
	)
	(segment
		(start 158.99 82.7)
		(end 163.69 82.7)
		(width 0.15)
		(layer "F.Cu")
		(net 315)
	)
	(segment
		(start 173.955 87.813908)
		(end 173.955 79.875)
		(width 0.15)
		(layer "F.Cu")
		(net 315)
	)
	(segment
		(start 168.83 79.75)
		(end 167.43 81.15)
		(width 0.15)
		(layer "F.Cu")
		(net 315)
	)
	(segment
		(start 173.28 123.21)
		(end 173.28 88.488908)
		(width 0.15)
		(layer "F.Cu")
		(net 315)
	)
	(segment
		(start 164.33 123.75)
		(end 167.04 123.75)
		(width 0.15)
		(layer "F.Cu")
		(net 315)
	)
	(segment
		(start 172.49 124)
		(end 173.28 123.21)
		(width 0.15)
		(layer "F.Cu")
		(net 315)
	)
	(segment
		(start 173.83 79.75)
		(end 168.83 79.75)
		(width 0.15)
		(layer "F.Cu")
		(net 315)
	)
	(segment
		(start 164.34 82.05)
		(end 164.34 81.15)
		(width 0.15)
		(layer "F.Cu")
		(net 315)
	)
	(segment
		(start 167.43 81.15)
		(end 164.34 81.15)
		(width 0.15)
		(layer "F.Cu")
		(net 315)
	)
	(segment
		(start 167.04 123.75)
		(end 167.29 124)
		(width 0.15)
		(layer "F.Cu")
		(net 315)
	)
	(segment
		(start 173.28 88.488908)
		(end 173.955 87.813908)
		(width 0.15)
		(layer "F.Cu")
		(net 315)
	)
	(segment
		(start 108.615 101.475)
		(end 110.23 101.475)
		(width 0.15)
		(layer "F.Cu")
		(net 316)
	)
	(segment
		(start 131.68 119.18)
		(end 130.75 118.25)
		(width 0.15)
		(layer "F.Cu")
		(net 323)
	)
	(segment
		(start 131.68 120.125)
		(end 131.68 119.18)
		(width 0.15)
		(layer "F.Cu")
		(net 323)
	)
	(segment
		(start 130.75 118.25)
		(end 130.75 117.235)
		(width 0.15)
		(layer "F.Cu")
		(net 323)
	)
	(segment
		(start 109 92.2)
		(end 109 91.4408)
		(width 0.15)
		(layer "F.Cu")
		(net 324)
	)
	(segment
		(start 108.906084 90.316084)
		(end 108.39 90.316084)
		(width 0.15)
		(layer "F.Cu")
		(net 324)
	)
	(segment
		(start 109.4 95.6)
		(end 109.1 95.6)
		(width 0.15)
		(layer "F.Cu")
		(net 324)
	)
	(segment
		(start 109.1408 90.5508)
		(end 108.906084 90.316084)
		(width 0.15)
		(layer "F.Cu")
		(net 324)
	)
	(segment
		(start 109.1 95.6)
		(end 108.6 95.1)
		(width 0.15)
		(layer "F.Cu")
		(net 324)
	)
	(segment
		(start 109.1408 91.3)
		(end 109.1408 90.5508)
		(width 0.15)
		(layer "F.Cu")
		(net 324)
	)
	(via
		(at 109 92.2)
		(size 0.45)
		(drill 0.2)
		(layers "F.Cu" "B.Cu")
		(net 324)
	)
	(via
		(at 108.6 95.1)
		(size 0.45)
		(drill 0.2)
		(layers "F.Cu" "B.Cu")
		(net 324)
	)
	(segment
		(start 108.6 95.1)
		(end 108.6 92.6)
		(width 0.15)
		(layer "B.Cu")
		(net 324)
	)
	(segment
		(start 108.6 92.6)
		(end 109 92.2)
		(width 0.15)
		(layer "B.Cu")
		(net 324)
	)
	(segment
		(start 155.090498 65.585)
		(end 156.69 65.585)
		(width 0.3)
		(layer "F.Cu")
		(net 325)
	)
	(segment
		(start 154.98 65.474502)
		(end 155.090498 65.585)
		(width 0.3)
		(layer "F.Cu")
		(net 325)
	)
	(via
		(at 152.25 81.5)
		(size 0.45)
		(drill 0.2)
		(layers "F.Cu" "B.Cu")
		(remove_unused_layers yes)
		(keep_end_layers yes)
		(zone_layer_connections)
		(net 325)
	)
	(via
		(at 154.98 65.474502)
		(size 0.45)
		(drill 0.2)
		(layers "F.Cu" "B.Cu")
		(remove_unused_layers yes)
		(keep_end_layers yes)
		(zone_layer_connections)
		(net 325)
	)
	(segment
		(start 156.08 67.3)
		(end 157.68 67.3)
		(width 0.3)
		(layer "B.Cu")
		(net 325)
	)
	(segment
		(start 149.25 85.5)
		(end 149.5 85.25)
		(width 0.3)
		(layer "B.Cu")
		(net 325)
	)
	(segment
		(start 150.515 84.235)
		(end 152.25 82.5)
		(width 0.3)
		(layer "B.Cu")
		(net 325)
	)
	(segment
		(start 154.98 65.474502)
		(end 154.98 66.7)
		(width 0.3)
		(layer "B.Cu")
		(net 325)
	)
	(segment
		(start 148.75 85.5)
		(end 149.25 85.5)
		(width 0.3)
		(layer "B.Cu")
		(net 325)
	)
	(segment
		(start 148.175 84.925)
		(end 148.75 85.5)
		(width 0.3)
		(layer "B.Cu")
		(net 325)
	)
	(segment
		(start 147.55 84.925)
		(end 148.175 84.925)
		(width 0.3)
		(layer "B.Cu")
		(net 325)
	)
	(segment
		(start 152.25 82.5)
		(end 152.25 81.5)
		(width 0.3)
		(layer "B.Cu")
		(net 325)
	)
	(segment
		(start 149.5 85.25)
		(end 149.5 84.235)
		(width 0.3)
		(layer "B.Cu")
		(net 325)
	)
	(segment
		(start 155.48 66.7)
		(end 156.08 67.3)
		(width 0.3)
		(layer "B.Cu")
		(net 325)
	)
	(segment
		(start 154.98 66.7)
		(end 155.48 66.7)
		(width 0.3)
		(layer "B.Cu")
		(net 325)
	)
	(segment
		(start 149.5 84.235)
		(end 150.515 84.235)
		(width 0.3)
		(layer "B.Cu")
		(net 325)
	)
	(segment
		(start 155 67.25)
		(end 152.25 70)
		(width 0.3)
		(layer "In2.Cu")
		(net 325)
	)
	(segment
		(start 152.25 70)
		(end 152.25 81.5)
		(width 0.3)
		(layer "In2.Cu")
		(net 325)
	)
	(segment
		(start 154.98 65.474502)
		(end 155 65.494502)
		(width 0.3)
		(layer "In2.Cu")
		(net 325)
	)
	(segment
		(start 155 65.494502)
		(end 155 67.25)
		(width 0.3)
		(layer "In2.Cu")
		(net 325)
	)
	(via
		(at 161.75 110.75)
		(size 0.45)
		(drill 0.2)
		(layers "F.Cu" "B.Cu")
		(remove_unused_layers yes)
		(keep_end_layers yes)
		(free yes)
		(zone_layer_connections "In2.Cu")
		(net 329)
	)
	(via
		(at 165.03 73.65)
		(size 0.45)
		(drill 0.2)
		(layers "F.Cu" "B.Cu")
		(remove_unused_layers yes)
		(keep_end_layers yes)
		(free yes)
		(zone_layer_connections "In2.Cu")
		(net 329)
	)
	(via
		(at 165.53 73.65)
		(size 0.45)
		(drill 0.2)
		(layers "F.Cu" "B.Cu")
		(remove_unused_layers yes)
		(keep_end_layers yes)
		(free yes)
		(zone_layer_connections "In2.Cu")
		(net 329)
	)
	(via
		(at 161.25 110.25)
		(size 0.45)
		(drill 0.2)
		(layers "F.Cu" "B.Cu")
		(remove_unused_layers yes)
		(keep_end_layers yes)
		(free yes)
		(zone_layer_connections "In2.Cu")
		(net 329)
	)
	(via
		(at 164.53 73.65)
		(size 0.45)
		(drill 0.2)
		(layers "F.Cu" "B.Cu")
		(remove_unused_layers yes)
		(keep_end_layers yes)
		(free yes)
		(zone_layer_connections "In2.Cu")
		(net 329)
	)
	(via
		(at 165.28 74.15)
		(size 0.45)
		(drill 0.2)
		(layers "F.Cu" "B.Cu")
		(remove_unused_layers yes)
		(keep_end_layers yes)
		(free yes)
		(zone_layer_connections "In2.Cu")
		(net 329)
	)
	(via
		(at 164.78 74.15)
		(size 0.45)
		(drill 0.2)
		(layers "F.Cu" "B.Cu")
		(remove_unused_layers yes)
		(keep_end_layers yes)
		(free yes)
		(zone_layer_connections "In2.Cu")
		(net 329)
	)
	(via
		(at 160.75 109.75)
		(size 0.45)
		(drill 0.2)
		(layers "F.Cu" "B.Cu")
		(remove_unused_layers yes)
		(keep_end_layers yes)
		(free yes)
		(zone_layer_connections "In2.Cu")
		(net 329)
	)
	(via
		(at 160.25 109.25)
		(size 0.45)
		(drill 0.2)
		(layers "F.Cu" "B.Cu")
		(remove_unused_layers yes)
		(keep_end_layers yes)
		(free yes)
		(zone_layer_connections "In2.Cu")
		(net 329)
	)
	(segment
		(start 159.69 71.4)
		(end 161.49 71.4)
		(width 0.5)
		(layer "B.Cu")
		(net 329)
	)
	(segment
		(start 163.3 73.49)
		(end 163.39 73.49)
		(width 0.5)
		(layer "B.Cu")
		(net 329)
	)
	(segment
		(start 162.175 73.9)
		(end 162.175 74.9)
		(width 0.3)
		(layer "B.Cu")
		(net 329)
	)
	(segment
		(start 163.49 73.3)
		(end 163.3 73.49)
		(width 0.5)
		(layer "B.Cu")
		(net 329)
	)
	(segment
		(start 163.49 72)
		(end 163.49 73.3)
		(width 0.5)
		(layer "B.Cu")
		(net 329)
	)
	(segment
		(start 163.3 73.49)
		(end 162.89 73.9)
		(width 0.5)
		(layer "B.Cu")
		(net 329)
	)
	(segment
		(start 162.89 73.9)
		(end 162.175 73.9)
		(width 0.5)
		(layer "B.Cu")
		(net 329)
	)
	(segment
		(start 162.89 71.4)
		(end 163.49 72)
		(width 0.5)
		(layer "B.Cu")
		(net 329)
	)
	(segment
		(start 161.49 71.4)
		(end 162.89 71.4)
		(width 0.5)
		(layer "B.Cu")
		(net 329)
	)
	(segment
		(start 110.03 102.125)
		(end 108.615 102.125)
		(width 0.15)
		(layer "F.Cu")
		(net 330)
	)
	(segment
		(start 110.305 102.4)
		(end 110.03 102.125)
		(width 0.15)
		(layer "F.Cu")
		(net 330)
	)
	(segment
		(start 149.26 118.74)
		(end 152.76 118.74)
		(width 0.5)
		(layer "F.Cu")
		(net 331)
	)
	(segment
		(start 152.76 118.74)
		(end 153.359 118.141)
		(width 0.5)
		(layer "F.Cu")
		(net 331)
	)
	(segment
		(start 149.025 119.95)
		(end 149.025 118.975)
		(width 0.5)
		(layer "F.Cu")
		(net 331)
	)
	(segment
		(start 149.025 118.975)
		(end 149.26 118.74)
		(width 0.5)
		(layer "F.Cu")
		(net 331)
	)
	(segment
		(start 153.359 115.391)
		(end 153.5 115.25)
		(width 0.5)
		(layer "F.Cu")
		(net 331)
	)
	(segment
		(start 153.359 118.141)
		(end 153.359 115.391)
		(width 0.5)
		(layer "F.Cu")
		(net 331)
	)
	(via
		(at 153.5 115.25)
		(size 0.45)
		(drill 0.2)
		(layers "F.Cu" "B.Cu")
		(remove_unused_layers yes)
		(keep_end_layers yes)
		(zone_layer_connections)
		(net 331)
	)
	(segment
		(start 152.4 114.3425)
		(end 153.3075 115.25)
		(width 0.5)
		(layer "B.Cu")
		(net 331)
	)
	(segment
		(start 153.3075 115.25)
		(end 153.5 115.25)
		(width 0.5)
		(layer "B.Cu")
		(net 331)
	)
	(segment
		(start 152.4 112.72)
		(end 152.4 114.3425)
		(width 0.5)
		(layer "B.Cu")
		(net 331)
	)
	(segment
		(start 118.96 90.7)
		(end 120.3 90.7)
		(width 0.15)
		(layer "F.Cu")
		(net 332)
	)
	(segment
		(start 118.5605 90.3005)
		(end 118.96 90.7)
		(width 0.15)
		(layer "F.Cu")
		(net 332)
	)
	(segment
		(start 150 119.975)
		(end 150 123.5)
		(width 0.15)
		(layer "F.Cu")
		(net 332)
	)
	(segment
		(start 118.19 90.3005)
		(end 118.5605 90.3005)
		(width 0.15)
		(layer "F.Cu")
		(net 332)
	)
	(via
		(at 150 123.5)
		(size 0.45)
		(drill 0.2)
		(layers "F.Cu" "B.Cu")
		(remove_unused_layers yes)
		(keep_end_layers yes)
		(zone_layer_connections)
		(net 332)
	)
	(via
		(at 155 118.75)
		(size 0.45)
		(drill 0.2)
		(layers "F.Cu" "B.Cu")
		(remove_unused_layers yes)
		(keep_end_layers yes)
		(zone_layer_connections)
		(net 332)
	)
	(via
		(at 118.19 90.3005)
		(size 0.45)
		(drill 0.2)
		(layers "F.Cu" "B.Cu")
		(remove_unused_layers yes)
		(keep_end_layers yes)
		(zone_layer_connections)
		(net 332)
	)
	(segment
		(start 149.97 123.53)
		(end 131.203517 123.53)
		(width 0.15)
		(layer "B.Cu")
		(net 332)
	)
	(segment
		(start 131.203517 123.53)
		(end 125.853026 118.179509)
		(width 0.15)
		(layer "B.Cu")
		(net 332)
	)
	(segment
		(start 125.853026 118.179509)
		(end 125.609509 118.179509)
		(width 0.15)
		(layer "B.Cu")
		(net 332)
	)
	(segment
		(start 117.815 110.385)
		(end 117.6 110.17)
		(width 0.125)
		(layer "B.Cu")
		(net 332)
	)
	(segment
		(start 150 123.5)
		(end 149.97 123.53)
		(width 0.15)
		(layer "B.Cu")
		(net 332)
	)
	(segment
		(start 117.6 110.17)
		(end 117.6 90.501)
		(width 0.125)
		(layer "B.Cu")
		(net 332)
	)
	(segment
		(start 125.609509 118.179509)
		(end 117.815 110.385)
		(width 0.15)
		(layer "B.Cu")
		(net 332)
	)
	(segment
		(start 117.8005 90.3005)
		(end 118.19 90.3005)
		(width 0.125)
		(layer "B.Cu")
		(net 332)
	)
	(segment
		(start 117.6 90.501)
		(end 117.8005 90.3005)
		(width 0.125)
		(layer "B.Cu")
		(net 332)
	)
	(segment
		(start 154.94 112.72)
		(end 154.94 118.69)
		(width 0.15)
		(layer "B.Cu")
		(net 332)
	)
	(segment
		(start 154.94 118.69)
		(end 155 118.75)
		(width 0.15)
		(layer "B.Cu")
		(net 332)
	)
	(segment
		(start 150 123.5)
		(end 150 121)
		(width 0.15)
		(layer "In2.Cu")
		(net 332)
	)
	(segment
		(start 152.25 118.75)
		(end 155 118.75)
		(width 0.15)
		(layer "In2.Cu")
		(net 332)
	)
	(segment
		(start 150 121)
		(end 152.25 118.75)
		(width 0.15)
		(layer "In2.Cu")
		(net 332)
	)
	(segment
		(start 121.476765 91.100001)
		(end 121.499999 91.100001)
		(width 0.15)
		(layer "F.Cu")
		(net 333)
	)
	(segment
		(start 151.025 119.95)
		(end 151.025 122.725)
		(width 0.15)
		(layer "F.Cu")
		(net 333)
	)
	(segment
		(start 151.025 122.725)
		(end 150.75 123)
		(width 0.15)
		(layer "F.Cu")
		(net 333)
	)
	(segment
		(start 121.499999 91.100001)
		(end 121.9 90.7)
		(width 0.15)
		(layer "F.Cu")
		(net 333)
	)
	(via
		(at 121.476765 91.100001)
		(size 0.45)
		(drill 0.2)
		(layers "F.Cu" "B.Cu")
		(remove_unused_layers yes)
		(keep_end_layers yes)
		(free yes)
		(zone_layer_connections)
		(net 333)
	)
	(via
		(at 157.25 119.774502)
		(size 0.45)
		(drill 0.2)
		(layers "F.Cu" "B.Cu")
		(remove_unused_layers yes)
		(keep_end_layers yes)
		(zone_layer_connections)
		(net 333)
	)
	(via
		(at 150.75 123)
		(size 0.45)
		(drill 0.2)
		(layers "F.Cu" "B.Cu")
		(remove_unused_layers yes)
		(keep_end_layers yes)
		(free yes)
		(zone_layer_connections)
		(net 333)
	)
	(segment
		(start 120.976764 90.6)
		(end 121.476765 91.100001)
		(width 0.125)
		(layer "B.Cu")
		(net 333)
	)
	(segment
		(start 118.9 92.4)
		(end 118.9 91.8)
		(width 0.125)
		(layer "B.Cu")
		(net 333)
	)
	(segment
		(start 157.48 119.544502)
		(end 157.25 119.774502)
		(width 0.15)
		(layer "B.Cu")
		(net 333)
	)
	(segment
		(start 118.79 108.7)
		(end 118.4 108.31)
		(width 0.125)
		(layer "B.Cu")
		(net 333)
	)
	(segment
		(start 118.4 92.9)
		(end 118.9 92.4)
		(width 0.125)
		(layer "B.Cu")
		(net 333)
	)
	(segment
		(start 120.1 90.6)
		(end 120.976764 90.6)
		(width 0.125)
		(layer "B.Cu")
		(net 333)
	)
	(segment
		(start 133.13 123)
		(end 127.941483 117.811483)
		(width 0.15)
		(layer "B.Cu")
		(net 333)
	)
	(segment
		(start 127.901483 117.811483)
		(end 118.79 108.7)
		(width 0.15)
		(layer "B.Cu")
		(net 333)
	)
	(segment
		(start 157.48 112.72)
		(end 157.48 119.544502)
		(width 0.15)
		(layer "B.Cu")
		(net 333)
	)
	(segment
		(start 150.75 123)
		(end 133.13 123)
		(width 0.15)
		(layer "B.Cu")
		(net 333)
	)
	(segment
		(start 118.4 108.31)
		(end 118.4 92.9)
		(width 0.125)
		(layer "B.Cu")
		(net 333)
	)
	(segment
		(start 118.9 91.8)
		(end 120.1 90.6)
		(width 0.125)
		(layer "B.Cu")
		(net 333)
	)
	(segment
		(start 127.941483 117.811483)
		(end 127.901483 117.811483)
		(width 0.15)
		(layer "B.Cu")
		(net 333)
	)
	(segment
		(start 152.67 119.58)
		(end 157.055498 119.58)
		(width 0.15)
		(layer "In2.Cu")
		(net 333)
	)
	(segment
		(start 150.75 121.5)
		(end 152.67 119.58)
		(width 0.15)
		(layer "In2.Cu")
		(net 333)
	)
	(segment
		(start 157.055498 119.58)
		(end 157.25 119.774502)
		(width 0.15)
		(layer "In2.Cu")
		(net 333)
	)
	(segment
		(start 150.75 123)
		(end 150.75 121.5)
		(width 0.15)
		(layer "In2.Cu")
		(net 333)
	)
	(segment
		(start 121.09 90.7)
		(end 120.69 91.1)
		(width 0.15)
		(layer "F.Cu")
		(net 334)
	)
	(segment
		(start 152 119.975)
		(end 152 122.5)
		(width 0.15)
		(layer "F.Cu")
		(net 334)
	)
	(via
		(at 120.69 91.1)
		(size 0.45)
		(drill 0.2)
		(layers "F.Cu" "B.Cu")
		(remove_unused_layers yes)
		(keep_end_layers yes)
		(free yes)
		(zone_layer_connections)
		(net 334)
	)
	(via
		(at 160.098071 119.774502)
		(size 0.45)
		(drill 0.2)
		(layers "F.Cu" "B.Cu")
		(remove_unused_layers yes)
		(keep_end_layers yes)
		(zone_layer_connections)
		(net 334)
	)
	(via
		(at 152 122.5)
		(size 0.45)
		(drill 0.2)
		(layers "F.Cu" "B.Cu")
		(remove_unused_layers yes)
		(keep_end_layers yes)
		(zone_layer_connections)
		(net 334)
	)
	(segment
		(start 118.8 93.5)
		(end 119.8 92.5)
		(width 0.125)
		(layer "B.Cu")
		(net 334)
	)
	(segment
		(start 119.8 91.9)
		(end 120.6 91.1)
		(width 0.125)
		(layer "B.Cu")
		(net 334)
	)
	(segment
		(start 119.8 92.5)
		(end 119.8 91.9)
		(width 0.125)
		(layer "B.Cu")
		(net 334)
	)
	(segment
		(start 119.13 106.94)
		(end 118.8 106.61)
		(width 0.125)
		(layer "B.Cu")
		(net 334)
	)
	(segment
		(start 160.02 112.72)
		(end 160.02 119.696431)
		(width 0.15)
		(layer "B.Cu")
		(net 334)
	)
	(segment
		(start 120.6 91.1)
		(end 120.69 91.1)
		(width 0.125)
		(layer "B.Cu")
		(net 334)
	)
	(segment
		(start 135.195686 122.55)
		(end 151.95 122.55)
		(width 0.125)
		(layer "B.Cu")
		(net 334)
	)
	(segment
		(start 160.02 119.696431)
		(end 160.098071 119.774502)
		(width 0.15)
		(layer "B.Cu")
		(net 334)
	)
	(segment
		(start 134.74 122.55)
		(end 119.13 106.94)
		(width 0.15)
		(layer "B.Cu")
		(net 334)
	)
	(segment
		(start 135.195686 122.55)
		(end 134.74 122.55)
		(width 0.15)
		(layer "B.Cu")
		(net 334)
	)
	(segment
		(start 151.95 122.55)
		(end 152 122.5)
		(width 0.125)
		(layer "B.Cu")
		(net 334)
	)
	(segment
		(start 118.8 106.61)
		(end 118.8 93.5)
		(width 0.125)
		(layer "B.Cu")
		(net 334)
	)
	(segment
		(start 153.25 120.5)
		(end 157.5 120.5)
		(width 0.15)
		(layer "In2.Cu")
		(net 334)
	)
	(segment
		(start 157.5 120.5)
		(end 158.5 119.5)
		(width 0.15)
		(layer "In2.Cu")
		(net 334)
	)
	(segment
		(start 159.823569 119.5)
		(end 160.098071 119.774502)
		(width 0.15)
		(layer "In2.Cu")
		(net 334)
	)
	(segment
		(start 152 122.5)
		(end 152 121.75)
		(width 0.15)
		(layer "In2.Cu")
		(net 334)
	)
	(segment
		(start 152 121.75)
		(end 153.25 120.5)
		(width 0.15)
		(layer "In2.Cu")
		(net 334)
	)
	(segment
		(start 158.5 119.5)
		(end 159.823569 119.5)
		(width 0.15)
		(layer "In2.Cu")
		(net 334)
	)
	(segment
		(start 153.5 122)
		(end 160.25 122)
		(width 0.15)
		(layer "F.Cu")
		(net 335)
	)
	(segment
		(start 153.025 119.95)
		(end 153.025 121.525)
		(width 0.15)
		(layer "F.Cu")
		(net 335)
	)
	(segment
		(start 120.87 89.9)
		(end 121.1 89.9)
		(width 0.15)
		(layer "F.Cu")
		(net 335)
	)
	(segment
		(start 153.025 121.525)
		(end 153.5 122)
		(width 0.15)
		(layer "F.Cu")
		(net 335)
	)
	(segment
		(start 153.5 122.5)
		(end 153.5 122)
		(width 0.15)
		(layer "F.Cu")
		(net 335)
	)
	(segment
		(start 120.4695 90.3005)
		(end 120.87 89.9)
		(width 0.15)
		(layer "F.Cu")
		(net 335)
	)
	(segment
		(start 160.25 122)
		(end 162 123.75)
		(width 0.15)
		(layer "F.Cu")
		(net 335)
	)
	(segment
		(start 162 123.75)
		(end 162.93 123.75)
		(width 0.15)
		(layer "F.Cu")
		(net 335)
	)
	(segment
		(start 119.56 90.3005)
		(end 120.4695 90.3005)
		(width 0.15)
		(layer "F.Cu")
		(net 335)
	)
	(via
		(at 162 119.5)
		(size 0.45)
		(drill 0.2)
		(layers "F.Cu" "B.Cu")
		(remove_unused_layers yes)
		(keep_end_layers yes)
		(zone_layer_connections)
		(net 335)
	)
	(via
		(at 119.56 90.3005)
		(size 0.45)
		(drill 0.2)
		(layers "F.Cu" "B.Cu")
		(remove_unused_layers yes)
		(keep_end_layers yes)
		(free yes)
		(zone_layer_connections)
		(net 335)
	)
	(via
		(at 153.5 122.5)
		(size 0.45)
		(drill 0.2)
		(layers "F.Cu" "B.Cu")
		(remove_unused_layers yes)
		(keep_end_layers yes)
		(zone_layer_connections)
		(net 335)
	)
	(segment
		(start 117.366267 112.133733)
		(end 117.2 111.967466)
		(width 0.125)
		(layer "B.Cu")
		(net 335)
	)
	(segment
		(start 121.27 119.32)
		(end 124.81 119.32)
		(width 0.15)
		(layer "B.Cu")
		(net 335)
	)
	(segment
		(start 129.59 124.1)
		(end 151.9 124.1)
		(width 0.15)
		(layer "B.Cu")
		(net 335)
	)
	(segment
		(start 162.56 112.72)
		(end 162.56 118.94)
		(width 0.15)
		(layer "B.Cu")
		(net 335)
	)
	(segment
		(start 151.9 124.1)
		(end 153.5 122.5)
		(width 0.15)
		(layer "B.Cu")
		(net 335)
	)
	(segment
		(start 119.1595 89.9)
		(end 119.56 90.3005)
		(width 0.125)
		(layer "B.Cu")
		(net 335)
	)
	(segment
		(start 117.2 111.967466)
		(end 117.2 90.3)
		(width 0.125)
		(layer "B.Cu")
		(net 335)
	)
	(segment
		(start 117.2 90.3)
		(end 117.6 89.9)
		(width 0.125)
		(layer "B.Cu")
		(net 335)
	)
	(segment
		(start 117.366267 112.133733)
		(end 120.41 115.177465)
		(width 0.15)
		(layer "B.Cu")
		(net 335)
	)
	(segment
		(start 120.41 118.46)
		(end 121.27 119.32)
		(width 0.15)
		(layer "B.Cu")
		(net 335)
	)
	(segment
		(start 124.81 119.32)
		(end 129.59 124.1)
		(width 0.15)
		(layer "B.Cu")
		(net 335)
	)
	(segment
		(start 162.56 118.94)
		(end 162 119.5)
		(width 0.15)
		(layer "B.Cu")
		(net 335)
	)
	(segment
		(start 117.6 89.9)
		(end 119.1595 89.9)
		(width 0.125)
		(layer "B.Cu")
		(net 335)
	)
	(segment
		(start 120.41 115.177465)
		(end 120.41 118.46)
		(width 0.15)
		(layer "B.Cu")
		(net 335)
	)
	(segment
		(start 160.25 121.5)
		(end 162 119.75)
		(width 0.15)
		(layer "In2.Cu")
		(net 335)
	)
	(segment
		(start 153.5 122.5)
		(end 154.5 121.5)
		(width 0.15)
		(layer "In2.Cu")
		(net 335)
	)
	(segment
		(start 162 119.75)
		(end 162 119.5)
		(width 0.15)
		(layer "In2.Cu")
		(net 335)
	)
	(segment
		(start 154.5 121.5)
		(end 160.25 121.5)
		(width 0.15)
		(layer "In2.Cu")
		(net 335)
	)
	(segment
		(start 168.4 96.1)
		(end 168.4 95.9)
		(width 0.15)
		(layer "F.Cu")
		(net 336)
	)
	(segment
		(start 168.4 95.9)
		(end 168.1 95.6)
		(width 0.15)
		(layer "F.Cu")
		(net 336)
	)
	(segment
		(start 168.695 96.395)
		(end 168.4 96.1)
		(width 0.15)
		(layer "F.Cu")
		(net 336)
	)
	(segment
		(start 169.6 96.395)
		(end 168.695 96.395)
		(width 0.15)
		(layer "F.Cu")
		(net 336)
	)
	(segment
		(start 168.1 95.6)
		(end 167.685 95.6)
		(width 0.15)
		(layer "F.Cu")
		(net 336)
	)
	(segment
		(start 168.895 95.895)
		(end 168.4 95.4)
		(width 0.15)
		(layer "F.Cu")
		(net 337)
	)
	(segment
		(start 168.4 95.4)
		(end 168.4 94.8)
		(width 0.15)
		(layer "F.Cu")
		(net 337)
	)
	(segment
		(start 169.6 95.895)
		(end 168.895 95.895)
		(width 0.15)
		(layer "F.Cu")
		(net 337)
	)
	(segment
		(start 168.4 94.8)
		(end 168.2 94.6)
		(width 0.15)
		(layer "F.Cu")
		(net 337)
	)
	(segment
		(start 168.2 94.6)
		(end 167.685 94.6)
		(width 0.15)
		(layer "F.Cu")
		(net 337)
	)
	(segment
		(start 168.605 93.395)
		(end 169.6 93.395)
		(width 0.15)
		(layer "F.Cu")
		(net 342)
	)
	(segment
		(start 168.4 93.6)
		(end 168.605 93.395)
		(width 0.15)
		(layer "F.Cu")
		(net 342)
	)
	(segment
		(start 167.685 93.6)
		(end 168.4 93.6)
		(width 0.15)
		(layer "F.Cu")
		(net 342)
	)
	(segment
		(start 128.18 120.125)
		(end 128.18 117.665)
		(width 0.15)
		(layer "F.Cu")
		(net 343)
	)
	(segment
		(start 128.18 117.665)
		(end 127.75 117.235)
		(width 0.15)
		(layer "F.Cu")
		(net 343)
	)
	(segment
		(start 128.68 120.125)
		(end 128.68 117.305)
		(width 0.15)
		(layer "F.Cu")
		(net 344)
	)
	(segment
		(start 129.18 120.125)
		(end 129.18 118.32)
		(width 0.15)
		(layer "F.Cu")
		(net 345)
	)
	(segment
		(start 129.75 117.75)
		(end 129.75 117.235)
		(width 0.15)
		(layer "F.Cu")
		(net 345)
	)
	(segment
		(start 129.18 118.32)
		(end 129.75 117.75)
		(width 0.15)
		(layer "F.Cu")
		(net 345)
	)
	(segment
		(start 132.68 120.125)
		(end 132.68 117.305)
		(width 0.15)
		(layer "F.Cu")
		(net 346)
	)
	(segment
		(start 133.18 120.125)
		(end 133.18 118.67)
		(width 0.15)
		(layer "F.Cu")
		(net 347)
	)
	(segment
		(start 133.75 118.1)
		(end 133.75 117.235)
		(width 0.15)
		(layer "F.Cu")
		(net 347)
	)
	(segment
		(start 133.18 118.67)
		(end 133.75 118.1)
		(width 0.15)
		(layer "F.Cu")
		(net 347)
	)
	(segment
		(start 142.2 85.5)
		(end 142.2 86.95)
		(width 0.3)
		(layer "F.Cu")
		(net 348)
	)
	(segment
		(start 142.2 86.95)
		(end 142.5 87.25)
		(width 0.3)
		(layer "F.Cu")
		(net 348)
	)
	(segment
		(start 141.5 81)
		(end 142.2 81)
		(width 0.3)
		(layer "F.Cu")
		(net 348)
	)
	(segment
		(start 141.5 85.5)
		(end 141.5 81)
		(width 0.3)
		(layer "F.Cu")
		(net 348)
	)
	(segment
		(start 142.2 85.5)
		(end 141.5 85.5)
		(width 0.3)
		(layer "F.Cu")
		(net 348)
	)
	(via
		(at 149 85)
		(size 0.45)
		(drill 0.2)
		(layers "F.Cu" "B.Cu")
		(remove_unused_layers yes)
		(keep_end_layers yes)
		(zone_layer_connections)
		(net 348)
	)
	(via
		(at 142.5 87.25)
		(size 0.45)
		(drill 0.2)
		(layers "F.Cu" "B.Cu")
		(remove_unused_layers yes)
		(keep_end_layers yes)
		(zone_layer_connections)
		(net 348)
	)
	(segment
		(start 147.45 83.45)
		(end 147.55 83.55)
		(width 0.3)
		(layer "B.Cu")
		(net 348)
	)
	(segment
		(start 146.725 83.45)
		(end 147.45 83.45)
		(width 0.3)
		(layer "B.Cu")
		(net 348)
	)
	(segment
		(start 147.55 83.55)
		(end 148.3 83.55)
		(width 0.3)
		(layer "B.Cu")
		(net 348)
	)
	(segment
		(start 148.5 83.75)
		(end 148.5 84.5)
		(width 0.3)
		(layer "B.Cu")
		(net 348)
	)
	(segment
		(start 148.5 84.5)
		(end 149 85)
		(width 0.3)
		(layer "B.Cu")
		(net 348)
	)
	(segment
		(start 147.55 83.55)
		(end 147.55 84.275)
		(width 0.3)
		(layer "B.Cu")
		(net 348)
	)
	(segment
		(start 143.95 86.225)
		(end 142.51 86.225)
		(width 0.3)
		(layer "B.Cu")
		(net 348)
	)
	(segment
		(start 148.3 83.55)
		(end 148.5 83.75)
		(width 0.3)
		(layer "B.Cu")
		(net 348)
	)
	(segment
		(start 142.5 86.235)
		(end 142.5 87.25)
		(width 0.3)
		(layer "B.Cu")
		(net 348)
	)
	(segment
		(start 144 87.25)
		(end 146.25 85)
		(width 0.5)
		(layer "In2.Cu")
		(net 348)
	)
	(segment
		(start 142.5 87.25)
		(end 144 87.25)
		(width 0.5)
		(layer "In2.Cu")
		(net 348)
	)
	(segment
		(start 146.25 85)
		(end 149 85)
		(width 0.5)
		(layer "In2.Cu")
		(net 348)
	)
	(segment
		(start 155.89 72.415)
		(end 157.325 72.415)
		(width 0.3)
		(layer "B.Cu")
		(net 349)
	)
	(segment
		(start 152.28 61.3)
		(end 152.28 62.505)
		(width 0.15)
		(layer "F.Cu")
		(net 350)
	)
	(segment
		(start 152.23 61.25)
		(end 152.28 61.3)
		(width 0.15)
		(layer "F.Cu")
		(net 350)
	)
	(via
		(at 152.23 61.25)
		(size 0.45)
		(drill 0.2)
		(layers "F.Cu" "B.Cu")
		(remove_unused_layers yes)
		(keep_end_layers yes)
		(zone_layer_connections)
		(net 350)
	)
	(segment
		(start 152.23 61.25)
		(end 152.23 60.735)
		(width 0.3)
		(layer "B.Cu")
		(net 350)
	)
	(segment
		(start 161.85 88.25)
		(end 163.55 88.25)
		(width 0.15)
		(layer "F.Cu")
		(net 351)
	)
	(segment
		(start 160.45 93.15)
		(end 158.78 93.15)
		(width 0.15)
		(layer "F.Cu")
		(net 351)
	)
	(segment
		(start 162.55 92.05)
		(end 161.55 92.05)
		(width 0.15)
		(layer "F.Cu")
		(net 351)
	)
	(segment
		(start 161.55 92.05)
		(end 161.55 88.55)
		(width 0.15)
		(layer "F.Cu")
		(net 351)
	)
	(segment
		(start 158.53 92.35)
		(end 158.53 92.9)
		(width 0.15)
		(layer "F.Cu")
		(net 351)
	)
	(segment
		(start 161.55 92.05)
		(end 160.45 93.15)
		(width 0.15)
		(layer "F.Cu")
		(net 351)
	)
	(segment
		(start 158.78 93.15)
		(end 158.3308 93.5992)
		(width 0.15)
		(layer "F.Cu")
		(net 351)
	)
	(segment
		(start 163.55 88.25)
		(end 163.68 88.12)
		(width 0.15)
		(layer "F.Cu")
		(net 351)
	)
	(segment
		(start 158.53 92.9)
		(end 158.78 93.15)
		(width 0.15)
		(layer "F.Cu")
		(net 351)
	)
	(segment
		(start 161.55 88.55)
		(end 161.85 88.25)
		(width 0.15)
		(layer "F.Cu")
		(net 351)
	)
	(segment
		(start 163.68 88.12)
		(end 163.68 87.6)
		(width 0.15)
		(layer "F.Cu")
		(net 351)
	)
	(segment
		(start 163.5 91.65)
		(end 162.95 91.1)
		(width 0.2)
		(layer "F.Cu")
		(net 353)
	)
	(segment
		(start 162.6 93.6)
		(end 163.5 92.7)
		(width 0.2)
		(layer "F.Cu")
		(net 353)
	)
	(segment
		(start 163.5 92.7)
		(end 163.5 91.65)
		(width 0.2)
		(layer "F.Cu")
		(net 353)
	)
	(segment
		(start 163.68 86.65)
		(end 165.48 86.65)
		(width 0.3)
		(layer "F.Cu")
		(net 354)
	)
	(segment
		(start 128.1 108.8465)
		(end 129.596 107.3505)
		(width 0.15)
		(layer "F.Cu")
		(net 355)
	)
	(segment
		(start 128.1 112.95)
		(end 128.1 108.8465)
		(width 0.15)
		(layer "F.Cu")
		(net 355)
	)
	(segment
		(start 108.46 89.65)
		(end 110.005419 88.104581)
		(width 0.15)
		(layer "F.Cu")
		(net 355)
	)
	(segment
		(start 102.65 90.65)
		(end 102.65 93)
		(width 0.15)
		(layer "F.Cu")
		(net 355)
	)
	(segment
		(start 103.65 89.65)
		(end 108.46 89.65)
		(width 0.15)
		(layer "F.Cu")
		(net 355)
	)
	(segment
		(start 121.9 116.3)
		(end 122.75 116.3)
		(width 0.15)
		(layer "F.Cu")
		(net 355)
	)
	(segment
		(start 116.05 116.1)
		(end 121.7 116.1)
		(width 0.15)
		(layer "F.Cu")
		(net 355)
	)
	(segment
		(start 123.1 90.3)
		(end 123.5 89.9)
		(width 0.15)
		(layer "F.Cu")
		(net 355)
	)
	(segment
		(start 121.7 116.1)
		(end 121.9 116.3)
		(width 0.15)
		(layer "F.Cu")
		(net 355)
	)
	(segment
		(start 122.75 116.3)
		(end 123.45 115.6)
		(width 0.15)
		(layer "F.Cu")
		(net 355)
	)
	(segment
		(start 125.45 115.6)
		(end 128.1 112.95)
		(width 0.15)
		(layer "F.Cu")
		(net 355)
	)
	(segment
		(start 102.65 90.65)
		(end 103.65 89.65)
		(width 0.15)
		(layer "F.Cu")
		(net 355)
	)
	(segment
		(start 123.45 115.6)
		(end 125.45 115.6)
		(width 0.15)
		(layer "F.Cu")
		(net 355)
	)
	(via
		(at 116.05 116.1)
		(size 0.45)
		(drill 0.2)
		(layers "F.Cu" "B.Cu")
		(remove_unused_layers yes)
		(keep_end_layers yes)
		(zone_layer_connections)
		(net 355)
	)
	(via
		(at 129.596 107.3505)
		(size 0.45)
		(drill 0.2)
		(layers "F.Cu" "B.Cu")
		(remove_unused_layers yes)
		(keep_end_layers yes)
		(zone_layer_connections)
		(net 355)
	)
	(via
		(at 123.1 90.3)
		(size 0.45)
		(drill 0.2)
		(layers "F.Cu" "B.Cu")
		(remove_unused_layers yes)
		(keep_end_layers yes)
		(free yes)
		(zone_layer_connections)
		(net 355)
	)
	(via
		(at 110.005419 88.104581)
		(size 0.45)
		(drill 0.2)
		(layers "F.Cu" "B.Cu")
		(net 355)
	)
	(via
		(at 102.65 93)
		(size 0.45)
		(drill 0.2)
		(layers "F.Cu" "B.Cu")
		(remove_unused_layers yes)
		(keep_end_layers yes)
		(zone_layer_connections)
		(net 355)
	)
	(segment
		(start 133.815 99.249314)
		(end 133.815 99.146752)
		(width 0.15)
		(layer "B.Cu")
		(net 355)
	)
	(segment
		(start 143.2225 85.575)
		(end 143.0475 85.75)
		(width 0.15)
		(layer "B.Cu")
		(net 355)
	)
	(segment
		(start 123.1 90.3)
		(end 122.6875 89.8875)
		(width 0.125)
		(layer "B.Cu")
		(net 355)
	)
	(segment
		(start 122.6875 89.8875)
		(end 122.6875 89.2875)
		(width 0.125)
		(layer "B.Cu")
		(net 355)
	)
	(segment
		(start 143.0475 85.75)
		(end 142.02 85.75)
		(width 0.15)
		(layer "B.Cu")
		(net 355)
	)
	(segment
		(start 101.4 105.3)
		(end 112.2 116.1)
		(width 0.15)
		(layer "B.Cu")
		(net 355)
	)
	(segment
		(start 100.56 100.79)
		(end 100.56 102.76)
		(width 0.15)
		(layer "B.Cu")
		(net 355)
	)
	(segment
		(start 102.65 95.7)
		(end 101.85 96.5)
		(width 0.15)
		(layer "B.Cu")
		(net 355)
	)
	(segment
		(start 129.965 100.095)
		(end 128.275 101.785)
		(width 0.15)
		(layer "B.Cu")
		(net 355)
	)
	(segment
		(start 122.6875 89.2875)
		(end 122.35 88.95)
		(width 0.125)
		(layer "B.Cu")
		(net 355)
	)
	(segment
		(start 134.965686 100.4)
		(end 133.815 99.249314)
		(width 0.15)
		(layer "B.Cu")
		(net 355)
	)
	(segment
		(start 112.2 116.1)
		(end 116.05 116.1)
		(width 0.15)
		(layer "B.Cu")
		(net 355)
	)
	(segment
		(start 102.65 93)
		(end 102.65 95.7)
		(width 0.15)
		(layer "B.Cu")
		(net 355)
	)
	(segment
		(start 133.815 99.146752)
		(end 133.268248 98.6)
		(width 0.15)
		(layer "B.Cu")
		(net 355)
	)
	(segment
		(start 143.95 85.575)
		(end 143.2225 85.575)
		(width 0.15)
		(layer "B.Cu")
		(net 355)
	)
	(segment
		(start 142.02 85.75)
		(end 141.73 86.04)
		(width 0.15)
		(layer "B.Cu")
		(net 355)
	)
	(segment
		(start 141.73 87.84)
		(end 143.22 89.33)
		(width 0.15)
		(layer "B.Cu")
		(net 355)
	)
	(segment
		(start 122.35 88.95)
		(end 114.85 88.95)
		(width 0.125)
		(layer "B.Cu")
		(net 355)
	)
	(segment
		(start 114.85 88.95)
		(end 113.96 88.06)
		(width 0.125)
		(layer "B.Cu")
		(net 355)
	)
	(segment
		(start 101.85 99.5)
		(end 100.56 100.79)
		(width 0.15)
		(layer "B.Cu")
		(net 355)
	)
	(segment
		(start 110.005419 88.104581)
		(end 110.05 88.06)
		(width 0.15)
		(layer "B.Cu")
		(net 355)
	)
	(segment
		(start 100.56 102.76)
		(end 101.4 103.6)
		(width 0.15)
		(layer "B.Cu")
		(net 355)
	)
	(segment
		(start 101.4 103.6)
		(end 101.4 105.3)
		(width 0.15)
		(layer "B.Cu")
		(net 355)
	)
	(segment
		(start 143.22 89.33)
		(end 143.22 94.345686)
		(width 0.15)
		(layer "B.Cu")
		(net 355)
	)
	(segment
		(start 101.85 96.5)
		(end 101.85 99.5)
		(width 0.15)
		(layer "B.Cu")
		(net 355)
	)
	(segment
		(start 128.275 101.785)
		(end 128.275 106.0295)
		(width 0.15)
		(layer "B.Cu")
		(net 355)
	)
	(segment
		(start 133.268248 98.6)
		(end 130.44 98.6)
		(width 0.15)
		(layer "B.Cu")
		(net 355)
	)
	(segment
		(start 128.275 106.0295)
		(end 129.596 107.3505)
		(width 0.15)
		(layer "B.Cu")
		(net 355)
	)
	(segment
		(start 130.44 98.6)
		(end 129.965 99.075)
		(width 0.15)
		(layer "B.Cu")
		(net 355)
	)
	(segment
		(start 110.05 88.06)
		(end 113.96 88.06)
		(width 0.15)
		(layer "B.Cu")
		(net 355)
	)
	(segment
		(start 143.22 94.345686)
		(end 137.165686 100.4)
		(width 0.15)
		(layer "B.Cu")
		(net 355)
	)
	(segment
		(start 129.965 99.075)
		(end 129.965 100.095)
		(width 0.15)
		(layer "B.Cu")
		(net 355)
	)
	(segment
		(start 141.73 86.04)
		(end 141.73 87.84)
		(width 0.15)
		(layer "B.Cu")
		(net 355)
	)
	(segment
		(start 137.165686 100.4)
		(end 134.965686 100.4)
		(width 0.15)
		(layer "B.Cu")
		(net 355)
	)
	(segment
		(start 163.39 78.85)
		(end 163.39 77.6)
		(width 0.15)
		(layer "F.Cu")
		(net 356)
	)
	(segment
		(start 163.39 77.6)
		(end 163.69 77.3)
		(width 0.15)
		(layer "F.Cu")
		(net 356)
	)
	(segment
		(start 164.29 77.3)
		(end 164.99 76.6)
		(width 0.15)
		(layer "F.Cu")
		(net 356)
	)
	(segment
		(start 163.69 77.3)
		(end 164.29 77.3)
		(width 0.15)
		(layer "F.Cu")
		(net 356)
	)
	(segment
		(start 100.5 90.1)
		(end 102.85 87.75)
		(width 0.15)
		(layer "F.Cu")
		(net 357)
	)
	(segment
		(start 122.65 116.8)
		(end 116.05 116.8)
		(width 0.15)
		(layer "F.Cu")
		(net 357)
	)
	(segment
		(start 100.5 91.5795)
		(end 100.5205 91.6)
		(width 0.15)
		(layer "F.Cu")
		(net 357)
	)
	(segment
		(start 128.45 113.3)
		(end 125.9 115.85)
		(width 0.15)
		(layer "F.Cu")
		(net 357)
	)
	(segment
		(start 123.9 90.323234)
		(end 123.9 90.3)
		(width 0.15)
		(layer "F.Cu")
		(net 357)
	)
	(segment
		(start 128.45 109.346)
		(end 128.45 113.3)
		(width 0.15)
		(layer "F.Cu")
		(net 357)
	)
	(segment
		(start 100.5 91.45)
		(end 100.5 91.5795)
		(width 0.15)
		(layer "F.Cu")
		(net 357)
	)
	(segment
		(start 100.5 90.1)
		(end 100.5 91.45)
		(width 0.15)
		(layer "F.Cu")
		(net 357)
	)
	(segment
		(start 123.6 115.85)
		(end 122.65 116.8)
		(width 0.15)
		(layer "F.Cu")
		(net 357)
	)
	(segment
		(start 125.9 115.85)
		(end 123.6 115.85)
		(width 0.15)
		(layer "F.Cu")
		(net 357)
	)
	(segment
		(start 123.9 90.3)
		(end 124.3 89.9)
		(width 0.15)
		(layer "F.Cu")
		(net 357)
	)
	(segment
		(start 129.596 108.2)
		(end 128.45 109.346)
		(width 0.15)
		(layer "F.Cu")
		(net 357)
	)
	(via
		(at 100.5205 91.6)
		(size 0.45)
		(drill 0.2)
		(layers "F.Cu" "B.Cu")
		(remove_unused_layers yes)
		(keep_end_layers yes)
		(zone_layer_connections)
		(net 357)
	)
	(via
		(at 129.596 108.2)
		(size 0.45)
		(drill 0.2)
		(layers "F.Cu" "B.Cu")
		(remove_unused_layers yes)
		(keep_end_layers yes)
		(zone_layer_connections)
		(net 357)
	)
	(via
		(at 123.9 90.323234)
		(size 0.45)
		(drill 0.2)
		(layers "F.Cu" "B.Cu")
		(remove_unused_layers yes)
		(keep_end_layers yes)
		(free yes)
		(zone_layer_connections)
		(net 357)
	)
	(via
		(at 116.05 116.8)
		(size 0.45)
		(drill 0.2)
		(layers "F.Cu" "B.Cu")
		(remove_unused_layers yes)
		(keep_end_layers yes)
		(zone_layer_connections)
		(net 357)
	)
	(via
		(at 102.85 87.75)
		(size 0.45)
		(drill 0.2)
		(layers "F.Cu" "B.Cu")
		(net 357)
	)
	(segment
		(start 134 105.5)
		(end 132.95 104.45)
		(width 0.15)
		(layer "B.Cu")
		(net 357)
	)
	(segment
		(start 100.5205 91.6)
		(end 100.5205 97.2205)
		(width 0.15)
		(layer "B.Cu")
		(net 357)
	)
	(segment
		(start 103.284314 88.75)
		(end 102.9 88.365686)
		(width 0.15)
		(layer "B.Cu")
		(net 357)
	)
	(segment
		(start 100.85 97.55)
		(end 100.85 99.8)
		(width 0.15)
		(layer "B.Cu")
		(net 357)
	)
	(segment
		(start 99.95 104.8)
		(end 111.95 116.8)
		(width 0.15)
		(layer "B.Cu")
		(net 357)
	)
	(segment
		(start 123.523234 90.7)
		(end 122.1 90.7)
		(width 0.125)
		(layer "B.Cu")
		(net 357)
	)
	(segment
		(start 131.7 104.9)
		(end 130.65 104.9)
		(width 0.15)
		(layer "B.Cu")
		(net 357)
	)
	(segment
		(start 111.95 116.8)
		(end 116.05 116.8)
		(width 0.15)
		(layer "B.Cu")
		(net 357)
	)
	(segment
		(start 133.6 108.15)
		(end 134 107.75)
		(width 0.15)
		(layer "B.Cu")
		(net 357)
	)
	(segment
		(start 122.1 90.7)
		(end 121.324004 89.924004)
		(width 0.125)
		(layer "B.Cu")
		(net 357)
	)
	(segment
		(start 100.5205 97.2205)
		(end 100.85 97.55)
		(width 0.15)
		(layer "B.Cu")
		(net 357)
	)
	(segment
		(start 145.425 88.275)
		(end 145.425 87.05)
		(width 0.15)
		(layer "B.Cu")
		(net 357)
	)
	(segment
		(start 119.851992 89.3)
		(end 114.6 89.3)
		(width 0.125)
		(layer "B.Cu")
		(net 357)
	)
	(segment
		(start 102.9 88.365686)
		(end 102.9 87.8)
		(width 0.15)
		(layer "B.Cu")
		(net 357)
	)
	(segment
		(start 132.15 104.45)
		(end 131.7 104.9)
		(width 0.15)
		(layer "B.Cu")
		(net 357)
	)
	(segment
		(start 130.65 104.9)
		(end 130.45 104.7)
		(width 0.15)
		(layer "B.Cu")
		(net 357)
	)
	(segment
		(start 145.05 90.215686)
		(end 144.6 89.765686)
		(width 0.15)
		(layer "B.Cu")
		(net 357)
	)
	(segment
		(start 131.15 103.25)
		(end 135.65 103.25)
		(width 0.15)
		(layer "B.Cu")
		(net 357)
	)
	(segment
		(start 121.324004 89.924004)
		(end 120.475996 89.924004)
		(width 0.125)
		(layer "B.Cu")
		(net 357)
	)
	(segment
		(start 114.6 89.3)
		(end 114.05 88.75)
		(width 0.125)
		(layer "B.Cu")
		(net 357)
	)
	(segment
		(start 120.475996 89.924004)
		(end 119.851992 89.3)
		(width 0.125)
		(layer "B.Cu")
		(net 357)
	)
	(segment
		(start 99.95 100.7)
		(end 99.95 104.8)
		(width 0.15)
		(layer "B.Cu")
		(net 357)
	)
	(segment
		(start 102.9 87.8)
		(end 102.85 87.75)
		(width 0.15)
		(layer "B.Cu")
		(net 357)
	)
	(segment
		(start 100.85 99.8)
		(end 99.95 100.7)
		(width 0.15)
		(layer "B.Cu")
		(net 357)
	)
	(segment
		(start 129.596 108.2)
		(end 129.646 108.15)
		(width 0.15)
		(layer "B.Cu")
		(net 357)
	)
	(segment
		(start 112.67 88.75)
		(end 103.284314 88.75)
		(width 0.15)
		(layer "B.Cu")
		(net 357)
	)
	(segment
		(start 145.05 93.85)
		(end 145.05 90.215686)
		(width 0.15)
		(layer "B.Cu")
		(net 357)
	)
	(segment
		(start 130.45 103.95)
		(end 131.15 103.25)
		(width 0.15)
		(layer "B.Cu")
		(net 357)
	)
	(segment
		(start 144.6 89.1)
		(end 145.425 88.275)
		(width 0.15)
		(layer "B.Cu")
		(net 357)
	)
	(segment
		(start 129.646 108.15)
		(end 133.6 108.15)
		(width 0.15)
		(layer "B.Cu")
		(net 357)
	)
	(segment
		(start 134 107.75)
		(end 134 105.5)
		(width 0.15)
		(layer "B.Cu")
		(net 357)
	)
	(segment
		(start 114.05 88.75)
		(end 112.67 88.75)
		(width 0.125)
		(layer "B.Cu")
		(net 357)
	)
	(segment
		(start 135.65 103.25)
		(end 145.05 93.85)
		(width 0.15)
		(layer "B.Cu")
		(net 357)
	)
	(segment
		(start 144.6 89.765686)
		(end 144.6 89.1)
		(width 0.15)
		(layer "B.Cu")
		(net 357)
	)
	(segment
		(start 123.9 90.323234)
		(end 123.523234 90.7)
		(width 0.125)
		(layer "B.Cu")
		(net 357)
	)
	(segment
		(start 132.95 104.45)
		(end 132.15 104.45)
		(width 0.15)
		(layer "B.Cu")
		(net 357)
	)
	(segment
		(start 130.45 104.7)
		(end 130.45 103.95)
		(width 0.15)
		(layer "B.Cu")
		(net 357)
	)
	(segment
		(start 107.89 105.9)
		(end 108.2 105.9)
		(width 0.15)
		(layer "F.Cu")
		(net 358)
	)
	(segment
		(start 107.6 104.9)
		(end 107.6 105.61)
		(width 0.15)
		(layer "F.Cu")
		(net 358)
	)
	(segment
		(start 108.615 104.725)
		(end 107.775 104.725)
		(width 0.15)
		(layer "F.Cu")
		(net 358)
	)
	(segment
		(start 108.4 106.1)
		(end 108.4 106.715)
		(width 0.15)
		(layer "F.Cu")
		(net 358)
	)
	(segment
		(start 107.775 104.725)
		(end 107.6 104.9)
		(width 0.15)
		(layer "F.Cu")
		(net 358)
	)
	(segment
		(start 108.2 105.9)
		(end 108.4 106.1)
		(width 0.15)
		(layer "F.Cu")
		(net 358)
	)
	(segment
		(start 107.6 105.61)
		(end 107.89 105.9)
		(width 0.15)
		(layer "F.Cu")
		(net 358)
	)
	(segment
		(start 154.209695 61.04981)
		(end 154.02019 61.04981)
		(width 0.182)
		(layer "F.Cu")
		(net 359)
	)
	(segment
		(start 154.28 61.642499)
		(end 154.339 61.583499)
		(width 0.182)
		(layer "F.Cu")
		(net 359)
	)
	(segment
		(start 154.25 61.75)
		(end 154.28 61.78)
		(width 0.15)
		(layer "F.Cu")
		(net 359)
	)
	(segment
		(start 153.28 61.78)
		(end 153.31 61.75)
		(width 0.15)
		(layer "F.Cu")
		(net 359)
	)
	(segment
		(start 154.28 61.78)
		(end 154.28 62.505)
		(width 0.15)
		(layer "F.Cu")
		(net 359)
	)
	(segment
		(start 154.28 62.505)
		(end 154.28 61.642499)
		(width 0.182)
		(layer "F.Cu")
		(net 359)
	)
	(segment
		(start 154.339 61.583499)
		(end 154.339 61.179115)
		(width 0.182)
		(layer "F.Cu")
		(net 359)
	)
	(segment
		(start 154.339 61.179115)
		(end 154.209695 61.04981)
		(width 0.182)
		(layer "F.Cu")
		(net 359)
	)
	(segment
		(start 153.31 61.75)
		(end 154.25 61.75)
		(width 0.15)
		(layer "F.Cu")
		(net 359)
	)
	(segment
		(start 153.28 62.505)
		(end 153.28 61.78)
		(width 0.15)
		(layer "F.Cu")
		(net 359)
	)
	(via
		(at 145.375 79.612201)
		(size 0.45)
		(drill 0.2)
		(layers "F.Cu" "B.Cu")
		(remove_unused_layers yes)
		(keep_end_layers yes)
		(zone_layer_connections)
		(net 359)
	)
	(via
		(at 154.02019 61.04981)
		(size 0.45)
		(drill 0.2)
		(layers "F.Cu" "B.Cu")
		(remove_unused_layers yes)
		(keep_end_layers yes)
		(zone_layer_connections)
		(net 359)
	)
	(segment
		(start 145.2 81.015)
		(end 145.509 80.706)
		(width 0.182)
		(layer "B.Cu")
		(net 359)
	)
	(segment
		(start 145.509 80.706)
		(end 145.509 79.746201)
		(width 0.182)
		(layer "B.Cu")
		(net 359)
	)
	(segment
		(start 144.2 81.015)
		(end 145.2 81.015)
		(width 0.182)
		(layer "B.Cu")
		(net 359)
	)
	(segment
		(start 145.509 79.746201)
		(end 145.375 79.612201)
		(width 0.182)
		(layer "B.Cu")
		(net 359)
	)
	(segment
		(start 150.905 66.915)
		(end 150.905 65.678222)
		(width 0.1)
		(layer "In2.Cu")
		(net 359)
	)
	(segment
		(start 145.575 79.412201)
		(end 145.575 75.608222)
		(width 0.1)
		(layer "In2.Cu")
		(net 359)
	)
	(segment
		(start 154.22981 62.263412)
		(end 154.22981 61.25943)
		(width 0.1)
		(layer "In2.Cu")
		(net 359)
	)
	(segment
		(start 152.228222 63.285)
		(end 153.208222 63.285)
		(width 0.1)
		(layer "In2.Cu")
		(net 359)
	)
	(segment
		(start 145.375 79.612201)
		(end 145.575 79.412201)
		(width 0.1)
		(layer "In2.Cu")
		(net 359)
	)
	(segment
		(start 145.575 75.608222)
		(end 150.905 70.278222)
		(width 0.1)
		(layer "In2.Cu")
		(net 359)
	)
	(segment
		(start 150.905 70.278222)
		(end 150.905 67.615)
		(width 0.1)
		(layer "In2.Cu")
		(net 359)
	)
	(segment
		(start 150.905 65.678222)
		(end 151.465 65.118222)
		(width 0.1)
		(layer "In2.Cu")
		(net 359)
	)
	(segment
		(start 151.465 65.118222)
		(end 151.465 64.048222)
		(width 0.1)
		(layer "In2.Cu")
		(net 359)
	)
	(segment
		(start 151.465 64.048222)
		(end 152.228222 63.285)
		(width 0.1)
		(layer "In2.Cu")
		(net 359)
	)
	(segment
		(start 150.585151 67.09)
		(end 150.73 67.09)
		(width 0.1)
		(layer "In2.Cu")
		(net 359)
	)
	(segment
		(start 154.22981 61.25943)
		(end 154.02019 61.04981)
		(width 0.1)
		(layer "In2.Cu")
		(net 359)
	)
	(segment
		(start 153.208222 63.285)
		(end 154.22981 62.263412)
		(width 0.1)
		(layer "In2.Cu")
		(net 359)
	)
	(segment
		(start 150.73 67.44)
		(end 150.585151 67.44)
		(width 0.1)
		(layer "In2.Cu")
		(net 359)
	)
	(arc
		(start 150.73 67.09)
		(mid 150.853744 67.038744)
		(end 150.905 66.915)
		(width 0.1)
		(layer "In2.Cu")
		(net 359)
	)
	(arc
		(start 150.410151 67.265)
		(mid 150.461407 67.141256)
		(end 150.585151 67.09)
		(width 0.1)
		(layer "In2.Cu")
		(net 359)
	)
	(arc
		(start 150.905 67.615)
		(mid 150.853744 67.491256)
		(end 150.73 67.44)
		(width 0.1)
		(layer "In2.Cu")
		(net 359)
	)
	(arc
		(start 150.585151 67.44)
		(mid 150.461407 67.388744)
		(end 150.410151 67.265)
		(width 0.1)
		(layer "In2.Cu")
		(net 359)
	)
	(segment
		(start 153.78 62.505)
		(end 153.78 63.23)
		(width 0.15)
		(layer "F.Cu")
		(net 360)
	)
	(segment
		(start 154.78 63.25)
		(end 154.78 62.505)
		(width 0.15)
		(layer "F.Cu")
		(net 360)
	)
	(segment
		(start 153.805 63.255)
		(end 154.775 63.255)
		(width 0.15)
		(layer "F.Cu")
		(net 360)
	)
	(segment
		(start 154.775 63.255)
		(end 154.78 63.25)
		(width 0.15)
		(layer "F.Cu")
		(net 360)
	)
	(segment
		(start 154.78 61.642499)
		(end 154.721 61.583499)
		(width 0.182)
		(layer "F.Cu")
		(net 360)
	)
	(segment
		(start 154.721 61.020885)
		(end 154.47981 60.779695)
		(width 0.182)
		(layer "F.Cu")
		(net 360)
	)
	(segment
		(start 154.78 62.505)
		(end 154.78 61.642499)
		(width 0.182)
		(layer "F.Cu")
		(net 360)
	)
	(segment
		(start 154.47981 60.779695)
		(end 154.47981 60.59019)
		(width 0.182)
		(layer "F.Cu")
		(net 360)
	)
	(segment
		(start 154.721 61.583499)
		(end 154.721 61.020885)
		(width 0.182)
		(layer "F.Cu")
		(net 360)
	)
	(segment
		(start 153.78 63.23)
		(end 153.805 63.255)
		(width 0.15)
		(layer "F.Cu")
		(net 360)
	)
	(via
		(at 146.025 79.612201)
		(size 0.45)
		(drill 0.2)
		(layers "F.Cu" "B.Cu")
		(remove_unused_layers yes)
		(keep_end_layers yes)
		(zone_layer_connections)
		(net 360)
	)
	(via
		(at 154.47981 60.59019)
		(size 0.45)
		(drill 0.2)
		(layers "F.Cu" "B.Cu")
		(remove_unused_layers yes)
		(keep_end_layers yes)
		(zone_layer_connections)
		(net 360)
	)
	(segment
		(start 146.2 81.015)
		(end 147.2 81.015)
		(width 0.182)
		(layer "B.Cu")
		(net 360)
	)
	(segment
		(start 145.891 80.706)
		(end 145.891 79.746201)
		(width 0.182)
		(layer "B.Cu")
		(net 360)
	)
	(segment
		(start 146.2 81.015)
		(end 145.891 80.706)
		(width 0.182)
		(layer "B.Cu")
		(net 360)
	)
	(segment
		(start 145.891 79.746201)
		(end 146.025 79.612201)
		(width 0.182)
		(layer "B.Cu")
		(net 360)
	)
	(segment
		(start 151.155 65.781778)
		(end 151.715 65.221778)
		(width 0.1)
		(layer "In2.Cu")
		(net 360)
	)
	(segment
		(start 151.715 64.151778)
		(end 152.331778 63.535)
		(width 0.1)
		(layer "In2.Cu")
		(net 360)
	)
	(segment
		(start 153.311778 63.535)
		(end 154.47981 62.366968)
		(width 0.1)
		(layer "In2.Cu")
		(net 360)
	)
	(segment
		(start 145.825 75.711778)
		(end 151.155 70.381778)
		(width 0.1)
		(layer "In2.Cu")
		(net 360)
	)
	(segment
		(start 152.331778 63.535)
		(end 153.311778 63.535)
		(width 0.1)
		(layer "In2.Cu")
		(net 360)
	)
	(segment
		(start 151.715 65.221778)
		(end 151.715 64.151778)
		(width 0.1)
		(layer "In2.Cu")
		(net 360)
	)
	(segment
		(start 151.155 70.381778)
		(end 151.155 65.781778)
		(width 0.1)
		(layer "In2.Cu")
		(net 360)
	)
	(segment
		(start 146.025 79.612201)
		(end 145.825 79.412201)
		(width 0.1)
		(layer "In2.Cu")
		(net 360)
	)
	(segment
		(start 145.825 79.412201)
		(end 145.825 75.711778)
		(width 0.1)
		(layer "In2.Cu")
		(net 360)
	)
	(segment
		(start 154.47981 62.366968)
		(end 154.47981 60.59019)
		(width 0.1)
		(layer "In2.Cu")
		(net 360)
	)
	(segment
		(start 145.941 82.715999)
		(end 145.941 82.18769)
		(width 0.182)
		(layer "B.Cu")
		(net 361)
	)
	(segment
		(start 146.075 83.45)
		(end 146.075 82.849999)
		(width 0.182)
		(layer "B.Cu")
		(net 361)
	)
	(segment
		(start 146.075 82.849999)
		(end 145.941 82.715999)
		(width 0.182)
		(layer "B.Cu")
		(net 361)
	)
	(segment
		(start 145.559 82.18769)
		(end 145.40269 82.18769)
		(width 0.182)
		(layer "B.Cu")
		(net 362)
	)
	(segment
		(start 145.425 83.45)
		(end 145.425 82.849999)
		(width 0.182)
		(layer "B.Cu")
		(net 362)
	)
	(segment
		(start 145.40269 82.18769)
		(end 145.2 81.985)
		(width 0.182)
		(layer "B.Cu")
		(net 362)
	)
	(segment
		(start 145.559 82.715999)
		(end 145.559 82.18769)
		(width 0.182)
		(layer "B.Cu")
		(net 362)
	)
	(segment
		(start 145.425 82.849999)
		(end 145.559 82.715999)
		(width 0.182)
		(layer "B.Cu")
		(net 362)
	)
	(segment
		(start 122.55 115.9)
		(end 122.515 115.865)
		(width 0.15)
		(layer "F.Cu")
		(net 363)
	)
	(segment
		(start 109.085 107.685)
		(end 109.2 107.8)
		(width 0.15)
		(layer "F.Cu")
		(net 363)
	)
	(segment
		(start 122.515 115.865)
		(end 122.515 115.15)
		(width 0.15)
		(layer "F.Cu")
		(net 363)
	)
	(segment
		(start 108.4 107.685)
		(end 109.085 107.685)
		(width 0.15)
		(layer "F.Cu")
		(net 363)
	)
	(via
		(at 122.55 115.9)
		(size 0.45)
		(drill 0.2)
		(layers "F.Cu" "B.Cu")
		(remove_unused_layers yes)
		(keep_end_layers yes)
		(zone_layer_connections)
		(net 363)
	)
	(via
		(at 109.2 107.8)
		(size 0.45)
		(drill 0.2)
		(layers "F.Cu" "B.Cu")
		(net 363)
	)
	(segment
		(start 122.55 115.9)
		(end 122.23 116.22)
		(width 0.15)
		(layer "In2.Cu")
		(net 363)
	)
	(segment
		(start 122.23 116.22)
		(end 117.32 116.22)
		(width 0.15)
		(layer "In2.Cu")
		(net 363)
	)
	(segment
		(start 117.32 116.22)
		(end 109.2 108.1)
		(width 0.15)
		(layer "In2.Cu")
		(net 363)
	)
	(segment
		(start 109.2 108.1)
		(end 109.2 107.8)
		(width 0.15)
		(layer "In2.Cu")
		(net 363)
	)
	(segment
		(start 168.605 92.895)
		(end 169.6 92.895)
		(width 0.15)
		(layer "F.Cu")
		(net 364)
	)
	(segment
		(start 168.3 92.6)
		(end 168.6 92.9)
		(width 0.15)
		(layer "F.Cu")
		(net 364)
	)
	(segment
		(start 167.685 92.6)
		(end 168.3 92.6)
		(width 0.15)
		(layer "F.Cu")
		(net 364)
	)
	(segment
		(start 168.6 92.9)
		(end 168.605 92.895)
		(width 0.15)
		(layer "F.Cu")
		(net 364)
	)
	(segment
		(start 168.5 92.2)
		(end 168.695 92.395)
		(width 0.15)
		(layer "F.Cu")
		(net 365)
	)
	(segment
		(start 167.685 91.6)
		(end 168.3 91.6)
		(width 0.15)
		(layer "F.Cu")
		(net 365)
	)
	(segment
		(start 168.3 91.6)
		(end 168.5 91.8)
		(width 0.15)
		(layer "F.Cu")
		(net 365)
	)
	(segment
		(start 168.5 91.8)
		(end 168.5 92.2)
		(width 0.15)
		(layer "F.Cu")
		(net 365)
	)
	(segment
		(start 168.695 92.395)
		(end 169.6 92.395)
		(width 0.15)
		(layer "F.Cu")
		(net 365)
	)
	(segment
		(start 168.1 90.6)
		(end 167.685 90.6)
		(width 0.15)
		(layer "F.Cu")
		(net 366)
	)
	(segment
		(start 169.6 91.895)
		(end 168.995 91.895)
		(width 0.15)
		(layer "F.Cu")
		(net 366)
	)
	(segment
		(start 168.995 91.895)
		(end 168.4 91.3)
		(width 0.15)
		(layer "F.Cu")
		(net 366)
	)
	(segment
		(start 168.4 91.3)
		(end 168.4 90.9)
		(width 0.15)
		(layer "F.Cu")
		(net 366)
	)
	(segment
		(start 168.4 90.9)
		(end 168.1 90.6)
		(width 0.15)
		(layer "F.Cu")
		(net 366)
	)
	(segment
		(start 133.75 116.265)
		(end 133.75 116)
		(width 0.15)
		(layer "F.Cu")
		(net 371)
	)
	(segment
		(start 133.75 116)
		(end 133 115.25)
		(width 0.15)
		(layer "F.Cu")
		(net 371)
	)
	(segment
		(start 123.49 90.7)
		(end 123.09 91.1)
		(width 0.1)
		(layer "F.Cu")
		(net 371)
	)
	(via
		(at 134.5 121.6)
		(size 0.45)
		(drill 0.2)
		(layers "F.Cu" "B.Cu")
		(remove_unused_layers yes)
		(keep_end_layers yes)
		(zone_layer_connections)
		(net 371)
	)
	(via
		(at 123.09 91.1)
		(size 0.45)
		(drill 0.2)
		(layers "F.Cu" "B.Cu")
		(remove_unused_layers yes)
		(keep_end_layers yes)
		(free yes)
		(zone_layer_connections)
		(net 371)
	)
	(via
		(at 133 115.25)
		(size 0.45)
		(drill 0.2)
		(layers "F.Cu" "B.Cu")
		(remove_unused_layers yes)
		(keep_end_layers yes)
		(zone_layer_connections)
		(net 371)
	)
	(segment
		(start 134.5 121.6)
		(end 134.48 121.6)
		(width 0.15)
		(layer "B.Cu")
		(net 371)
	)
	(segment
		(start 119.2 106.32)
		(end 119.2 93.552492)
		(width 0.125)
		(layer "B.Cu")
		(net 371)
	)
	(segment
		(start 122.848008 91.1)
		(end 122.460507 91.487501)
		(width 0.125)
		(layer "B.Cu")
		(net 371)
	)
	(segment
		(start 121.264991 91.487501)
		(end 119.2 93.552492)
		(width 0.125)
		(layer "B.Cu")
		(net 371)
	)
	(segment
		(start 123.09 91.1)
		(end 122.848008 91.1)
		(width 0.125)
		(layer "B.Cu")
		(net 371)
	)
	(segment
		(start 134.48 121.6)
		(end 119.93 107.05)
		(width 0.15)
		(layer "B.Cu")
		(net 371)
	)
	(segment
		(start 119.93 107.05)
		(end 119.2 106.32)
		(width 0.125)
		(layer "B.Cu")
		(net 371)
	)
	(segment
		(start 122.460507 91.487501)
		(end 121.264991 91.487501)
		(width 0.125)
		(layer "B.Cu")
		(net 371)
	)
	(segment
		(start 133 120.1)
		(end 133 115.25)
		(width 0.15)
		(layer "In2.Cu")
		(net 371)
	)
	(segment
		(start 134.5 121.6)
		(end 133 120.1)
		(width 0.15)
		(layer "In2.Cu")
		(net 371)
	)
	(segment
		(start 107.1 103.4)
		(end 107.1 106.415)
		(width 0.15)
		(layer "F.Cu")
		(net 372)
	)
	(segment
		(start 107.725 102.775)
		(end 107.1 103.4)
		(width 0.15)
		(layer "F.Cu")
		(net 372)
	)
	(segment
		(start 107.1 106.415)
		(end 107.4 106.715)
		(width 0.15)
		(layer "F.Cu")
		(net 372)
	)
	(segment
		(start 108.615 102.775)
		(end 107.725 102.775)
		(width 0.15)
		(layer "F.Cu")
		(net 372)
	)
	(segment
		(start 141.69 69.25)
		(end 140.29 69.25)
		(width 0.1)
		(layer "F.Cu")
		(net 373)
	)
	(segment
		(start 140.2892 69.25)
		(end 141.69 69.25)
		(width 0.3)
		(layer "F.Cu")
		(net 373)
	)
	(segment
		(start 146.54 57.95)
		(end 146.54 56.6)
		(width 0.3)
		(layer "F.Cu")
		(net 374)
	)
	(segment
		(start 165.79 66.1)
		(end 167.1408 66.1)
		(width 0.3)
		(layer "F.Cu")
		(net 375)
	)
	(segment
		(start 102.965 101.475)
		(end 104.925 101.475)
		(width 0.15)
		(layer "F.Cu")
		(net 376)
	)
	(segment
		(start 110.4 97.8)
		(end 110.5 97.9)
		(width 0.15)
		(layer "F.Cu")
		(net 376)
	)
	(segment
		(start 110.4 97)
		(end 110.4 97.8)
		(width 0.15)
		(layer "F.Cu")
		(net 376)
	)
	(segment
		(start 104.925 101.475)
		(end 105 101.4)
		(width 0.15)
		(layer "F.Cu")
		(net 376)
	)
	(via
		(at 105 101.4)
		(size 0.45)
		(drill 0.2)
		(layers "F.Cu" "B.Cu")
		(net 376)
	)
	(via
		(at 110.5 97.9)
		(size 0.45)
		(drill 0.2)
		(layers "F.Cu" "B.Cu")
		(net 376)
	)
	(segment
		(start 105 101.4)
		(end 105 100.9)
		(width 0.15)
		(layer "B.Cu")
		(net 376)
	)
	(segment
		(start 110.3 97.9)
		(end 110.5 97.9)
		(width 0.15)
		(layer "B.Cu")
		(net 376)
	)
	(segment
		(start 107.63 98.27)
		(end 108.13 98.27)
		(width 0.15)
		(layer "B.Cu")
		(net 376)
	)
	(segment
		(start 105 100.9)
		(end 107.63 98.27)
		(width 0.15)
		(layer "B.Cu")
		(net 376)
	)
	(segment
		(start 110 97.6)
		(end 110.3 97.9)
		(width 0.15)
		(layer "B.Cu")
		(net 376)
	)
	(segment
		(start 108.8 97.6)
		(end 110 97.6)
		(width 0.15)
		(layer "B.Cu")
		(net 376)
	)
	(segment
		(start 108.13 98.27)
		(end 108.8 97.6)
		(width 0.15)
		(layer "B.Cu")
		(net 376)
	)
	(segment
		(start 95.6 80.9)
		(end 95.6 81.64)
		(width 0.15)
		(layer "F.Cu")
		(net 377)
	)
	(segment
		(start 96.1 80.4)
		(end 95.6 80.9)
		(width 0.15)
		(layer "F.Cu")
		(net 377)
	)
	(segment
		(start 96.6 83.8892)
		(end 96.18 84.3092)
		(width 0.15)
		(layer "F.Cu")
		(net 377)
	)
	(segment
		(start 96.36 81.96)
		(end 96.6 82.2)
		(width 0.15)
		(layer "F.Cu")
		(net 377)
	)
	(segment
		(start 95.92 81.96)
		(end 96.36 81.96)
		(width 0.15)
		(layer "F.Cu")
		(net 377)
	)
	(segment
		(start 95.6 81.64)
		(end 95.92 81.96)
		(width 0.15)
		(layer "F.Cu")
		(net 377)
	)
	(segment
		(start 96.6 82.2)
		(end 96.6 83.8892)
		(width 0.15)
		(layer "F.Cu")
		(net 377)
	)
	(segment
		(start 88.675 107.825)
		(end 88.675 109.1742)
		(width 0.1)
		(layer "F.Cu")
		(net 378)
	)
	(segment
		(start 145.75749 91.59171)
		(end 145 92.3492)
		(width 0.15)
		(layer "F.Cu")
		(net 379)
	)
	(segment
		(start 145.75749 89.20749)
		(end 145.75749 91.59171)
		(width 0.15)
		(layer "F.Cu")
		(net 379)
	)
	(via
		(at 145.75749 89.20749)
		(size 0.45)
		(drill 0.2)
		(layers "F.Cu" "B.Cu")
		(remove_unused_layers yes)
		(keep_end_layers yes)
		(zone_layer_connections)
		(net 379)
	)
	(segment
		(start 148.8 88.8)
		(end 148.8 86.6)
		(width 0.15)
		(layer "B.Cu")
		(net 379)
	)
	(segment
		(start 148.8 86.6)
		(end 148.425 86.225)
		(width 0.15)
		(layer "B.Cu")
		(net 379)
	)
	(segment
		(start 148.425 86.225)
		(end 147.55 86.225)
		(width 0.15)
		(layer "B.Cu")
		(net 379)
	)
	(segment
		(start 148.39251 89.20749)
		(end 148.8 88.8)
		(width 0.15)
		(layer "B.Cu")
		(net 379)
	)
	(segment
		(start 145.75749 89.20749)
		(end 148.39251 89.20749)
		(width 0.15)
		(layer "B.Cu")
		(net 379)
	)
	(segment
		(start 145 91.2)
		(end 145 89.6)
		(width 0.15)
		(layer "F.Cu")
		(net 380)
	)
	(via
		(at 145 89.6)
		(size 0.45)
		(drill 0.2)
		(layers "F.Cu" "B.Cu")
		(remove_unused_layers yes)
		(keep_end_layers yes)
		(zone_layer_connections)
		(net 380)
	)
	(segment
		(start 145 89.6)
		(end 145 89.4)
		(width 0.15)
		(layer "B.Cu")
		(net 380)
	)
	(segment
		(start 145 89.4)
		(end 146.075 88.325)
		(width 0.15)
		(layer "B.Cu")
		(net 380)
	)
	(segment
		(start 146.075 88.325)
		(end 146.075 87.05)
		(width 0.15)
		(layer "B.Cu")
		(net 380)
	)
	(segment
		(start 134.315 113.15)
		(end 134.315 112.15)
		(width 0.15)
		(layer "F.Cu")
		(net 381)
	)
	(segment
		(start 134.315 112.12)
		(end 133.345 111.15)
		(width 0.15)
		(layer "F.Cu")
		(net 381)
	)
	(segment
		(start 154.98 64.8)
		(end 154.23 64.8)
		(width 0.15)
		(layer "B.Cu")
		(net 382)
	)
	(segment
		(start 154.23 64.8)
		(end 154.23 66.7)
		(width 0.15)
		(layer "B.Cu")
		(net 382)
	)
	(segment
		(start 154.305 66.625)
		(end 154.305 64.875)
		(width 0.3)
		(layer "B.Cu")
		(net 382)
	)
	(segment
		(start 154.305 64.875)
		(end 154.23 64.8)
		(width 0.3)
		(layer "B.Cu")
		(net 382)
	)
	(segment
		(start 154.23 66.7)
		(end 154.305 66.625)
		(width 0.3)
		(layer "B.Cu")
		(net 382)
	)
	(segment
		(start 154.23 64.8)
		(end 156.165 64.8)
		(width 0.3)
		(layer "B.Cu")
		(net 382)
	)
	(segment
		(start 156.23 64.865)
		(end 155.045 64.865)
		(width 0.15)
		(layer "B.Cu")
		(net 382)
	)
	(zone
		(net 274)
		(net_name "/Power Supply/1V5_OUT")
		(layer "F.Cu")
		(hatch edge 0.508)
		(priority 2)
		(connect_pads yes
			(clearance 0.1)
		)
		(min_thickness 0.1)
		(filled_areas_thickness no)
		(fill yes
			(thermal_gap 0.508)
			(thermal_bridge_width 0.508)
		)
		(polygon
			(pts
				(xy 144.34 61.5) (xy 144.09 61.5) (xy 144.09 63.15) (xy 144.34 63.15) (xy 144.34 65.8) (xy 143.09 65.8)
				(xy 143.09 64.85) (xy 140.09 64.85) (xy 140.09 63.55) (xy 141.49 63.55) (xy 141.49 61.7) (xy 139.09 61.7)
				(xy 139.09 59.3) (xy 140.3 59.3) (xy 140.3 59.95) (xy 144.34 59.95)
			)
		)
	)
	(zone
		(net 1)
		(net_name "GND")
		(layer "F.Cu")
		(hatch edge 0.508)
		(connect_pads yes
			(clearance 0.1)
		)
		(min_thickness 0.1)
		(filled_areas_thickness no)
		(fill yes
			(thermal_gap 0.508)
			(thermal_bridge_width 0.508)
		)
		(polygon
			(pts
				(xy 141.04 102.95) (xy 141.04 103.85) (xy 146.19 103.85) (xy 148.09 113.25) (xy 148.09 117.4) (xy 138.24 117.35)
				(xy 138.24 110.19) (xy 138.24 110.15) (xy 138.24 109.23) (xy 138.24 109.18) (xy 138.24 102.95)
			)
		)
	)
	(zone
		(net 270)
		(net_name "Net-(U7-FB)")
		(layer "F.Cu")
		(hatch edge 0.508)
		(connect_pads yes
			(clearance 0.1)
		)
		(min_thickness 0.1)
		(filled_areas_thickness no)
		(fill yes
			(thermal_gap 0.508)
			(thermal_bridge_width 0.508)
		)
		(polygon
			(pts
				(xy 169.43 68.25) (xy 163.98 68.25) (xy 163.98 66.55) (xy 169.43 66.55)
			)
		)
	)
	(zone
		(net 263)
		(net_name "Net-(U6-FB)")
		(layer "F.Cu")
		(hatch edge 0.508)
		(connect_pads yes
			(clearance 0.1)
		)
		(min_thickness 0.1)
		(filled_areas_thickness no)
		(fill yes
			(thermal_gap 0.508)
			(thermal_bridge_width 0.508)
		)
		(polygon
			(pts
				(xy 148.88 58.6) (xy 147.03 58.6) (xy 147.03 55.25) (xy 148.88 55.25)
			)
		)
	)
	(zone
		(net 2)
		(net_name "+3V3")
		(layer "F.Cu")
		(hatch edge 0.508)
		(priority 6)
		(connect_pads yes
			(clearance 0.1)
		)
		(min_thickness 0.1)
		(filled_areas_thickness no)
		(fill yes
			(thermal_gap 0.508)
			(thermal_bridge_width 0.508)
		)
		(polygon
			(pts
				(xy 146.14 107.3) (xy 146.14 105.8) (xy 145.04 105.8) (xy 145.04 105.7) (xy 149.54 105.7) (xy 149.54 117.1)
				(xy 146.44 117.1) (xy 146.44 114.6) (xy 147.84 114.6) (xy 147.84 113.2) (xy 144.99 113.2) (xy 144.99 109.9)
				(xy 146.54 109.9) (xy 146.54 108.5) (xy 144.84 108.5) (xy 144.84 107.3)
			)
		)
	)
	(zone
		(net 14)
		(net_name "+5V")
		(layer "F.Cu")
		(hatch edge 0.508)
		(priority 10)
		(connect_pads yes
			(clearance 0.1)
		)
		(min_thickness 0.1)
		(filled_areas_thickness no)
		(fill yes
			(thermal_gap 0.508)
			(thermal_bridge_width 0.508)
		)
		(polygon
			(pts
				(xy 147.19 68.74) (xy 147.19 66.74) (xy 146.64 66.74) (xy 146.64 63.09) (xy 148.74 63.09) (xy 148.74 65.89)
				(xy 151.39 65.89) (xy 151.39 67.94) (xy 153.59 67.94) (xy 153.59 70.54) (xy 158.49 70.54) (xy 158.49 68.34)
				(xy 166.69 68.34) (xy 166.69 69.8) (xy 165.59 69.8) (xy 165.59 69) (xy 162.09 69) (xy 162.09 69.8)
				(xy 160.89 69.8) (xy 160.89 73.74) (xy 153.59 73.74) (xy 153.59 75.74) (xy 151.99 75.74) (xy 151.99 72.1)
				(xy 151.39 72.1) (xy 151.39 68.74)
			)
		)
	)
	(zone
		(net 17)
		(net_name "/Peripherals/FFC1_3V3")
		(layer "F.Cu")
		(hatch edge 0.508)
		(connect_pads yes
			(clearance 0.1)
		)
		(min_thickness 0.1)
		(filled_areas_thickness no)
		(fill yes
			(thermal_gap 0.508)
			(thermal_bridge_width 0.508)
		)
		(polygon
			(pts
				(xy 170.33 89.65) (xy 167.98 89.65) (xy 166.98 90.65) (xy 161.83 90.65) (xy 161.83 88.65) (xy 170.33 88.65)
			)
		)
	)
	(zone
		(net 49)
		(net_name "1V0_Clean")
		(layer "F.Cu")
		(hatch edge 0.508)
		(priority 1)
		(connect_pads yes
			(clearance 0.1)
		)
		(min_thickness 0.1)
		(filled_areas_thickness no)
		(fill yes
			(thermal_gap 0.508)
			(thermal_bridge_width 0.508)
		)
		(polygon
			(pts
				(xy 139.44 107.3) (xy 138.186 107.3) (xy 138.19 107.45) (xy 136.69 107.45) (xy 136.69 104.95) (xy 138.19 104.95)
				(xy 138.19 105.2) (xy 139.44 105.2)
			)
		)
	)
	(zone
		(net 16)
		(net_name "/Peripherals/FFC1_5V")
		(layer "F.Cu")
		(hatch edge 0.508)
		(connect_pads yes
			(clearance 0.1)
		)
		(min_thickness 0.1)
		(filled_areas_thickness no)
		(fill yes
			(thermal_gap 0.508)
			(thermal_bridge_width 0.508)
		)
		(polygon
			(pts
				(xy 169.03 85.65) (xy 169.03 87.65) (xy 170.33 87.65) (xy 170.33 88.45) (xy 167.98 88.45) (xy 167.98 86.15)
				(xy 162.98 86.15) (xy 162.98 85.1) (xy 168.48 85.1)
			)
		)
	)
	(zone
		(net 1)
		(net_name "GND")
		(layer "F.Cu")
		(hatch edge 0.508)
		(priority 1)
		(connect_pads yes
			(clearance 0.1)
		)
		(min_thickness 0.1)
		(filled_areas_thickness no)
		(fill yes
			(thermal_gap 0.508)
			(thermal_bridge_width 0.508)
		)
		(polygon
			(pts
				(xy 149.44 76.5) (xy 146.34 76.5) (xy 145.69 78.4) (xy 144.34 78.4) (xy 144.34 76.55) (xy 145.29 76.55)
				(xy 145.29 75.5) (xy 148.49 75.5) (xy 148.49 74.15) (xy 149.44 74.15)
			)
		)
	)
	(zone
		(net 3)
		(net_name "+1V2")
		(layer "F.Cu")
		(hatch edge 0.508)
		(priority 1)
		(connect_pads yes
			(clearance 0.1)
		)
		(min_thickness 0.1)
		(filled_areas_thickness no)
		(fill yes
			(thermal_gap 0.508)
			(thermal_bridge_width 0.508)
		)
		(polygon
			(pts
				(xy 140.94 115.9) (xy 138.09 115.9) (xy 138.09 117.1) (xy 136.79 117.1) (xy 136.79 114.7) (xy 140.94 114.7)
			)
		)
	)
	(zone
		(net 276)
		(net_name "/Power Supply/1V0_SW")
		(layer "F.Cu")
		(hatch edge 0.508)
		(priority 3)
		(connect_pads yes
			(clearance 0.1)
		)
		(min_thickness 0.1)
		(filled_areas_thickness no)
		(fill yes
			(thermal_gap 0.508)
			(thermal_bridge_width 0.508)
		)
		(polygon
			(pts
				(xy 142.39 71.15) (xy 142.39 68.75) (xy 144.94 68.75) (xy 144.94 69.75) (xy 143.64 69.75) (xy 143.64 75.45)
				(xy 140.99 75.45) (xy 139.78 74.3) (xy 139.79 72.1) (xy 139.78 71.15)
			)
		)
	)
	(zone
		(net 275)
		(net_name "/Power Supply/3V3_OUT")
		(layer "F.Cu")
		(hatch edge 0.508)
		(priority 2)
		(connect_pads yes
			(clearance 0.1)
		)
		(min_thickness 0.1)
		(filled_areas_thickness no)
		(fill yes
			(thermal_gap 0.508)
			(thermal_bridge_width 0.508)
		)
		(polygon
			(pts
				(xy 160.79 63.9) (xy 160.79 65) (xy 159.19 65) (xy 159.19 63.9) (xy 159.19 63.16) (xy 160.38 63.16)
				(xy 160.38 57.85) (xy 162.09 57.85) (xy 163.19 57.85) (xy 163.19 59.9) (xy 163.79 59.9) (xy 163.79 63.9)
			)
		)
	)
	(zone
		(net 329)
		(net_name "/Power Supply/FFC2_5V_1")
		(layer "F.Cu")
		(name "DDR3_CLEARNECE_OVERRIDE")
		(hatch edge 0.508)
		(connect_pads yes
			(clearance 0.1)
		)
		(min_thickness 0.1)
		(filled_areas_thickness no)
		(fill yes
			(thermal_gap 0.508)
			(thermal_bridge_width 0.508)
		)
		(polygon
			(pts
				(xy 162.03 111.65) (xy 157.03 111.65) (xy 157.03 108.9) (xy 162.03 108.9)
			)
		)
	)
	(zone
		(net 1)
		(net_name "GND")
		(layer "F.Cu")
		(hatch edge 0.508)
		(connect_pads yes
			(clearance 0.1)
		)
		(min_thickness 0.1)
		(filled_areas_thickness no)
		(fill yes
			(thermal_gap 0.508)
			(thermal_bridge_width 0.508)
		)
		(polygon
			(pts
				(xy 145.99 59.95) (xy 145.99 61.5) (xy 145.49 61.5) (xy 145.49 63) (xy 146.49 63) (xy 146.49 66.8)
				(xy 140.14 66.8) (xy 140.14 64.91) (xy 142.99 64.91) (xy 142.990739 65.86) (xy 144.39 65.86) (xy 144.39 63.05)
				(xy 144.14 63.05) (xy 144.14 61.55) (xy 144.39 61.55) (xy 144.39 59.95)
			)
		)
	)
	(zone
		(net 1)
		(net_name "GND")
		(layer "F.Cu")
		(hatch edge 0.508)
		(connect_pads yes
			(clearance 0.1)
		)
		(min_thickness 0.1)
		(filled_areas_thickness no)
		(fill yes
			(thermal_gap 0.508)
			(thermal_bridge_width 0.508)
		)
		(polygon
			(pts
				(xy 150.43 63.65) (xy 149.33 63.65) (xy 149.33 65.8) (xy 151.88 65.8) (xy 151.88 65) (xy 151.25 65)
				(xy 151.23 62.25) (xy 150.43 62.25)
			)
		)
	)
	(zone
		(net 278)
		(net_name "/Power Supply/3V3_SW")
		(layer "F.Cu")
		(hatch edge 0.508)
		(priority 3)
		(connect_pads yes
			(clearance 0.1)
		)
		(min_thickness 0.1)
		(filled_areas_thickness no)
		(fill yes
			(thermal_gap 0.508)
			(thermal_bridge_width 0.508)
		)
		(polygon
			(pts
				(xy 165.09 64.2) (xy 165.09 66.5) (xy 162.44 66.5) (xy 162.44 65.6) (xy 163.84 65.6) (xy 163.84 59.9)
				(xy 166.49 59.9) (xy 166.49 63.25) (xy 167.69 63.25) (xy 167.69 64.215)
			)
		)
	)
	(zone
		(net 1)
		(net_name "GND")
		(layer "F.Cu")
		(hatch edge 0.508)
		(connect_pads yes
			(clearance 0.1)
		)
		(min_thickness 0.1)
		(filled_areas_thickness no)
		(fill yes
			(thermal_gap 0.508)
			(thermal_bridge_width 0.508)
		)
		(polygon
			(pts
				(xy 160.29 62.95) (xy 159.19 62.95) (xy 159.19 58.95) (xy 160.29 58.95)
			)
		)
	)
	(zone
		(net 325)
		(net_name "USB_POWER_IN")
		(layer "F.Cu")
		(hatch edge 0.508)
		(priority 1)
		(connect_pads yes
			(clearance 0.1)
		)
		(min_thickness 0.1)
		(filled_areas_thickness no)
		(fill yes
			(thermal_gap 0.508)
			(thermal_bridge_width 0.508)
		)
		(polygon
			(pts
				(xy 152.03 63.55) (xy 156.03 63.55) (xy 156.03 62.25) (xy 156.83 62.25) (xy 156.83 64.45) (xy 156.13 64.45)
				(xy 155.03 65.65) (xy 153.43 65.65) (xy 152.23 64.45) (xy 151.23 64.45) (xy 151.23 62.25) (xy 152.03 62.25)
			)
		)
	)
	(zone
		(net 328)
		(net_name "/Power Supply/5V_3V3_IN")
		(layer "F.Cu")
		(hatch edge 0.508)
		(priority 1)
		(connect_pads yes
			(clearance 0.1)
		)
		(min_thickness 0.1)
		(filled_areas_thickness no)
		(fill yes
			(thermal_gap 0.508)
			(thermal_bridge_width 0.508)
		)
		(polygon
			(pts
				(xy 163.89 66.55) (xy 163.89 68.25) (xy 158.99 68.25) (xy 158.99 66.55)
			)
		)
	)
	(zone
		(net 61)
		(net_name "Net-(U5-BST)")
		(layer "F.Cu")
		(hatch edge 0.508)
		(connect_pads yes
			(clearance 0.1)
		)
		(min_thickness 0.1)
		(filled_areas_thickness no)
		(fill yes
			(thermal_gap 0.508)
			(thermal_bridge_width 0.508)
		)
		(polygon
			(pts
				(xy 142.33 71.1) (xy 139.53 71.1) (xy 139.53 69.75) (xy 142.33 69.75)
			)
		)
	)
	(zone
		(net 1)
		(net_name "GND")
		(layer "F.Cu")
		(hatch edge 0.508)
		(connect_pads yes
			(clearance 0.1)
		)
		(min_thickness 0.1)
		(filled_areas_thickness no)
		(fill yes
			(thermal_gap 0.508)
			(thermal_bridge_width 0.508)
		)
		(polygon
			(pts
				(xy 156.83 62.25) (xy 157.63 62.25) (xy 157.63 63.65) (xy 159.09 63.65) (xy 159.09 65.1) (xy 160.905 65.1)
				(xy 160.905 64) (xy 163.705 64) (xy 163.705 65.5) (xy 162.405 65.5) (xy 162.405 66.5) (xy 158.89 66.5)
				(xy 158.89 67.8) (xy 156.905 67.8) (xy 156.83 65.45) (xy 156.83 63.67)
			)
		)
	)
	(zone
		(net 1)
		(net_name "GND")
		(layer "F.Cu")
		(hatch edge 0.508)
		(priority 1)
		(connect_pads yes
			(clearance 0.1)
		)
		(min_thickness 0.1)
		(filled_areas_thickness no)
		(fill yes
			(thermal_gap 0.508)
			(thermal_bridge_width 0.508)
		)
		(polygon
			(pts
				(xy 156.19 76.04) (xy 153.69 76.04) (xy 153.69 73.84) (xy 156.19 73.84)
			)
		)
	)
	(zone
		(net 1)
		(net_name "GND")
		(layer "F.Cu")
		(hatch edge 0.508)
		(priority 1)
		(connect_pads yes
			(clearance 0.1)
		)
		(min_thickness 0.1)
		(filled_areas_thickness no)
		(fill yes
			(thermal_gap 0.508)
			(thermal_bridge_width 0.508)
		)
		(polygon
			(pts
				(xy 143.69 69.8) (xy 145.09 69.8) (xy 147.19 69.8) (xy 147.19 68.8) (xy 150.24 68.8) (xy 150.24 71.1)
				(xy 147.04 71.1) (xy 147.04 71.4) (xy 143.69 71.4)
			)
		)
	)
	(zone
		(net 19)
		(net_name "FFC2_5V")
		(layer "F.Cu")
		(name "DDR3_CLEARNECE_OVERRIDE")
		(hatch edge 0.508)
		(priority 5)
		(connect_pads yes
			(clearance 0.1)
		)
		(min_thickness 0.1)
		(filled_areas_thickness no)
		(fill yes
			(thermal_gap 0.508)
			(thermal_bridge_width 0.508)
		)
		(polygon
			(pts
				(xy 155.2816 109.450013) (xy 155.28 111.6) (xy 154.43 111.6) (xy 152.03 114.15) (xy 152.03 118.4)
				(xy 146.75 118.4) (xy 146 119.9) (xy 137.53 119.9) (xy 137.53 120.9) (xy 136.53 120.9) (xy 136.53 118.65)
				(xy 145.25 118.65) (xy 146.03 117.4) (xy 150.53 117.4) (xy 150.53 113.65) (xy 154.03 110.15) (xy 154.0316 109.440013)
			)
		)
	)
	(zone
		(net 4)
		(net_name "1V0_Power")
		(layer "F.Cu")
		(hatch edge 0.508)
		(connect_pads yes
			(clearance 0.1)
		)
		(min_thickness 0.1)
		(filled_areas_thickness no)
		(fill yes
			(thermal_gap 0.508)
			(thermal_bridge_width 0.508)
		)
		(polygon
			(pts
				(xy 151.948538 89.55) (xy 152.446879 89.951982) (xy 152.431025 91.951982) (xy 151.95 92.35) (xy 151.89 96.9)
				(xy 146.09 102.7) (xy 139.49 102.7) (xy 136.79 102.7) (xy 136.79 103.1) (xy 131.09 103.1) (xy 131.09 99.5)
				(xy 133.19 99.5) (xy 133.19 98.7) (xy 141.89 98.7) (xy 146.49 94.1) (xy 146.49 76.7) (xy 149.49 76.7)
				(xy 149.49 74.1) (xy 148.49 74.1) (xy 148.49 72.3) (xy 152.089952 72.3063)
			)
		)
	)
	(zone
		(net 50)
		(net_name "+1V8")
		(layer "F.Cu")
		(hatch edge 0.508)
		(priority 1)
		(connect_pads yes
			(clearance 0.1)
		)
		(min_thickness 0.1)
		(filled_areas_thickness no)
		(fill yes
			(thermal_gap 0.508)
			(thermal_bridge_width 0.508)
		)
		(polygon
			(pts
				(xy 139.59 112.6) (xy 138.19 112.6) (xy 138.19 113.9) (xy 136.89 113.9) (xy 136.89 111.5) (xy 137.99 111.5)
				(xy 137.99 110.2) (xy 139.59 110.2)
			)
		)
	)
	(zone
		(net 273)
		(net_name "/Power Supply/1V0_OUT")
		(layer "F.Cu")
		(hatch edge 0.508)
		(priority 2)
		(connect_pads yes
			(clearance 0.1)
		)
		(min_thickness 0.1)
		(filled_areas_thickness no)
		(fill yes
			(thermal_gap 0.508)
			(thermal_bridge_width 0.508)
		)
		(polygon
			(pts
				(xy 147.09 71.55) (xy 147.09 71.15) (xy 149.69 71.15) (xy 149.69 72.3) (xy 148.44 72.3) (xy 148.44 75.45)
				(xy 145.32 75.45) (xy 145.25 76.4) (xy 144.33 76.4) (xy 144.32 75.53) (xy 143.69 75.52) (xy 143.69 71.55)
			)
		)
	)
	(zone
		(net 248)
		(net_name "+1V5")
		(layer "F.Cu")
		(hatch edge 0.508)
		(priority 100)
		(connect_pads yes
			(clearance 0.1)
		)
		(min_thickness 0.1)
		(filled_areas_thickness no)
		(fill yes
			(thermal_gap 0.508)
			(thermal_bridge_width 0.508)
		)
		(polygon
			(pts
				(xy 141.39 63.4) (xy 139.99 63.4) (xy 139.99 64.6) (xy 137.19 64.6) (xy 137.19 58.1) (xy 138.89 58.1)
				(xy 138.89 61.7) (xy 141.39 61.7)
			)
		)
	)
	(zone
		(net 326)
		(net_name "/Power Supply/5V_1V0_IN")
		(layer "F.Cu")
		(hatch edge 0.508)
		(priority 4)
		(connect_pads yes
			(clearance 0.1)
		)
		(min_thickness 0.1)
		(filled_areas_thickness no)
		(fill yes
			(thermal_gap 0.508)
			(thermal_bridge_width 0.508)
		)
		(polygon
			(pts
				(xy 147.09 66.9) (xy 147.09 69.75) (xy 145.04 69.75) (xy 145.04 68.7) (xy 142.39 68.7) (xy 142.39 66.9)
			)
		)
	)
	(zone
		(net 277)
		(net_name "/Power Supply/1V5_SW")
		(layer "F.Cu")
		(hatch edge 0.508)
		(priority 4)
		(connect_pads yes
			(clearance 0.1)
		)
		(min_thickness 0.1)
		(filled_areas_thickness no)
		(fill yes
			(thermal_gap 0.508)
			(thermal_bridge_width 0.508)
		)
		(polygon
			(pts
				(xy 144.64 58.65) (xy 147.04 58.65) (xy 147.04 61.2) (xy 146.04 61.2) (xy 146.04 59.8) (xy 140.34 59.8)
				(xy 140.34 57.25) (xy 143.69 57.25) (xy 143.69 55.9) (xy 144.655 55.9)
			)
		)
	)
	(zone
		(net 1)
		(net_name "GND")
		(layer "F.Cu")
		(hatch edge 0.508)
		(priority 3)
		(connect_pads yes
			(clearance 0.1)
		)
		(min_thickness 0.1)
		(filled_areas_thickness no)
		(fill yes
			(thermal_gap 0.508)
			(thermal_bridge_width 0.508)
		)
		(polygon
			(pts
				(xy 138.89 74.6) (xy 141.39 78.1) (xy 140.49 78.8) (xy 137.69 75) (xy 137.69 64.6) (xy 138.89 64.6)
			)
		)
	)
	(zone
		(net 267)
		(net_name "Net-(U5-FB)")
		(layer "F.Cu")
		(hatch edge 0.508)
		(priority 20)
		(connect_pads yes
			(clearance 0.1)
		)
		(min_thickness 0.1)
		(filled_areas_thickness no)
		(fill yes
			(thermal_gap 0.508)
			(thermal_bridge_width 0.508)
		)
		(polygon
			(pts
				(xy 142.33 68.7) (xy 138.98 68.7) (xy 138.98 66.9) (xy 142.33 66.9)
			)
		)
	)
	(zone
		(net 2)
		(net_name "+3V3")
		(layer "F.Cu")
		(hatch edge 0.508)
		(connect_pads yes
			(clearance 0.1)
		)
		(min_thickness 0.1)
		(filled_areas_thickness no)
		(fill yes
			(thermal_gap 0.508)
			(thermal_bridge_width 0.508)
		)
		(polygon
			(pts
				(xy 165.89 57.7) (xy 159.69 57.7) (xy 159.69 55.3) (xy 165.89 55.3)
			)
		)
	)
	(zone
		(net 327)
		(net_name "/Power Supply/5V_1V5_IN")
		(layer "F.Cu")
		(hatch edge 0.508)
		(priority 3)
		(connect_pads yes
			(clearance 0.1)
		)
		(min_thickness 0.1)
		(filled_areas_thickness no)
		(fill yes
			(thermal_gap 0.508)
			(thermal_bridge_width 0.508)
		)
		(polygon
			(pts
				(xy 148.89 62.95) (xy 145.54 62.95) (xy 145.54 61.55) (xy 146.04 61.55) (xy 146.04 61.3) (xy 147.09 61.3)
				(xy 147.09 58.7) (xy 148.89 58.7)
			)
		)
	)
	(zone
		(net 140)
		(net_name "Net-(U7-BST)")
		(layer "F.Cu")
		(hatch edge 0.508)
		(connect_pads yes
			(clearance 0.1)
		)
		(min_thickness 0.1)
		(filled_areas_thickness no)
		(fill yes
			(thermal_gap 0.508)
			(thermal_bridge_width 0.508)
		)
		(polygon
			(pts
				(xy 167.68 65.65) (xy 165.13 65.65) (xy 165.13 64.25) (xy 167.68 64.25)
			)
		)
	)
	(zone
		(net 304)
		(net_name "/Power Supply/5V_I")
		(layer "F.Cu")
		(hatch edge 0.508)
		(connect_pads yes
			(clearance 0.1)
		)
		(min_thickness 0.1)
		(filled_areas_thickness no)
		(fill yes
			(thermal_gap 0.508)
			(thermal_bridge_width 0.508)
		)
		(polygon
			(pts
				(xy 155.89 68.1) (xy 156.78 68.1) (xy 158.28 68.1) (xy 158.28 70.5) (xy 156.09 70.5) (xy 156.09 70.3)
				(xy 153.69 70.3) (xy 153.69 66.4) (xy 155.89 66.4)
			)
		)
	)
	(zone
		(net 65)
		(net_name "Net-(U6-BST)")
		(layer "F.Cu")
		(hatch edge 0.508)
		(connect_pads yes
			(clearance 0.1)
		)
		(min_thickness 0.1)
		(filled_areas_thickness no)
		(fill yes
			(thermal_gap 0.508)
			(thermal_bridge_width 0.508)
		)
		(polygon
			(pts
				(xy 146.03 58.55) (xy 144.73 58.55) (xy 144.73 55.9) (xy 146.03 55.9)
			)
		)
	)
	(zone
		(net 1)
		(net_name "GND")
		(layer "B.Cu")
		(hatch edge 0.508)
		(priority 10)
		(connect_pads yes
			(clearance 0.1)
		)
		(min_thickness 0.1)
		(filled_areas_thickness no)
		(fill yes
			(thermal_gap 0.508)
			(thermal_bridge_width 0.508)
		)
		(polygon
			(pts
				(xy 164.03 59.15) (xy 164.03 68.15) (xy 155.53 68.15) (xy 155.53 66.15) (xy 150.28 66.15) (xy 150.28 69.4)
				(xy 141.03 69.4) (xy 141.03 55.65) (xy 160.53 55.65)
			)
		)
	)
	(zone
		(net 6)
		(net_name "Vtt")
		(layer "B.Cu")
		(hatch edge 0.508)
		(connect_pads yes
			(clearance 0.1)
		)
		(min_thickness 0.1)
		(filled_areas_thickness no)
		(fill yes
			(thermal_gap 0.508)
			(thermal_bridge_width 0.508)
		)
		(polygon
			(pts
				(xy 134.388769 56.624248) (xy 129.638769 56.684248) (xy 129.63 58.25) (xy 131.68 58.25) (xy 131.651076 62.264122)
				(xy 129.601076 62.314122) (xy 129.63 60.3) (xy 128.23 58.7) (xy 128.23 57.45) (xy 123.31 57.45)
				(xy 123.431325 58.057913) (xy 124.381417 59.110941) (xy 124.73 59.25) (xy 124.73 61.35) (xy 124.48 61.6)
				(xy 124.48 66.45) (xy 123.83 66.45) (xy 123.73 59.425) (xy 122.78 58.4) (xy 122.78 57.45) (xy 119.08 57.45)
				(xy 119.08 55.3) (xy 134.38 55.3)
			)
		)
	)
	(zone
		(net 13)
		(net_name "/FPGA Power/VCC_PLLDPHY")
		(layer "B.Cu")
		(hatch edge 0.508)
		(connect_pads yes
			(clearance 0.1)
		)
		(min_thickness 0.1)
		(filled_areas_thickness no)
		(fill yes
			(thermal_gap 0.508)
			(thermal_bridge_width 0.508)
		)
		(polygon
			(pts
				(xy 134.84 98.75) (xy 133.09 98.75) (xy 133.09 96.4) (xy 134.84 96.4)
			)
		)
	)
	(zone
		(net 304)
		(net_name "/Power Supply/5V_I")
		(layer "B.Cu")
		(hatch edge 0.508)
		(connect_pads yes
			(clearance 0.1)
		)
		(min_thickness 0.1)
		(filled_areas_thickness no)
		(fill yes
			(thermal_gap 0.508)
			(thermal_bridge_width 0.508)
		)
		(polygon
			(pts
				(xy 158.29 71.9) (xy 156.09 71.9) (xy 156.09 68.1) (xy 158.29 68.1)
			)
		)
	)
	(zone
		(net 329)
		(net_name "/Power Supply/FFC2_5V_1")
		(layer "B.Cu")
		(name "DDR3_CLEARNECE_OVERRIDE")
		(hatch edge 0.508)
		(connect_pads yes
			(clearance 0.1)
		)
		(min_thickness 0.1)
		(filled_areas_thickness no)
		(fill yes
			(thermal_gap 0.508)
			(thermal_bridge_width 0.508)
		)
		(polygon
			(pts
				(xy 165.78 74.4) (xy 162.78 74.4) (xy 162.78 75.4) (xy 161.78 75.4) (xy 161.78 73.4) (xy 162.53 73.4)
				(xy 163.03 72.9) (xy 163.03 72.4) (xy 165.78 72.4)
			)
		)
	)
	(zone
		(net 10)
		(net_name "/FPGA Power/VCC_AUXA")
		(layer "B.Cu")
		(hatch edge 0.508)
		(priority 1)
		(connect_pads yes
			(clearance 0.1)
		)
		(min_thickness 0.1)
		(filled_areas_thickness no)
		(fill yes
			(thermal_gap 0.508)
			(thermal_bridge_width 0.508)
		)
		(polygon
			(pts
				(xy 137.39 92.35) (xy 134.89 92.35) (xy 134.89 90.8) (xy 137.39 90.8)
			)
		)
	)
	(zone
		(net 50)
		(net_name "+1V8")
		(layer "B.Cu")
		(hatch edge 0.508)
		(connect_pads yes
			(clearance 0.1)
		)
		(min_thickness 0.1)
		(filled_areas_thickness no)
		(fill yes
			(thermal_gap 0.508)
			(thermal_bridge_width 0.508)
		)
		(polygon
			(pts
				(xy 138.5 92.3) (xy 137.7 92.3) (xy 137.7 89.1) (xy 136.74 89.1) (xy 136.74 85.6) (xy 134.1 82.9)
				(xy 130.79 82.9) (xy 130.79 80.2) (xy 133.7 80.2) (xy 138.5 85)
			)
		)
	)
	(zone
		(net 49)
		(net_name "1V0_Clean")
		(layer "B.Cu")
		(hatch edge 0.508)
		(priority 1)
		(connect_pads yes
			(clearance 0.1)
		)
		(min_thickness 0.1)
		(filled_areas_thickness no)
		(fill yes
			(thermal_gap 0.508)
			(thermal_bridge_width 0.508)
		)
		(polygon
			(pts
				(xy 136.39 100.3) (xy 130.04 100.3) (xy 130.04 98.85) (xy 134.89 98.85) (xy 134.89 97.45) (xy 136.39 97.45)
			)
		)
	)
	(zone
		(net 9)
		(net_name "/FPGA Power/VCC_AUX")
		(layer "B.Cu")
		(hatch edge 0.508)
		(connect_pads yes
			(clearance 0.1)
		)
		(min_thickness 0.1)
		(filled_areas_thickness no)
		(fill yes
			(thermal_gap 0.508)
			(thermal_bridge_width 0.508)
		)
		(polygon
			(pts
				(xy 130.5 82.7) (xy 127.99 82.7) (xy 127.99 80.2) (xy 130.5 80.2)
			)
		)
	)
	(zone
		(net 12)
		(net_name "/FPGA Power/VCC_ADPHY")
		(layer "B.Cu")
		(hatch edge 0.508)
		(priority 2)
		(connect_pads yes
			(clearance 0.1)
		)
		(min_thickness 0.1)
		(filled_areas_thickness no)
		(fill yes
			(thermal_gap 0.508)
			(thermal_bridge_width 0.508)
		)
		(polygon
			(pts
				(xy 136.74 97.25) (xy 134.54 97.25) (xy 134.54 95.65) (xy 136.74 95.65)
			)
		)
	)
	(zone
		(net 1)
		(net_name "GND")
		(layer "B.Cu")
		(hatch edge 0.508)
		(connect_pads yes
			(clearance 0.1)
		)
		(min_thickness 0.1)
		(filled_areas_thickness no)
		(fill yes
			(thermal_gap 0.508)
			(thermal_bridge_width 0.508)
		)
		(polygon
			(pts
				(xy 149.69 117.45) (xy 137.69 117.45) (xy 137.69 102.95) (xy 149.69 102.95)
			)
		)
	)
	(zone
		(net 11)
		(net_name "/FPGA Power/VCC_DPHY")
		(layer "B.Cu")
		(hatch edge 0.508)
		(connect_pads yes
			(clearance 0.1)
		)
		(min_thickness 0.1)
		(filled_areas_thickness no)
		(fill yes
			(thermal_gap 0.508)
			(thermal_bridge_width 0.508)
		)
		(polygon
			(pts
				(xy 129.59 100.4) (xy 127.04 100.4) (xy 127.04 98.9) (xy 129.59 98.9)
			)
		)
	)
	(zone
		(net 3)
		(net_name "+1V2")
		(layer "B.Cu")
		(hatch edge 0.508)
		(connect_pads yes
			(clearance 0.1)
		)
		(min_thickness 0.1)
		(filled_areas_thickness no)
		(fill yes
			(thermal_gap 0.508)
			(thermal_bridge_width 0.508)
		)
		(polygon
			(pts
				(xy 116.99 103.15) (xy 114.59 105.55) (xy 108.49 99.45) (xy 110.89 97.05)
			)
		)
	)
	(zone
		(net 13)
		(net_name "/FPGA Power/VCC_PLLDPHY")
		(layer "B.Cu")
		(hatch edge 0.508)
		(priority 3)
		(connect_pads yes
			(clearance 0.1)
		)
		(min_thickness 0.1)
		(filled_areas_thickness no)
		(fill yes
			(thermal_gap 0.508)
			(thermal_bridge_width 0.508)
		)
		(polygon
			(pts
				(xy 134.42 96.030001) (xy 134.42 98.590001) (xy 129.24 98.6) (xy 129.24 95.12) (xy 129.97 95.12)
				(xy 129.97 96.03)
			)
		)
	)
	(zone
		(net 50)
		(net_name "+1V8")
		(layer "B.Cu")
		(hatch edge 0.508)
		(connect_pads yes
			(clearance 0.1)
		)
		(min_thickness 0.1)
		(filled_areas_thickness no)
		(fill yes
			(thermal_gap 0.508)
			(thermal_bridge_width 0.508)
		)
		(polygon
			(pts
				(xy 139.99 97.45) (xy 137.19 97.45) (xy 137.19 95.6) (xy 139.99 95.6)
			)
		)
	)
	(zone
		(net 1)
		(net_name "GND")
		(layer "B.Cu")
		(hatch edge 0.508)
		(connect_pads yes
			(clearance 0.1)
		)
		(min_thickness 0.1)
		(filled_areas_thickness no)
		(fill yes
			(thermal_gap 0.508)
			(thermal_bridge_width 0.508)
		)
		(polygon
			(pts
				(xy 127.6 82.7) (xy 126.3 82.7) (xy 126.3 80.2) (xy 127.6 80.2)
			)
		)
	)
	(zone
		(net 2)
		(net_name "+3V3")
		(layer "B.Cu")
		(hatch edge 0.508)
		(connect_pads yes
			(clearance 0.1)
		)
		(min_thickness 0.1)
		(filled_areas_thickness no)
		(fill yes
			(thermal_gap 0.508)
			(thermal_bridge_width 0.508)
		)
		(polygon
			(pts
				(xy 131.000458 87.218429) (xy 131.020458 89.768429) (xy 130.038886 89.740258) (xy 129.99 92.6) (xy 128.166757 92.6)
				(xy 128.16 90.51) (xy 125.83 88.59) (xy 114.51 88.6) (xy 114.51 85.39) (xy 117.49 85.39) (xy 117.49 86.53)
				(xy 123.48 86.51) (xy 123.84 86.9) (xy 130.09 86.9)
			)
		)
	)
	(zone
		(net 3)
		(net_name "+1V2")
		(layer "B.Cu")
		(hatch edge 0.508)
		(connect_pads yes
			(clearance 0.1)
		)
		(min_thickness 0.1)
		(filled_areas_thickness no)
		(fill yes
			(thermal_gap 0.508)
			(thermal_bridge_width 0.508)
		)
		(polygon
			(pts
				(xy 104.79 79.3) (xy 91.14 79.3) (xy 91.14 73.6) (xy 104.79 73.6)
			)
		)
	)
	(zone
		(net 1)
		(net_name "GND")
		(layer "In1.Cu")
		(hatch edge 0.508)
		(connect_pads yes
			(clearance 0.1)
		)
		(min_thickness 0.1)
		(filled_areas_thickness no)
		(fill yes
			(thermal_gap 0.508)
			(thermal_bridge_width 0.508)
		)
		(polygon
			(pts
				(xy 180 127.5) (xy 72.5 127.5) (xy 72.5 52.5) (xy 180 52.5)
			)
		)
	)
	(zone
		(net 0)
		(net_name "")
		(layers "In1.Cu" "In2.Cu")
		(hatch edge 0.508)
		(connect_pads
			(clearance 0)
		)
		(min_thickness 0.254)
		(filled_areas_thickness no)
		(keepout
			(tracks allowed)
			(vias allowed)
			(pads not_allowed)
			(copperpour not_allowed)
			(footprints allowed)
		)
		(placement
			(enabled no)
			(sheetname "")
		)
		(fill
			(thermal_gap 0.508)
			(thermal_bridge_width 0.508)
		)
		(polygon
			(pts
				(xy 89 112) (xy 75 112) (xy 75 98) (xy 89 98)
			)
		)
	)
	(zone
		(net 0)
		(net_name "")
		(layers "In1.Cu" "In2.Cu")
		(hatch edge 0.508)
		(connect_pads
			(clearance 0)
		)
		(min_thickness 0.254)
		(filled_areas_thickness no)
		(keepout
			(tracks not_allowed)
			(vias allowed)
			(pads allowed)
			(copperpour not_allowed)
			(footprints allowed)
		)
		(placement
			(enabled no)
			(sheetname "")
		)
		(fill
			(thermal_gap 0.508)
			(thermal_bridge_width 0.508)
		)
		(polygon
			(pts
				(xy 90.994747 73.821478) (xy 90.998658 80.050018) (xy 87.030003 80.05) (xy 87.03 83) (xy 75 83)
				(xy 75 68) (xy 87.4 68) (xy 87.404747 73.781478)
			)
		)
	)
	(zone
		(net 329)
		(net_name "/Power Supply/FFC2_5V_1")
		(layer "In2.Cu")
		(name "DDR3_CLEARNECE_OVERRIDE")
		(hatch edge 0.508)
		(connect_pads yes
			(clearance 0.1)
		)
		(min_thickness 0.1)
		(filled_areas_thickness no)
		(fill yes
			(thermal_gap 0.508)
			(thermal_bridge_width 0.508)
		)
		(polygon
			(pts
				(xy 166.03 111.25) (xy 157.03 111.25) (xy 157.03 108.9) (xy 164.03 108.9) (xy 164.03 96.15) (xy 164.03 80.15)
				(xy 163.03 79.15) (xy 163.03 73.15) (xy 166.03 73.15)
			)
		)
	)
	(zone
		(net 1)
		(net_name "GND")
		(layer "In3.Cu")
		(name "DDR3_CLEARNECE_OVERRIDE")
		(hatch edge 0.508)
		(connect_pads yes
			(clearance 0.1)
		)
		(min_thickness 0.1)
		(filled_areas_thickness no)
		(fill yes
			(thermal_gap 0.508)
			(thermal_bridge_width 0.508)
		)
		(polygon
			(pts
				(xy 180 127.49) (xy 72.5 127.5) (xy 72.5 52.5) (xy 180 52.49)
			)
		)
	)
	(zone
		(net 0)
		(net_name "")
		(layers "In3.Cu" "In4.Cu")
		(hatch edge 0.508)
		(connect_pads
			(clearance 0)
		)
		(min_thickness 0.1)
		(filled_areas_thickness no)
		(keepout
			(tracks not_allowed)
			(vias not_allowed)
			(pads not_allowed)
			(copperpour not_allowed)
			(footprints allowed)
		)
		(placement
			(enabled no)
			(sheetname "")
		)
		(fill
			(thermal_gap 0.508)
			(thermal_bridge_width 0.508)
		)
		(polygon
			(pts
				(xy 77.23 75.65) (xy 75.03 75.65) (xy 75.03 74.15) (xy 77.23 74.15)
			)
		)
	)
	(zone
		(net 0)
		(net_name "")
		(layers "In3.Cu" "In4.Cu")
		(hatch edge 0.508)
		(connect_pads
			(clearance 0)
		)
		(min_thickness 0.1)
		(filled_areas_thickness no)
		(keepout
			(tracks not_allowed)
			(vias not_allowed)
			(pads not_allowed)
			(copperpour not_allowed)
			(footprints allowed)
		)
		(placement
			(enabled no)
			(sheetname "")
		)
		(fill
			(thermal_gap 0.508)
			(thermal_bridge_width 0.508)
		)
		(polygon
			(pts
				(xy 77.205 105.65) (xy 75.03 105.65) (xy 75.03 104.15) (xy 77.205 104.15)
			)
		)
	)
	(zone
		(net 1)
		(net_name "GND")
		(layer "In5.Cu")
		(hatch edge 0.508)
		(connect_pads yes
			(clearance 0.1)
		)
		(min_thickness 0.1)
		(filled_areas_thickness no)
		(fill yes
			(thermal_gap 0.508)
			(thermal_bridge_width 0.508)
		)
		(polygon
			(pts
				(xy 180 127.5) (xy 72.5 127.5) (xy 72.5 52.5) (xy 180 52.5)
			)
		)
	)
	(zone
		(net 10)
		(net_name "/FPGA Power/VCC_AUXA")
		(layer "In6.Cu")
		(hatch edge 0.508)
		(priority 5)
		(connect_pads yes
			(clearance 0.1)
		)
		(min_thickness 0.1)
		(filled_areas_thickness no)
		(fill yes
			(thermal_gap 0.508)
			(thermal_bridge_width 0.508)
		)
		(polygon
			(pts
				(xy 138.23564 92.438781) (xy 131.56 92.43988) (xy 131.469956 92.169851) (xy 130.831512 92.169956)
				(xy 129.94 92.38) (xy 129.09 93.05) (xy 128.331538 93.05) (xy 128.331538 92.99) (xy 127.581538 92.99)
				(xy 127.582916 92.284432) (xy 128.907263 92.262823) (xy 130.25587 90.278273) (xy 138.233466 90.258674)
			)
		)
	)
	(zone
		(net 12)
		(net_name "/FPGA Power/VCC_ADPHY")
		(layer "In6.Cu")
		(hatch edge 0.508)
		(priority 4)
		(connect_pads yes
			(clearance 0.1)
		)
		(min_thickness 0.1)
		(filled_areas_thickness no)
		(fill yes
			(thermal_gap 0.508)
			(thermal_bridge_width 0.508)
		)
		(polygon
			(pts
				(xy 131.37 93.54) (xy 134.02 93.54) (xy 135.94 93.55) (xy 135.96 95.89) (xy 135.96 97.24) (xy 134.54 97.25)
				(xy 134.54 96.45) (xy 130.64 96.45) (xy 130.641472 94.611642) (xy 127.446988 94.626732) (xy 127.11 94.63)
				(xy 126.65 94.97) (xy 126.45 95.3) (xy 126.35 95.35) (xy 126.2 95.35) (xy 126.1 95.25) (xy 126.05 95.15)
				(xy 126.05 95.05) (xy 126.21 94.79) (xy 127.05 93.85) (xy 127.483729 93.850254) (xy 128.4 93.85)
				(xy 128.4 93.616216) (xy 128.4 93.1) (xy 130.789255 93.081967) (xy 130.790011 92.379914) (xy 131.37 92.38)
			)
		)
	)
	(zone
		(net 248)
		(net_name "+1V5")
		(layer "In6.Cu")
		(hatch edge 0.508)
		(priority 3)
		(connect_pads yes
			(clearance 0.1)
		)
		(min_thickness 0.1)
		(filled_areas_thickness no)
		(fill yes
			(thermal_gap 0.508)
			(thermal_bridge_width 0.508)
		)
		(polygon
			(pts
				(xy 133.44 85.1) (xy 133.45 88.35) (xy 129.05 88.35) (xy 129.05 87.45) (xy 128.4 87.45) (xy 128.4 86.6)
				(xy 131 86.6) (xy 130.99 85.1) (xy 130.99 73) (xy 130.611047 73.0004) (xy 130.613479 71.55) (xy 133.42 71.55)
			)
		)
	)
	(zone
		(net 50)
		(net_name "+1V8")
		(layer "In6.Cu")
		(hatch edge 0.508)
		(priority 6)
		(connect_pads yes
			(clearance 0.1)
		)
		(min_thickness 0.1)
		(filled_areas_thickness no)
		(fill yes
			(thermal_gap 0.508)
			(thermal_bridge_width 0.508)
		)
		(polygon
			(pts
				(xy 140.54 109.29) (xy 138.29 111.29) (xy 138.29 113.88) (xy 136.54 113.88) (xy 136.54 109.19) (xy 138.39 107.34)
				(xy 138.39 93) (xy 136.6 93) (xy 136.6 87.4) (xy 140.6 87.4)
			)
		)
	)
	(zone
		(net 2)
		(net_name "+3V3")
		(layer "In6.Cu")
		(hatch edge 0.508)
		(priority 4)
		(connect_pads yes
			(clearance 0.1)
		)
		(min_thickness 0.1)
		(filled_areas_thickness no)
		(fill yes
			(thermal_gap 0.508)
			(thermal_bridge_width 0.508)
		)
		(polygon
			(pts
				(xy 133.84 88.45) (xy 133.84 90.31) (xy 130.15 90.33) (xy 128.85 92.05) (xy 128.39 92.05) (xy 128.39 91.5)
				(xy 128.74 91.5) (xy 128.93 91) (xy 128.93 88.45)
			)
		)
	)
	(zone
		(net 11)
		(net_name "/FPGA Power/VCC_DPHY")
		(layer "In6.Cu")
		(hatch edge 0.508)
		(priority 2)
		(connect_pads yes
			(clearance 0.1)
		)
		(min_thickness 0.1)
		(filled_areas_thickness no)
		(fill yes
			(thermal_gap 0.508)
			(thermal_bridge_width 0.508)
		)
		(polygon
			(pts
				(xy 130.62 95.37) (xy 130.62 96.41) (xy 129.15 96.41) (xy 129.157179 100.348912) (xy 127.007254 100.358645)
				(xy 127 94.72) (xy 130.62 94.72)
			)
		)
	)
	(zone
		(net 248)
		(net_name "+1V5")
		(layer "In6.Cu")
		(hatch edge 0.508)
		(priority 2)
		(connect_pads yes
			(clearance 0.1)
		)
		(min_thickness 0.1)
		(filled_areas_thickness no)
		(fill yes
			(thermal_gap 0.508)
			(thermal_bridge_width 0.508)
		)
		(polygon
			(pts
				(xy 131.32 80.4) (xy 124.12 80.4) (xy 124.12 84.99) (xy 125.12 85.99) (xy 125.12 86.99) (xy 120.78 87)
				(xy 120.78 83.8) (xy 119.73 82.5) (xy 119.73 78.9) (xy 116.78 76) (xy 116.78 72.94) (xy 117 72.94)
				(xy 117 55.35) (xy 131 55.35) (xy 131 58.075) (xy 138.89 58.075) (xy 138.9 60.975) (xy 131 60.975)
				(xy 131 73) (xy 131.32 73)
			)
		)
	)
	(zone
		(net 3)
		(net_name "+1V2")
		(layer "In6.Cu")
		(hatch edge 0.508)
		(priority 7)
		(connect_pads yes
			(clearance 0.1)
		)
		(min_thickness 0.1)
		(filled_areas_thickness no)
		(fill yes
			(thermal_gap 0.508)
			(thermal_bridge_width 0.508)
		)
		(polygon
			(pts
				(xy 143.34 117.1) (xy 138.04 117.1) (xy 138.04 117.15) (xy 126.54 117.15) (xy 112.69 103.6) (xy 115.14 101.15)
				(xy 128.14 114.2) (xy 136.39 114.2) (xy 136.39 114.15) (xy 140.69 114.15) (xy 140.69 111.6) (xy 140.69 109.45)
				(xy 140.69 98.275) (xy 140.69 87.1) (xy 135.89 87.1) (xy 135.89 85.8) (xy 143.34 85.8)
			)
		)
	)
	(zone
		(net 4)
		(net_name "1V0_Power")
		(layer "In6.Cu")
		(hatch edge 0.508)
		(priority 1)
		(connect_pads yes
			(clearance 0.1)
		)
		(min_thickness 0.1)
		(filled_areas_thickness no)
		(fill yes
			(thermal_gap 0.508)
			(thermal_bridge_width 0.508)
		)
		(polygon
			(pts
				(xy 127.38 91.39) (xy 126.8 91.39) (xy 126.8 92.29) (xy 127.62 92.29) (xy 127.62 92.99) (xy 128.37 92.99)
				(xy 128.37 93.79) (xy 127.54 93.79) (xy 126.95 93.8) (xy 126 94.75) (xy 126 95.4) (xy 126.95 95.4)
				(xy 126.95 100.4) (xy 128.4 100.4) (xy 133.49 100.4) (xy 133.49 103.54) (xy 123.945 103.54) (xy 123.945 89.86)
				(xy 125.12 89.86) (xy 125.12 89.19) (xy 125.87 89.19) (xy 125.87 89.84) (xy 127.38 89.84)
			)
		)
	)
	(zone
		(net 9)
		(net_name "/FPGA Power/VCC_AUX")
		(layer "In6.Cu")
		(hatch edge 0.508)
		(priority 6)
		(connect_pads yes
			(clearance 0.1)
		)
		(min_thickness 0.1)
		(filled_areas_thickness no)
		(fill yes
			(thermal_gap 0.508)
			(thermal_bridge_width 0.508)
		)
		(polygon
			(pts
				(xy 130.94 84.65) (xy 129.33 84.65) (xy 128.93 85.05) (xy 128.93 85.9) (xy 128.23 85.9) (xy 128.23 87.59)
				(xy 129.05 87.59) (xy 129.05 88.45) (xy 128.835009 90.712137) (xy 128.602866 91.470814) (xy 128.157059 91.476414)
				(xy 128.149192 92.243691) (xy 126.85 92.25) (xy 126.85 91.45) (xy 127.51 91.45) (xy 127.51 89.8)
				(xy 125.98 89.8) (xy 125.98 89.06) (xy 124.98 89.06) (xy 124.98 89.8) (xy 124.34 89.8) (xy 124.34 87.05)
				(xy 125.19 87.05) (xy 125.19 85.95) (xy 124.37 85.15) (xy 124.37 80.545) (xy 130.94 80.55)
			)
		)
	)
	(zone
		(net 49)
		(net_name "1V0_Clean")
		(layer "In6.Cu")
		(hatch edge 0.508)
		(priority 7)
		(connect_pads yes
			(clearance 0.1)
		)
		(min_thickness 0.1)
		(filled_areas_thickness no)
		(fill yes
			(thermal_gap 0.508)
			(thermal_bridge_width 0.508)
		)
		(polygon
			(pts
				(xy 136.04 102.4) (xy 138.19 104.55) (xy 138.19 107.4) (xy 136.74 107.4) (xy 133.69 104.35) (xy 133.69 100.3)
				(xy 129.24 100.3) (xy 129.24 98.65) (xy 136.04 98.65)
			)
		)
	)
	(zone
		(net 3)
		(net_name "+1V2")
		(layer "In6.Cu")
		(hatch edge 0.508)
		(priority 7)
		(connect_pads yes
			(clearance 0.1)
		)
		(min_thickness 0.1)
		(filled_areas_thickness no)
		(fill yes
			(thermal_gap 0.508)
			(thermal_bridge_width 0.508)
		)
		(polygon
			(pts
				(xy 104.89 86.2) (xy 101.12 90.7) (xy 101.12 99.3) (xy 107.99 99.3) (xy 110.59 96.7) (xy 112.785269 98.943963)
				(xy 109.185269 102.593963) (xy 96.99 102.5) (xy 96.99 90.7) (xy 101.571545 86.100302) (xy 101.621545 72.550302)
				(xy 104.79 72.55)
			)
		)
	)
	(zone
		(net 2)
		(net_name "+3V3")
		(layer "In6.Cu")
		(hatch edge 0.508)
		(connect_pads yes
			(clearance 0.1)
		)
		(min_thickness 0.1)
		(filled_areas_thickness no)
		(fill yes
			(thermal_gap 0.508)
			(thermal_bridge_width 0.508)
		)
		(polygon
			(pts
				(xy 180 127.5) (xy 72.5 127.5) (xy 72.5 52.5) (xy 180 52.5)
			)
		)
	)
)
